(kicad_pcb
	(version 20260206)
	(generator "pcbnew")
	(generator_version "10.0")
	(general
		(thickness 1.6)
		(legacy_teardrops no)
	)
	(paper "A4")
	(layers
		(0 "F.Cu" signal "TOP")
		(4 "In1.Cu" signal "L2GND")
		(6 "In2.Cu" signal "L3VCC")
		(2 "B.Cu" signal "BOTTOM")
		(9 "F.Adhes" user "F.Adhesive")
		(11 "B.Adhes" user "B.Adhesive")
		(13 "F.Paste" user "Package Geometry/Pastemask Top")
		(15 "B.Paste" user "Package Geometry/Pastemask Bottom")
		(5 "F.SilkS" user "Ref Des/Silkscreen Top")
		(7 "B.SilkS" user "Ref Des/Silkscreen Bottom")
		(1 "F.Mask" user "Board Geometry/Soldermask Top")
		(3 "B.Mask" user "Board Geometry/Soldermask Bottom")
		(17 "Dwgs.User" user "User.Drawings")
		(19 "Cmts.User" user "User.Comments")
		(21 "Eco1.User" user "User.Eco1")
		(23 "Eco2.User" user "User.Eco2")
		(25 "Edge.Cuts" user "Board Geometry/Outline")
		(27 "Margin" user)
		(31 "F.CrtYd" user "Package Geometry/Place Bound Top")
		(29 "B.CrtYd" user "Package Geometry/Place Bound Bottom")
		(35 "F.Fab" user "Ref Des/Assembly Top")
		(33 "B.Fab" user "Ref Des/Assembly Bottom")
	)
	(setup
		(pad_to_mask_clearance 0)
		(allow_soldermask_bridges_in_footprints no)
		(tenting
			(front yes)
			(back yes)
		)
		(covering
			(front no)
			(back no)
		)
		(plugging
			(front no)
			(back no)
		)
		(capping no)
		(filling no)
		(pcbplotparams
			(layerselection 0x00000000_00000000_55555555_5755f5ff)
			(plot_on_all_layers_selection 0x00000000_00000000_00000000_00000000)
			(disableapertmacros no)
			(usegerberextensions no)
			(usegerberattributes yes)
			(usegerberadvancedattributes yes)
			(creategerberjobfile yes)
			(dashed_line_dash_ratio 12)
			(dashed_line_gap_ratio 3)
			(svgprecision 4)
			(plotframeref no)
			(mode 1)
			(useauxorigin no)
			(pdf_front_fp_property_popups yes)
			(pdf_back_fp_property_popups yes)
			(pdf_metadata yes)
			(pdf_single_document no)
			(dxfpolygonmode yes)
			(dxfimperialunits yes)
			(dxfusepcbnewfont yes)
			(psnegative no)
			(psa4output no)
			(plot_black_and_white yes)
			(sketchpadsonfab no)
			(plotpadnumbers no)
			(hidednponfab no)
			(sketchdnponfab yes)
			(crossoutdnponfab yes)
			(subtractmaskfromsilk no)
			(outputformat 1)
			(mirror no)
			(drillshape 1)
			(scaleselection 1)
			(outputdirectory "")
		)
	)
	(footprint ""
		(layer "F.Cu")
		(at 34.716466 -141.089634 180)
		(property "Reference" "PR107"
			(at 0 0 180)
			(layer "F.SilkS")
			(hide yes)
			(effects
				(font
					(size 1.27 1.27)
				)
			)
		)
		(property "Value" "1KR2F-3-GP"
			(at 0.064008 -3.993896 180)
			(unlocked yes)
			(layer "F.Fab")
			(hide yes)
			(effects
				(font
					(size 1.016 1.016)
					(thickness 0.1524)
				)
			)
		)
		(property "Device Type" "R402H16"
			(at 0.064008 -5.517896 180)
			(unlocked yes)
			(layer "F.Fab")
			(hide yes)
			(effects
				(font
					(size 1.016 1.016)
					(thickness 0.1524)
				)
			)
		)
		(duplicate_pad_numbers_are_jumpers no)
		(fp_line
			(start 0.508 -0.9398)
			(end -0.508 -0.9398)
			(stroke
				(width 0.1524)
				(type default)
			)
			(layer "F.SilkS")
		)
		(fp_line
			(start -0.508 -0.9398)
			(end -0.508 0.9398)
			(stroke
				(width 0.1524)
				(type default)
			)
			(layer "F.SilkS")
		)
		(fp_rect
			(start -0.508 0.9398)
			(end 0.508 -0.9398)
			(stroke
				(width 0)
				(type default)
			)
			(fill no)
			(layer "F.CrtYd")
		)
		(fp_rect
			(start -0.508 0.9398)
			(end 0.508 -0.9398)
			(stroke
				(width 0)
				(type default)
			)
			(fill no)
			(layer "F.Fab")
		)
		(pad "1" smd custom
			(at 0 -0.4445 180)
			(size 0.1397 0.1397)
			(layers "F.Cu" "F.Mask" "F.Paste")
			(net "P12VL_2490_PG")
			(options
				(clearance outline)
				(anchor circle)
			)
			(primitives
				(gr_poly
					(pts
						(arc
							(start -0.1778 -0.2794)
							(mid -0.249642 -0.249642)
							(end -0.2794 -0.1778)
						)
						(arc
							(start -0.2794 0.1778)
							(mid -0.249642 0.249642)
							(end -0.1778 0.2794)
						)
						(arc
							(start 0.1778 0.2794)
							(mid 0.249642 0.249642)
							(end 0.2794 0.1778)
						)
						(arc
							(start 0.2794 -0.1778)
							(mid 0.249642 -0.249642)
							(end 0.1778 -0.2794)
						)
					)
					(width 0)
					(fill yes)
				)
			)
		)
		(pad "2" smd custom
			(at 0 0.4445 180)
			(size 0.1397 0.1397)
			(layers "F.Cu" "F.Mask" "F.Paste")
			(net "GND")
			(options
				(clearance outline)
				(anchor circle)
			)
			(primitives
				(gr_poly
					(pts
						(arc
							(start -0.1778 -0.2794)
							(mid -0.249642 -0.249642)
							(end -0.2794 -0.1778)
						)
						(arc
							(start -0.2794 0.1778)
							(mid -0.249642 0.249642)
							(end -0.1778 0.2794)
						)
						(arc
							(start 0.1778 0.2794)
							(mid 0.249642 0.249642)
							(end 0.2794 0.1778)
						)
						(arc
							(start 0.2794 -0.1778)
							(mid 0.249642 -0.249642)
							(end 0.1778 -0.2794)
						)
					)
					(width 0)
					(fill yes)
				)
			)
		)
	)
	(footprint ""
		(layer "F.Cu")
		(at 5.993384 -65.735962 180)
		(property "Reference" "Q3"
			(at 0 0 180)
			(layer "F.SilkS")
			(hide yes)
			(effects
				(font
					(size 1.27 1.27)
				)
			)
		)
		(property "Value" "PMBS3904-1-GP"
			(at 0 -9.0932 180)
			(unlocked yes)
			(layer "F.Fab")
			(hide yes)
			(effects
				(font
					(size 1.016 1.016)
					(thickness 0.1524)
				)
			)
		)
		(property "Device Type" "SOT-23-10H44"
			(at 0 -10.6172 180)
			(unlocked yes)
			(layer "F.Fab")
			(hide yes)
			(effects
				(font
					(size 1.016 1.016)
					(thickness 0.1524)
				)
			)
		)
		(duplicate_pad_numbers_are_jumpers no)
		(fp_line
			(start 1.651 1.778)
			(end 1.651 -1.778)
			(stroke
				(width 0.1524)
				(type default)
			)
			(layer "F.SilkS")
		)
		(fp_line
			(start 1.651 -1.778)
			(end -1.651 -1.778)
			(stroke
				(width 0.1524)
				(type default)
			)
			(layer "F.SilkS")
		)
		(fp_line
			(start -0.635 1.8796)
			(end -1.7526 1.8796)
			(stroke
				(width 0.3302)
				(type default)
			)
			(layer "F.SilkS")
		)
		(fp_line
			(start -0.71628 2.15265)
			(end -1.26492 2.15265)
			(stroke
				(width 0.0127)
				(type default)
			)
			(layer "F.SilkS")
		)
		(fp_line
			(start -0.719074 2.145538)
			(end -1.265936 2.14122)
			(stroke
				(width 0.0127)
				(type default)
			)
			(layer "F.SilkS")
		)
		(fp_line
			(start -0.9906 1.86309)
			(end -0.701294 2.15265)
			(stroke
				(width 0.0127)
				(type default)
			)
			(layer "F.SilkS")
		)
		(fp_line
			(start -0.994156 1.8669)
			(end -0.987044 1.8669)
			(stroke
				(width 0.0127)
				(type default)
			)
			(layer "F.SilkS")
		)
		(fp_line
			(start -1.003808 1.876552)
			(end -0.977646 1.876552)
			(stroke
				(width 0.0127)
				(type default)
			)
			(layer "F.SilkS")
		)
		(fp_line
			(start -1.013206 1.88595)
			(end -0.967994 1.88595)
			(stroke
				(width 0.0127)
				(type default)
			)
			(layer "F.SilkS")
		)
		(fp_line
			(start -1.022858 1.895602)
			(end -0.958596 1.895602)
			(stroke
				(width 0.0127)
				(type default)
			)
			(layer "F.SilkS")
		)
		(fp_line
			(start -1.032256 1.905)
			(end -0.948944 1.905)
			(stroke
				(width 0.0127)
				(type default)
			)
			(layer "F.SilkS")
		)
		(fp_line
			(start -1.041908 1.914652)
			(end -0.939546 1.914652)
			(stroke
				(width 0.0127)
				(type default)
			)
			(layer "F.SilkS")
		)
		(fp_line
			(start -1.051306 1.92405)
			(end -0.929894 1.92405)
			(stroke
				(width 0.0127)
				(type default)
			)
			(layer "F.SilkS")
		)
		(fp_line
			(start -1.060958 1.933702)
			(end -0.920496 1.933702)
			(stroke
				(width 0.0127)
				(type default)
			)
			(layer "F.SilkS")
		)
		(fp_line
			(start -1.070356 1.9431)
			(end -0.910844 1.9431)
			(stroke
				(width 0.0127)
				(type default)
			)
			(layer "F.SilkS")
		)
		(fp_line
			(start -1.080008 1.952752)
			(end -0.901446 1.952752)
			(stroke
				(width 0.0127)
				(type default)
			)
			(layer "F.SilkS")
		)
		(fp_line
			(start -1.089406 1.96215)
			(end -0.891794 1.96215)
			(stroke
				(width 0.0127)
				(type default)
			)
			(layer "F.SilkS")
		)
		(fp_line
			(start -1.099058 1.971802)
			(end -0.882396 1.971802)
			(stroke
				(width 0.0127)
				(type default)
			)
			(layer "F.SilkS")
		)
		(fp_line
			(start -1.108456 1.9812)
			(end -0.872744 1.9812)
			(stroke
				(width 0.0127)
				(type default)
			)
			(layer "F.SilkS")
		)
		(fp_line
			(start -1.118108 1.990852)
			(end -0.863346 1.990852)
			(stroke
				(width 0.0127)
				(type default)
			)
			(layer "F.SilkS")
		)
		(fp_line
			(start -1.127506 2.00025)
			(end -0.853694 2.00025)
			(stroke
				(width 0.0127)
				(type default)
			)
			(layer "F.SilkS")
		)
		(fp_line
			(start -1.137158 2.009902)
			(end -0.844296 2.009902)
			(stroke
				(width 0.0127)
				(type default)
			)
			(layer "F.SilkS")
		)
		(fp_line
			(start -1.146556 2.0193)
			(end -0.834644 2.0193)
			(stroke
				(width 0.0127)
				(type default)
			)
			(layer "F.SilkS")
		)
		(fp_line
			(start -1.156208 2.028952)
			(end -0.825246 2.028952)
			(stroke
				(width 0.0127)
				(type default)
			)
			(layer "F.SilkS")
		)
		(fp_line
			(start -1.165606 2.03835)
			(end -0.815594 2.03835)
			(stroke
				(width 0.0127)
				(type default)
			)
			(layer "F.SilkS")
		)
		(fp_line
			(start -1.175258 2.048002)
			(end -0.806196 2.048002)
			(stroke
				(width 0.0127)
				(type default)
			)
			(layer "F.SilkS")
		)
		(fp_line
			(start -1.184656 2.0574)
			(end -0.796544 2.0574)
			(stroke
				(width 0.0127)
				(type default)
			)
			(layer "F.SilkS")
		)
		(fp_line
			(start -1.194308 2.067052)
			(end -0.787146 2.067052)
			(stroke
				(width 0.0127)
				(type default)
			)
			(layer "F.SilkS")
		)
		(fp_line
			(start -1.203706 2.07645)
			(end -0.777494 2.07645)
			(stroke
				(width 0.0127)
				(type default)
			)
			(layer "F.SilkS")
		)
		(fp_line
			(start -1.213358 2.086102)
			(end -0.768096 2.086102)
			(stroke
				(width 0.0127)
				(type default)
			)
			(layer "F.SilkS")
		)
		(fp_line
			(start -1.222756 2.0955)
			(end -0.758444 2.0955)
			(stroke
				(width 0.0127)
				(type default)
			)
			(layer "F.SilkS")
		)
		(fp_line
			(start -1.232408 2.105152)
			(end -0.749046 2.105152)
			(stroke
				(width 0.0127)
				(type default)
			)
			(layer "F.SilkS")
		)
		(fp_line
			(start -1.241806 2.11455)
			(end -0.739394 2.11455)
			(stroke
				(width 0.0127)
				(type default)
			)
			(layer "F.SilkS")
		)
		(fp_line
			(start -1.251458 2.124202)
			(end -0.729996 2.124202)
			(stroke
				(width 0.0127)
				(type default)
			)
			(layer "F.SilkS")
		)
		(fp_line
			(start -1.260856 2.1336)
			(end -0.720344 2.1336)
			(stroke
				(width 0.0127)
				(type default)
			)
			(layer "F.SilkS")
		)
		(fp_line
			(start -1.279144 2.15265)
			(end -0.701294 2.15265)
			(stroke
				(width 0.0127)
				(type default)
			)
			(layer "F.SilkS")
		)
		(fp_line
			(start -1.279398 2.152142)
			(end -0.9906 1.86309)
			(stroke
				(width 0.0127)
				(type default)
			)
			(layer "F.SilkS")
		)
		(fp_line
			(start -1.651 1.778)
			(end 1.651 1.778)
			(stroke
				(width 0.1524)
				(type default)
			)
			(layer "F.SilkS")
		)
		(fp_line
			(start -1.651 -1.778)
			(end -1.651 1.778)
			(stroke
				(width 0.1524)
				(type default)
			)
			(layer "F.SilkS")
		)
		(fp_line
			(start -1.7526 1.8796)
			(end -1.7526 0.9906)
			(stroke
				(width 0.3302)
				(type default)
			)
			(layer "F.SilkS")
		)
		(fp_poly
			(pts
				(xy -1.285748 2.159) (xy -1.285748 1.8796) (xy -1.778 1.8796) (xy -1.778 -1.8796) (xy 1.778 -1.8796)
				(xy 1.778 1.8796) (xy -0.694944 1.8796) (xy -0.694944 2.159)
			)
			(stroke
				(width 0)
				(type default)
			)
			(fill no)
			(layer "F.CrtYd")
		)
		(fp_poly
			(pts
				(xy -1.285748 2.159) (xy -1.285748 1.8796) (xy -1.778 1.8796) (xy -1.778 -1.8796) (xy 1.778 -1.8796)
				(xy 1.778 1.8796) (xy -0.694944 1.8796) (xy -0.694944 2.159)
			)
			(stroke
				(width 0)
				(type default)
			)
			(fill no)
			(layer "F.Fab")
		)
		(pad "1" smd rect
			(at -0.98425 0.9525 180)
			(size 0.762 1.143)
			(layers "F.Cu" "F.Mask" "F.Paste")
			(net "LED_DR_LED5_B")
		)
		(pad "2" smd rect
			(at 0.98425 0.9525 180)
			(size 0.762 1.143)
			(layers "F.Cu" "F.Mask" "F.Paste")
			(net "GND")
		)
		(pad "3" smd rect
			(at 0 -0.9525 180)
			(size 0.762 1.143)
			(layers "F.Cu" "F.Mask" "F.Paste")
			(net "LED_DR_LED5_BLUE")
		)
	)
	(footprint ""
		(layer "F.Cu")
		(at 21.7678 -219.8878 90)
		(property "Reference" "R135"
			(at 0 0 90)
			(layer "F.SilkS")
			(hide yes)
			(effects
				(font
					(size 1.27 1.27)
				)
			)
		)
		(property "Value" "4K7R2F-GP"
			(at 0.064008 -3.993896 90)
			(unlocked yes)
			(layer "F.Fab")
			(hide yes)
			(effects
				(font
					(size 1.016 1.016)
					(thickness 0.1524)
				)
			)
		)
		(property "Device Type" "R402H16"
			(at 0.064008 -5.517896 90)
			(unlocked yes)
			(layer "F.Fab")
			(hide yes)
			(effects
				(font
					(size 1.016 1.016)
					(thickness 0.1524)
				)
			)
		)
		(duplicate_pad_numbers_are_jumpers no)
		(fp_line
			(start 0.508 -0.9398)
			(end -0.508 -0.9398)
			(stroke
				(width 0.1524)
				(type default)
			)
			(layer "F.SilkS")
		)
		(fp_line
			(start -0.508 -0.9398)
			(end -0.508 0.9398)
			(stroke
				(width 0.1524)
				(type default)
			)
			(layer "F.SilkS")
		)
		(fp_rect
			(start -0.508 0.9398)
			(end 0.508 -0.9398)
			(stroke
				(width 0)
				(type default)
			)
			(fill no)
			(layer "F.CrtYd")
		)
		(fp_rect
			(start -0.508 0.9398)
			(end 0.508 -0.9398)
			(stroke
				(width 0)
				(type default)
			)
			(fill no)
			(layer "F.Fab")
		)
		(pad "1" smd custom
			(at 0 -0.4445 90)
			(size 0.1397 0.1397)
			(layers "F.Cu" "F.Mask" "F.Paste")
			(net "P3V3")
			(options
				(clearance outline)
				(anchor circle)
			)
			(primitives
				(gr_poly
					(pts
						(arc
							(start -0.1778 -0.2794)
							(mid -0.249642 -0.249642)
							(end -0.2794 -0.1778)
						)
						(arc
							(start -0.2794 0.1778)
							(mid -0.249642 0.249642)
							(end -0.1778 0.2794)
						)
						(arc
							(start 0.1778 0.2794)
							(mid 0.249642 0.249642)
							(end 0.2794 0.1778)
						)
						(arc
							(start 0.2794 -0.1778)
							(mid 0.249642 -0.249642)
							(end 0.1778 -0.2794)
						)
					)
					(width 0)
					(fill yes)
				)
			)
		)
		(pad "2" smd custom
			(at 0 0.4445 90)
			(size 0.1397 0.1397)
			(layers "F.Cu" "F.Mask" "F.Paste")
			(net "PWM_OUT_FAN1")
			(options
				(clearance outline)
				(anchor circle)
			)
			(primitives
				(gr_poly
					(pts
						(arc
							(start -0.1778 -0.2794)
							(mid -0.249642 -0.249642)
							(end -0.2794 -0.1778)
						)
						(arc
							(start -0.2794 0.1778)
							(mid -0.249642 0.249642)
							(end -0.1778 0.2794)
						)
						(arc
							(start 0.1778 0.2794)
							(mid 0.249642 0.249642)
							(end 0.2794 0.1778)
						)
						(arc
							(start 0.2794 -0.1778)
							(mid 0.249642 -0.249642)
							(end 0.1778 -0.2794)
						)
					)
					(width 0)
					(fill yes)
				)
			)
		)
	)
	(footprint ""
		(layer "F.Cu")
		(at 4.040124 -193.339974 -90)
		(property "Reference" "CN4"
			(at 0 0 270)
			(layer "F.SilkS")
			(hide yes)
			(effects
				(font
					(size 1.27 1.27)
				)
			)
		)
		(property "Value" "JWT-CON5-42-GP"
			(at -7.8105 2.9591 270)
			(unlocked yes)
			(layer "F.Fab")
			(hide yes)
			(effects
				(font
					(size 1.016 1.016)
					(thickness 0.1524)
				)
			)
		)
		(property "Device Type" "A2541WR0-1TX5PA-6T-0E"
			(at -7.8105 1.4351 270)
			(unlocked yes)
			(layer "F.Fab")
			(hide yes)
			(effects
				(font
					(size 1.016 1.016)
					(thickness 0.1524)
				)
			)
		)
		(duplicate_pad_numbers_are_jumpers no)
		(fp_line
			(start -6.604 10.287)
			(end 6.604 10.287)
			(stroke
				(width 0.1524)
				(type default)
			)
			(layer "F.SilkS")
		)
		(fp_line
			(start 6.604 10.287)
			(end 6.604 -0.9652)
			(stroke
				(width 0.1524)
				(type default)
			)
			(layer "F.SilkS")
		)
		(fp_line
			(start -6.604 -0.9652)
			(end -6.604 10.287)
			(stroke
				(width 0.1524)
				(type default)
			)
			(layer "F.SilkS")
		)
		(fp_line
			(start 6.604 -0.9652)
			(end -6.604 -0.9652)
			(stroke
				(width 0.1524)
				(type default)
			)
			(layer "F.SilkS")
		)
		(fp_line
			(start -6.731 -1.0922)
			(end -6.731 0.1778)
			(stroke
				(width 0.4064)
				(type default)
			)
			(layer "F.SilkS")
		)
		(fp_line
			(start -5.461 -1.0922)
			(end -6.731 -1.0922)
			(stroke
				(width 0.4064)
				(type default)
			)
			(layer "F.SilkS")
		)
		(fp_circle
			(center -5.08 0)
			(end -5.08 -1.0668)
			(stroke
				(width 0.3048)
				(type default)
			)
			(fill no)
			(layer "F.SilkS")
		)
		(fp_circle
			(center -2.54 0)
			(end -2.54 -1.0668)
			(stroke
				(width 0.3048)
				(type default)
			)
			(fill no)
			(layer "F.SilkS")
		)
		(fp_circle
			(center 0 0)
			(end 0 -1.0668)
			(stroke
				(width 0.3048)
				(type default)
			)
			(fill no)
			(layer "F.SilkS")
		)
		(fp_circle
			(center 2.54 0)
			(end 2.54 -1.0668)
			(stroke
				(width 0.3048)
				(type default)
			)
			(fill no)
			(layer "F.SilkS")
		)
		(fp_circle
			(center 5.08 0)
			(end 5.08 -1.0668)
			(stroke
				(width 0.3048)
				(type default)
			)
			(fill no)
			(layer "F.SilkS")
		)
		(fp_rect
			(start -6.35 10.033)
			(end 6.35 -0.3302)
			(stroke
				(width 0)
				(type default)
			)
			(fill no)
			(layer "F.CrtYd")
		)
		(fp_poly
			(pts
				(xy -6.35 -0.3302) (xy 6.858 -0.3302) (xy 6.858 -1.2192) (xy -6.858 -1.2192) (xy -6.858 10.541)
				(xy 6.858 10.541) (xy 6.858 -0.3175) (xy 6.35 -0.3175) (xy 6.35 10.033) (xy -6.35 10.033)
			)
			(stroke
				(width 0)
				(type default)
			)
			(fill no)
			(layer "F.CrtYd")
		)
		(fp_rect
			(start -6.858 10.541)
			(end 6.858 -1.2192)
			(stroke
				(width 0)
				(type default)
			)
			(fill no)
			(layer "F.Fab")
		)
		(pad "1" thru_hole circle
			(at -5.08 0 270)
			(size 1.4224 1.4224)
			(drill 1.016)
			(layers "*.Cu" "*.Mask")
			(remove_unused_layers no)
			(net "GND")
			(clearance 0.1524)
			(thermal_gap 0.1524)
		)
		(pad "2" thru_hole circle
			(at -2.54 0 270)
			(size 1.4224 1.4224)
			(drill 1.016)
			(layers "*.Cu" "*.Mask")
			(remove_unused_layers no)
			(net "P12V_FAN4")
			(clearance 0.1524)
			(thermal_gap 0.1524)
		)
		(pad "3" thru_hole circle
			(at 0 0 270)
			(size 1.4224 1.4224)
			(drill 1.016)
			(layers "*.Cu" "*.Mask")
			(remove_unused_layers no)
			(net "FAN_TACH8")
			(clearance 0.1524)
			(thermal_gap 0.1524)
		)
		(pad "4" thru_hole circle
			(at 2.54 0 270)
			(size 1.4224 1.4224)
			(drill 1.016)
			(layers "*.Cu" "*.Mask")
			(remove_unused_layers no)
			(net "PWM_OUT_FAN4_NET")
			(clearance 0.1524)
			(thermal_gap 0.1524)
		)
		(pad "5" thru_hole circle
			(at 5.08 0 270)
			(size 1.4224 1.4224)
			(drill 1.016)
			(layers "*.Cu" "*.Mask")
			(remove_unused_layers no)
			(net "FAN_TACH7")
			(clearance 0.1524)
			(thermal_gap 0.1524)
		)
	)
	(footprint ""
		(layer "F.Cu")
		(at 26.416 -111.633)
		(property "Reference" "PQ7"
			(at 0 0 0)
			(layer "F.SilkS")
			(hide yes)
			(effects
				(font
					(size 1.27 1.27)
				)
			)
		)
		(property "Value" "PH0925CL-GP"
			(at -4.2799 -0.4572 0)
			(unlocked yes)
			(layer "F.Fab")
			(hide yes)
			(effects
				(font
					(size 1.016 1.016)
					(thickness 0.1524)
				)
			)
		)
		(property "Device Type" "LFPAK-5PH48-U"
			(at -4.2799 -1.9812 0)
			(unlocked yes)
			(layer "F.Fab")
			(hide yes)
			(effects
				(font
					(size 1.016 1.016)
					(thickness 0.1524)
				)
			)
		)
		(duplicate_pad_numbers_are_jumpers no)
		(fp_line
			(start -2.7559 -6.5532)
			(end -2.7559 1.0668)
			(stroke
				(width 0.1524)
				(type default)
			)
			(layer "F.SilkS")
		)
		(fp_line
			(start -2.7559 1.0668)
			(end 2.7559 1.0668)
			(stroke
				(width 0.1524)
				(type default)
			)
			(layer "F.SilkS")
		)
		(fp_line
			(start -1.7272 1.1684)
			(end -2.1082 1.1684)
			(stroke
				(width 0.3302)
				(type default)
			)
			(layer "F.SilkS")
		)
		(fp_line
			(start 2.7559 -6.5532)
			(end -2.7559 -6.5532)
			(stroke
				(width 0.1524)
				(type default)
			)
			(layer "F.SilkS")
		)
		(fp_line
			(start 2.7559 1.0668)
			(end 2.7559 -6.5532)
			(stroke
				(width 0.1524)
				(type default)
			)
			(layer "F.SilkS")
		)
		(fp_poly
			(pts
				(xy -2.3368 1.5748) (xy -1.905 1.143) (xy -1.4732 1.5748)
			)
			(stroke
				(width 0)
				(type default)
			)
			(fill yes)
			(layer "F.SilkS")
		)
		(fp_poly
			(pts
				(xy -2.5019 -4.02971) (xy -0.3302 -4.02971) (xy -0.3302 -6.30301) (xy -2.5019 -6.30301)
			)
			(stroke
				(width 0)
				(type default)
			)
			(fill yes)
			(layer "F.Paste")
		)
		(fp_poly
			(pts
				(xy -2.5019 -1.09601) (xy -0.3302 -1.09601) (xy -0.3302 -3.36931) (xy -2.5019 -3.36931)
			)
			(stroke
				(width 0)
				(type default)
			)
			(fill yes)
			(layer "F.Paste")
		)
		(fp_poly
			(pts
				(xy 0.3302 -4.02971) (xy 2.5019 -4.02971) (xy 2.5019 -6.30301) (xy 0.3302 -6.30301)
			)
			(stroke
				(width 0)
				(type default)
			)
			(fill yes)
			(layer "F.Paste")
		)
		(fp_poly
			(pts
				(xy 0.3302 -1.09601) (xy 2.5019 -1.09601) (xy 2.5019 -3.36931) (xy 0.3302 -3.36931)
			)
			(stroke
				(width 0)
				(type default)
			)
			(fill yes)
			(layer "F.Paste")
		)
		(fp_rect
			(start -2.4511 0.3048)
			(end 2.4511 -5.6896)
			(stroke
				(width 0)
				(type default)
			)
			(fill no)
			(layer "F.CrtYd")
		)
		(fp_poly
			(pts
				(xy -3.0099 1.3208) (xy -3.0099 -6.8072) (xy 3.0099 -6.8072) (xy 3.0099 -1.016) (xy 2.4511 -1.016)
				(xy 2.4511 -5.6896) (xy -2.4511 -5.6896) (xy -2.4511 0.3048) (xy 2.4511 0.3048) (xy 2.4511 -1.0033)
				(xy 3.0099 -1.0033) (xy 3.0099 1.3208)
			)
			(stroke
				(width 0)
				(type default)
			)
			(fill no)
			(layer "F.CrtYd")
		)
		(fp_rect
			(start -3.0099 1.3208)
			(end 3.0099 -6.8072)
			(stroke
				(width 0)
				(type default)
			)
			(fill no)
			(layer "F.Fab")
		)
		(pad "1" smd rect
			(at -1.905 0)
			(size 0.762 1.6256)
			(layers "F.Cu" "F.Mask" "F.Paste")
			(net "P12VU")
		)
		(pad "2" smd rect
			(at -0.635 0)
			(size 0.762 1.6256)
			(layers "F.Cu" "F.Mask" "F.Paste")
			(net "P12VU")
		)
		(pad "3" smd rect
			(at 0.635 0)
			(size 0.762 1.6256)
			(layers "F.Cu" "F.Mask" "F.Paste")
			(net "P12VU")
		)
		(pad "4" smd rect
			(at 1.905 0)
			(size 0.762 1.6256)
			(layers "F.Cu" "F.Mask" "F.Paste")
			(net "P12VU_2490_GATE_DRV")
		)
		(pad "5" smd rect
			(at 0 -3.69951)
			(size 5.0038 5.207)
			(layers "F.Cu" "F.Mask" "F.Paste")
			(net "P12VU_NET")
		)
	)
	(footprint ""
		(layer "F.Cu")
		(at 8.763 -69.1642 90)
		(property "Reference" "R166"
			(at 0 0 90)
			(layer "F.SilkS")
			(hide yes)
			(effects
				(font
					(size 1.27 1.27)
				)
			)
		)
		(property "Value" "4K7R2F-GP"
			(at 0.064008 -3.993896 90)
			(unlocked yes)
			(layer "F.Fab")
			(hide yes)
			(effects
				(font
					(size 1.016 1.016)
					(thickness 0.1524)
				)
			)
		)
		(property "Device Type" "R402H16"
			(at 0.064008 -5.517896 90)
			(unlocked yes)
			(layer "F.Fab")
			(hide yes)
			(effects
				(font
					(size 1.016 1.016)
					(thickness 0.1524)
				)
			)
		)
		(duplicate_pad_numbers_are_jumpers no)
		(fp_line
			(start 0.508 -0.9398)
			(end -0.508 -0.9398)
			(stroke
				(width 0.1524)
				(type default)
			)
			(layer "F.SilkS")
		)
		(fp_line
			(start -0.508 -0.9398)
			(end -0.508 0.9398)
			(stroke
				(width 0.1524)
				(type default)
			)
			(layer "F.SilkS")
		)
		(fp_rect
			(start -0.508 0.9398)
			(end 0.508 -0.9398)
			(stroke
				(width 0)
				(type default)
			)
			(fill no)
			(layer "F.CrtYd")
		)
		(fp_rect
			(start -0.508 0.9398)
			(end 0.508 -0.9398)
			(stroke
				(width 0)
				(type default)
			)
			(fill no)
			(layer "F.Fab")
		)
		(pad "1" smd custom
			(at 0 -0.4445 90)
			(size 0.1397 0.1397)
			(layers "F.Cu" "F.Mask" "F.Paste")
			(net "P3V3")
			(options
				(clearance outline)
				(anchor circle)
			)
			(primitives
				(gr_poly
					(pts
						(arc
							(start -0.1778 -0.2794)
							(mid -0.249642 -0.249642)
							(end -0.2794 -0.1778)
						)
						(arc
							(start -0.2794 0.1778)
							(mid -0.249642 0.249642)
							(end -0.1778 0.2794)
						)
						(arc
							(start 0.1778 0.2794)
							(mid 0.249642 0.249642)
							(end 0.2794 0.1778)
						)
						(arc
							(start 0.2794 -0.1778)
							(mid 0.249642 -0.249642)
							(end 0.1778 -0.2794)
						)
					)
					(width 0)
					(fill yes)
				)
			)
		)
		(pad "2" smd custom
			(at 0 0.4445 90)
			(size 0.1397 0.1397)
			(layers "F.Cu" "F.Mask" "F.Paste")
			(net "PWM_BUFFER_IN_FAN3_FAN4")
			(options
				(clearance outline)
				(anchor circle)
			)
			(primitives
				(gr_poly
					(pts
						(arc
							(start -0.1778 -0.2794)
							(mid -0.249642 -0.249642)
							(end -0.2794 -0.1778)
						)
						(arc
							(start -0.2794 0.1778)
							(mid -0.249642 0.249642)
							(end -0.1778 0.2794)
						)
						(arc
							(start 0.1778 0.2794)
							(mid 0.249642 0.249642)
							(end 0.2794 0.1778)
						)
						(arc
							(start 0.2794 -0.1778)
							(mid 0.249642 -0.249642)
							(end 0.1778 -0.2794)
						)
					)
					(width 0)
					(fill yes)
				)
			)
		)
	)
	(footprint ""
		(layer "F.Cu")
		(at 14.8844 -50.6222 90)
		(property "Reference" "R175"
			(at 0 0 90)
			(layer "F.SilkS")
			(hide yes)
			(effects
				(font
					(size 1.27 1.27)
				)
			)
		)
		(property "Value" "0R2J-2-GP"
			(at 0.064008 -3.993896 90)
			(unlocked yes)
			(layer "F.Fab")
			(hide yes)
			(effects
				(font
					(size 1.016 1.016)
					(thickness 0.1524)
				)
			)
		)
		(property "Device Type" "R402H16"
			(at 0.064008 -5.517896 90)
			(unlocked yes)
			(layer "F.Fab")
			(hide yes)
			(effects
				(font
					(size 1.016 1.016)
					(thickness 0.1524)
				)
			)
		)
		(duplicate_pad_numbers_are_jumpers no)
		(fp_line
			(start 0.508 -0.9398)
			(end -0.508 -0.9398)
			(stroke
				(width 0.1524)
				(type default)
			)
			(layer "F.SilkS")
		)
		(fp_line
			(start -0.508 -0.9398)
			(end -0.508 0.9398)
			(stroke
				(width 0.1524)
				(type default)
			)
			(layer "F.SilkS")
		)
		(fp_rect
			(start -0.508 0.9398)
			(end 0.508 -0.9398)
			(stroke
				(width 0)
				(type default)
			)
			(fill no)
			(layer "F.CrtYd")
		)
		(fp_rect
			(start -0.508 0.9398)
			(end 0.508 -0.9398)
			(stroke
				(width 0)
				(type default)
			)
			(fill no)
			(layer "F.Fab")
		)
		(pad "1" smd custom
			(at 0 -0.4445 90)
			(size 0.1397 0.1397)
			(layers "F.Cu" "F.Mask" "F.Paste")
			(net "SD_LATCH_RELEASE_U")
			(options
				(clearance outline)
				(anchor circle)
			)
			(primitives
				(gr_poly
					(pts
						(arc
							(start -0.1778 -0.2794)
							(mid -0.249642 -0.249642)
							(end -0.2794 -0.1778)
						)
						(arc
							(start -0.2794 0.1778)
							(mid -0.249642 0.249642)
							(end -0.1778 0.2794)
						)
						(arc
							(start 0.1778 0.2794)
							(mid 0.249642 0.249642)
							(end 0.2794 0.1778)
						)
						(arc
							(start 0.2794 -0.1778)
							(mid 0.249642 -0.249642)
							(end 0.1778 -0.2794)
						)
					)
					(width 0)
					(fill yes)
				)
			)
		)
		(pad "2" smd custom
			(at 0 0.4445 90)
			(size 0.1397 0.1397)
			(layers "F.Cu" "F.Mask" "F.Paste")
			(net "TEMP_ALM#_REVERSE_R")
			(options
				(clearance outline)
				(anchor circle)
			)
			(primitives
				(gr_poly
					(pts
						(arc
							(start -0.1778 -0.2794)
							(mid -0.249642 -0.249642)
							(end -0.2794 -0.1778)
						)
						(arc
							(start -0.2794 0.1778)
							(mid -0.249642 0.249642)
							(end -0.1778 0.2794)
						)
						(arc
							(start 0.1778 0.2794)
							(mid 0.249642 0.249642)
							(end 0.2794 0.1778)
						)
						(arc
							(start 0.2794 -0.1778)
							(mid 0.249642 -0.249642)
							(end 0.1778 -0.2794)
						)
					)
					(width 0)
					(fill yes)
				)
			)
		)
	)
	(footprint ""
		(layer "F.Cu")
		(at 29.7942 -238.252 180)
		(property "Reference" "R40"
			(at 0 0 180)
			(layer "F.SilkS")
			(hide yes)
			(effects
				(font
					(size 1.27 1.27)
				)
			)
		)
		(property "Value" "4K7R2J-2-GP"
			(at 0.064008 -3.993896 180)
			(unlocked yes)
			(layer "F.Fab")
			(hide yes)
			(effects
				(font
					(size 1.016 1.016)
					(thickness 0.1524)
				)
			)
		)
		(property "Device Type" "R402H16"
			(at 0.064008 -5.517896 180)
			(unlocked yes)
			(layer "F.Fab")
			(hide yes)
			(effects
				(font
					(size 1.016 1.016)
					(thickness 0.1524)
				)
			)
		)
		(duplicate_pad_numbers_are_jumpers no)
		(fp_line
			(start 0.508 -0.9398)
			(end -0.508 -0.9398)
			(stroke
				(width 0.1524)
				(type default)
			)
			(layer "F.SilkS")
		)
		(fp_line
			(start -0.508 -0.9398)
			(end -0.508 0.9398)
			(stroke
				(width 0.1524)
				(type default)
			)
			(layer "F.SilkS")
		)
		(fp_rect
			(start -0.508 0.9398)
			(end 0.508 -0.9398)
			(stroke
				(width 0)
				(type default)
			)
			(fill no)
			(layer "F.CrtYd")
		)
		(fp_rect
			(start -0.508 0.9398)
			(end 0.508 -0.9398)
			(stroke
				(width 0)
				(type default)
			)
			(fill no)
			(layer "F.Fab")
		)
		(pad "1" smd custom
			(at 0 -0.4445 180)
			(size 0.1397 0.1397)
			(layers "F.Cu" "F.Mask" "F.Paste")
			(net "P3V3")
			(options
				(clearance outline)
				(anchor circle)
			)
			(primitives
				(gr_poly
					(pts
						(arc
							(start -0.1778 -0.2794)
							(mid -0.249642 -0.249642)
							(end -0.2794 -0.1778)
						)
						(arc
							(start -0.2794 0.1778)
							(mid -0.249642 0.249642)
							(end -0.1778 0.2794)
						)
						(arc
							(start 0.1778 0.2794)
							(mid 0.249642 0.249642)
							(end 0.2794 0.1778)
						)
						(arc
							(start 0.2794 -0.1778)
							(mid 0.249642 -0.249642)
							(end 0.1778 -0.2794)
						)
					)
					(width 0)
					(fill yes)
				)
			)
		)
		(pad "2" smd custom
			(at 0 0.4445 180)
			(size 0.1397 0.1397)
			(layers "F.Cu" "F.Mask" "F.Paste")
			(net "FCB_EEPROM_A1")
			(options
				(clearance outline)
				(anchor circle)
			)
			(primitives
				(gr_poly
					(pts
						(arc
							(start -0.1778 -0.2794)
							(mid -0.249642 -0.249642)
							(end -0.2794 -0.1778)
						)
						(arc
							(start -0.2794 0.1778)
							(mid -0.249642 0.249642)
							(end -0.1778 0.2794)
						)
						(arc
							(start 0.1778 0.2794)
							(mid 0.249642 0.249642)
							(end 0.2794 0.1778)
						)
						(arc
							(start 0.2794 -0.1778)
							(mid 0.249642 -0.249642)
							(end 0.1778 -0.2794)
						)
					)
					(width 0)
					(fill yes)
				)
			)
		)
	)
	(footprint ""
		(layer "F.Cu")
		(at 22.1996 -146.2786 180)
		(property "Reference" "PC93"
			(at 0 0 180)
			(layer "F.SilkS")
			(hide yes)
			(effects
				(font
					(size 1.27 1.27)
				)
			)
		)
		(property "Value" "SC220P50V2KX-3GP"
			(at 1.1811 -2.7051 180)
			(unlocked yes)
			(layer "F.Fab")
			(hide yes)
			(effects
				(font
					(size 1.016 1.016)
					(thickness 0.1524)
				)
			)
		)
		(property "Device Type" "C402H22"
			(at 1.1811 -4.2291 180)
			(unlocked yes)
			(layer "F.Fab")
			(hide yes)
			(effects
				(font
					(size 1.016 1.016)
					(thickness 0.1524)
				)
			)
		)
		(duplicate_pad_numbers_are_jumpers no)
		(fp_rect
			(start -0.4318 0.9525)
			(end 0.4318 -0.9525)
			(stroke
				(width 0)
				(type default)
			)
			(fill no)
			(layer "F.CrtYd")
		)
		(fp_rect
			(start -0.4318 0.9525)
			(end 0.4318 -0.9525)
			(stroke
				(width 0)
				(type default)
			)
			(fill no)
			(layer "F.Fab")
		)
		(pad "1" smd custom
			(at 0 -0.4445 180)
			(size 0.1524 0.1524)
			(layers "F.Cu" "F.Mask" "F.Paste")
			(net "P12VU_2490_VREF")
			(options
				(clearance outline)
				(anchor circle)
			)
			(primitives
				(gr_poly
					(pts
						(arc
							(start 0.3048 -0.2032)
							(mid 0.275042 -0.275042)
							(end 0.2032 -0.3048)
						)
						(arc
							(start -0.2032 -0.3048)
							(mid -0.275042 -0.275042)
							(end -0.3048 -0.2032)
						)
						(arc
							(start -0.3048 0.2032)
							(mid -0.275042 0.275042)
							(end -0.2032 0.3048)
						)
						(arc
							(start 0.2032 0.3048)
							(mid 0.275042 0.275042)
							(end 0.3048 0.2032)
						)
					)
					(width 0)
					(fill yes)
				)
			)
		)
		(pad "2" smd custom
			(at 0 0.4445 180)
			(size 0.1524 0.1524)
			(layers "F.Cu" "F.Mask" "F.Paste")
			(net "GND")
			(options
				(clearance outline)
				(anchor circle)
			)
			(primitives
				(gr_poly
					(pts
						(arc
							(start 0.3048 -0.2032)
							(mid 0.275042 -0.275042)
							(end 0.2032 -0.3048)
						)
						(arc
							(start -0.2032 -0.3048)
							(mid -0.275042 -0.275042)
							(end -0.3048 -0.2032)
						)
						(arc
							(start -0.3048 0.2032)
							(mid -0.275042 0.275042)
							(end -0.2032 0.3048)
						)
						(arc
							(start 0.2032 0.3048)
							(mid 0.275042 0.275042)
							(end 0.3048 0.2032)
						)
					)
					(width 0)
					(fill yes)
				)
			)
		)
	)
	(footprint ""
		(layer "F.Cu")
		(at 35.687 -240.3094 180)
		(property "Reference" "R56"
			(at 0 0 180)
			(layer "F.SilkS")
			(hide yes)
			(effects
				(font
					(size 1.27 1.27)
				)
			)
		)
		(property "Value" "4K7R2J-2-GP"
			(at 0.064008 -3.993896 180)
			(unlocked yes)
			(layer "F.Fab")
			(hide yes)
			(effects
				(font
					(size 1.016 1.016)
					(thickness 0.1524)
				)
			)
		)
		(property "Device Type" "R402H16"
			(at 0.064008 -5.517896 180)
			(unlocked yes)
			(layer "F.Fab")
			(hide yes)
			(effects
				(font
					(size 1.016 1.016)
					(thickness 0.1524)
				)
			)
		)
		(duplicate_pad_numbers_are_jumpers no)
		(fp_line
			(start 0.508 -0.9398)
			(end -0.508 -0.9398)
			(stroke
				(width 0.1524)
				(type default)
			)
			(layer "F.SilkS")
		)
		(fp_line
			(start -0.508 -0.9398)
			(end -0.508 0.9398)
			(stroke
				(width 0.1524)
				(type default)
			)
			(layer "F.SilkS")
		)
		(fp_rect
			(start -0.508 0.9398)
			(end 0.508 -0.9398)
			(stroke
				(width 0)
				(type default)
			)
			(fill no)
			(layer "F.CrtYd")
		)
		(fp_rect
			(start -0.508 0.9398)
			(end 0.508 -0.9398)
			(stroke
				(width 0)
				(type default)
			)
			(fill no)
			(layer "F.Fab")
		)
		(pad "1" smd custom
			(at 0 -0.4445 180)
			(size 0.1397 0.1397)
			(layers "F.Cu" "F.Mask" "F.Paste")
			(net "GND")
			(options
				(clearance outline)
				(anchor circle)
			)
			(primitives
				(gr_poly
					(pts
						(arc
							(start -0.1778 -0.2794)
							(mid -0.249642 -0.249642)
							(end -0.2794 -0.1778)
						)
						(arc
							(start -0.2794 0.1778)
							(mid -0.249642 0.249642)
							(end -0.1778 0.2794)
						)
						(arc
							(start 0.1778 0.2794)
							(mid 0.249642 0.249642)
							(end 0.2794 0.1778)
						)
						(arc
							(start 0.2794 -0.1778)
							(mid 0.249642 -0.249642)
							(end 0.1778 -0.2794)
						)
					)
					(width 0)
					(fill yes)
				)
			)
		)
		(pad "2" smd custom
			(at 0 0.4445 180)
			(size 0.1397 0.1397)
			(layers "F.Cu" "F.Mask" "F.Paste")
			(net "LED_DRV_A2")
			(options
				(clearance outline)
				(anchor circle)
			)
			(primitives
				(gr_poly
					(pts
						(arc
							(start -0.1778 -0.2794)
							(mid -0.249642 -0.249642)
							(end -0.2794 -0.1778)
						)
						(arc
							(start -0.2794 0.1778)
							(mid -0.249642 0.249642)
							(end -0.1778 0.2794)
						)
						(arc
							(start 0.1778 0.2794)
							(mid 0.249642 0.249642)
							(end 0.2794 0.1778)
						)
						(arc
							(start 0.2794 -0.1778)
							(mid 0.249642 -0.249642)
							(end 0.1778 -0.2794)
						)
					)
					(width 0)
					(fill yes)
				)
			)
		)
	)
	(footprint ""
		(layer "F.Cu")
		(at 20.828 -179.1716 180)
		(property "Reference" "R87"
			(at 0 0 180)
			(layer "F.SilkS")
			(hide yes)
			(effects
				(font
					(size 1.27 1.27)
				)
			)
		)
		(property "Value" "27KR3F-GP"
			(at -0.0254 -2.5146 180)
			(unlocked yes)
			(layer "F.Fab")
			(hide yes)
			(effects
				(font
					(size 1.016 1.016)
					(thickness 0.1524)
				)
			)
		)
		(property "Device Type" "R603H22"
			(at -0.0254 -4.0386 180)
			(unlocked yes)
			(layer "F.Fab")
			(hide yes)
			(effects
				(font
					(size 1.016 1.016)
					(thickness 0.1524)
				)
			)
		)
		(duplicate_pad_numbers_are_jumpers no)
		(fp_line
			(start 0.2032 0)
			(end 0.4826 0)
			(stroke
				(width 0.2032)
				(type default)
			)
			(layer "F.SilkS")
		)
		(fp_line
			(start -0.4826 0)
			(end -0.2032 0)
			(stroke
				(width 0.2032)
				(type default)
			)
			(layer "F.SilkS")
		)
		(fp_rect
			(start -0.5842 1.3335)
			(end 0.5842 -1.3335)
			(stroke
				(width 0)
				(type default)
			)
			(fill no)
			(layer "F.CrtYd")
		)
		(fp_rect
			(start -0.5842 1.3335)
			(end 0.5842 -1.3335)
			(stroke
				(width 0)
				(type default)
			)
			(fill no)
			(layer "F.Fab")
		)
		(pad "1" smd custom
			(at 0 -0.762 180)
			(size 0.2159 0.2159)
			(layers "F.Cu" "F.Mask" "F.Paste")
			(net "FANIN_7")
			(options
				(clearance outline)
				(anchor circle)
			)
			(primitives
				(gr_poly
					(pts
						(arc
							(start -0.3302 -0.4318)
							(mid -0.402042 -0.402042)
							(end -0.4318 -0.3302)
						)
						(arc
							(start -0.4318 0.3302)
							(mid -0.402042 0.402042)
							(end -0.3302 0.4318)
						)
						(arc
							(start 0.3302 0.4318)
							(mid 0.402042 0.402042)
							(end 0.4318 0.3302)
						)
						(arc
							(start 0.4318 -0.3302)
							(mid 0.402042 -0.402042)
							(end 0.3302 -0.4318)
						)
					)
					(width 0)
					(fill yes)
				)
			)
		)
		(pad "2" smd custom
			(at 0 0.762 180)
			(size 0.2159 0.2159)
			(layers "F.Cu" "F.Mask" "F.Paste")
			(net "FAN_TACH7")
			(options
				(clearance outline)
				(anchor circle)
			)
			(primitives
				(gr_poly
					(pts
						(arc
							(start -0.3302 -0.4318)
							(mid -0.402042 -0.402042)
							(end -0.4318 -0.3302)
						)
						(arc
							(start -0.4318 0.3302)
							(mid -0.402042 0.402042)
							(end -0.3302 0.4318)
						)
						(arc
							(start 0.3302 0.4318)
							(mid 0.402042 0.402042)
							(end 0.4318 0.3302)
						)
						(arc
							(start 0.4318 -0.3302)
							(mid 0.402042 -0.402042)
							(end 0.3302 -0.4318)
						)
					)
					(width 0)
					(fill yes)
				)
			)
		)
	)
	(footprint ""
		(layer "F.Cu")
		(at 36.957 -174.244)
		(property "Reference" "PQ9"
			(at 0 0 0)
			(layer "F.SilkS")
			(hide yes)
			(effects
				(font
					(size 1.27 1.27)
				)
			)
		)
		(property "Value" "PMBS3904-1-GP"
			(at 0 -9.0932 0)
			(unlocked yes)
			(layer "F.Fab")
			(hide yes)
			(effects
				(font
					(size 1.016 1.016)
					(thickness 0.1524)
				)
			)
		)
		(property "Device Type" "SOT-23-10H44"
			(at 0 -10.6172 0)
			(unlocked yes)
			(layer "F.Fab")
			(hide yes)
			(effects
				(font
					(size 1.016 1.016)
					(thickness 0.1524)
				)
			)
		)
		(duplicate_pad_numbers_are_jumpers no)
		(fp_line
			(start -1.7526 1.8796)
			(end -1.7526 0.9906)
			(stroke
				(width 0.3302)
				(type default)
			)
			(layer "F.SilkS")
		)
		(fp_line
			(start -1.651 -1.778)
			(end -1.651 1.778)
			(stroke
				(width 0.1524)
				(type default)
			)
			(layer "F.SilkS")
		)
		(fp_line
			(start -1.651 1.778)
			(end 1.651 1.778)
			(stroke
				(width 0.1524)
				(type default)
			)
			(layer "F.SilkS")
		)
		(fp_line
			(start -1.279398 2.152142)
			(end -0.9906 1.86309)
			(stroke
				(width 0.0127)
				(type default)
			)
			(layer "F.SilkS")
		)
		(fp_line
			(start -1.279144 2.15265)
			(end -0.701294 2.15265)
			(stroke
				(width 0.0127)
				(type default)
			)
			(layer "F.SilkS")
		)
		(fp_line
			(start -1.260856 2.1336)
			(end -0.720344 2.1336)
			(stroke
				(width 0.0127)
				(type default)
			)
			(layer "F.SilkS")
		)
		(fp_line
			(start -1.251458 2.124202)
			(end -0.729996 2.124202)
			(stroke
				(width 0.0127)
				(type default)
			)
			(layer "F.SilkS")
		)
		(fp_line
			(start -1.241806 2.11455)
			(end -0.739394 2.11455)
			(stroke
				(width 0.0127)
				(type default)
			)
			(layer "F.SilkS")
		)
		(fp_line
			(start -1.232408 2.105152)
			(end -0.749046 2.105152)
			(stroke
				(width 0.0127)
				(type default)
			)
			(layer "F.SilkS")
		)
		(fp_line
			(start -1.222756 2.0955)
			(end -0.758444 2.0955)
			(stroke
				(width 0.0127)
				(type default)
			)
			(layer "F.SilkS")
		)
		(fp_line
			(start -1.213358 2.086102)
			(end -0.768096 2.086102)
			(stroke
				(width 0.0127)
				(type default)
			)
			(layer "F.SilkS")
		)
		(fp_line
			(start -1.203706 2.07645)
			(end -0.777494 2.07645)
			(stroke
				(width 0.0127)
				(type default)
			)
			(layer "F.SilkS")
		)
		(fp_line
			(start -1.194308 2.067052)
			(end -0.787146 2.067052)
			(stroke
				(width 0.0127)
				(type default)
			)
			(layer "F.SilkS")
		)
		(fp_line
			(start -1.184656 2.0574)
			(end -0.796544 2.0574)
			(stroke
				(width 0.0127)
				(type default)
			)
			(layer "F.SilkS")
		)
		(fp_line
			(start -1.175258 2.048002)
			(end -0.806196 2.048002)
			(stroke
				(width 0.0127)
				(type default)
			)
			(layer "F.SilkS")
		)
		(fp_line
			(start -1.165606 2.03835)
			(end -0.815594 2.03835)
			(stroke
				(width 0.0127)
				(type default)
			)
			(layer "F.SilkS")
		)
		(fp_line
			(start -1.156208 2.028952)
			(end -0.825246 2.028952)
			(stroke
				(width 0.0127)
				(type default)
			)
			(layer "F.SilkS")
		)
		(fp_line
			(start -1.146556 2.0193)
			(end -0.834644 2.0193)
			(stroke
				(width 0.0127)
				(type default)
			)
			(layer "F.SilkS")
		)
		(fp_line
			(start -1.137158 2.009902)
			(end -0.844296 2.009902)
			(stroke
				(width 0.0127)
				(type default)
			)
			(layer "F.SilkS")
		)
		(fp_line
			(start -1.127506 2.00025)
			(end -0.853694 2.00025)
			(stroke
				(width 0.0127)
				(type default)
			)
			(layer "F.SilkS")
		)
		(fp_line
			(start -1.118108 1.990852)
			(end -0.863346 1.990852)
			(stroke
				(width 0.0127)
				(type default)
			)
			(layer "F.SilkS")
		)
		(fp_line
			(start -1.108456 1.9812)
			(end -0.872744 1.9812)
			(stroke
				(width 0.0127)
				(type default)
			)
			(layer "F.SilkS")
		)
		(fp_line
			(start -1.099058 1.971802)
			(end -0.882396 1.971802)
			(stroke
				(width 0.0127)
				(type default)
			)
			(layer "F.SilkS")
		)
		(fp_line
			(start -1.089406 1.96215)
			(end -0.891794 1.96215)
			(stroke
				(width 0.0127)
				(type default)
			)
			(layer "F.SilkS")
		)
		(fp_line
			(start -1.080008 1.952752)
			(end -0.901446 1.952752)
			(stroke
				(width 0.0127)
				(type default)
			)
			(layer "F.SilkS")
		)
		(fp_line
			(start -1.070356 1.9431)
			(end -0.910844 1.9431)
			(stroke
				(width 0.0127)
				(type default)
			)
			(layer "F.SilkS")
		)
		(fp_line
			(start -1.060958 1.933702)
			(end -0.920496 1.933702)
			(stroke
				(width 0.0127)
				(type default)
			)
			(layer "F.SilkS")
		)
		(fp_line
			(start -1.051306 1.92405)
			(end -0.929894 1.92405)
			(stroke
				(width 0.0127)
				(type default)
			)
			(layer "F.SilkS")
		)
		(fp_line
			(start -1.041908 1.914652)
			(end -0.939546 1.914652)
			(stroke
				(width 0.0127)
				(type default)
			)
			(layer "F.SilkS")
		)
		(fp_line
			(start -1.032256 1.905)
			(end -0.948944 1.905)
			(stroke
				(width 0.0127)
				(type default)
			)
			(layer "F.SilkS")
		)
		(fp_line
			(start -1.022858 1.895602)
			(end -0.958596 1.895602)
			(stroke
				(width 0.0127)
				(type default)
			)
			(layer "F.SilkS")
		)
		(fp_line
			(start -1.013206 1.88595)
			(end -0.967994 1.88595)
			(stroke
				(width 0.0127)
				(type default)
			)
			(layer "F.SilkS")
		)
		(fp_line
			(start -1.003808 1.876552)
			(end -0.977646 1.876552)
			(stroke
				(width 0.0127)
				(type default)
			)
			(layer "F.SilkS")
		)
		(fp_line
			(start -0.994156 1.8669)
			(end -0.987044 1.8669)
			(stroke
				(width 0.0127)
				(type default)
			)
			(layer "F.SilkS")
		)
		(fp_line
			(start -0.9906 1.86309)
			(end -0.701294 2.15265)
			(stroke
				(width 0.0127)
				(type default)
			)
			(layer "F.SilkS")
		)
		(fp_line
			(start -0.719074 2.145538)
			(end -1.265936 2.14122)
			(stroke
				(width 0.0127)
				(type default)
			)
			(layer "F.SilkS")
		)
		(fp_line
			(start -0.71628 2.15265)
			(end -1.26492 2.15265)
			(stroke
				(width 0.0127)
				(type default)
			)
			(layer "F.SilkS")
		)
		(fp_line
			(start -0.635 1.8796)
			(end -1.7526 1.8796)
			(stroke
				(width 0.3302)
				(type default)
			)
			(layer "F.SilkS")
		)
		(fp_line
			(start 1.651 -1.778)
			(end -1.651 -1.778)
			(stroke
				(width 0.1524)
				(type default)
			)
			(layer "F.SilkS")
		)
		(fp_line
			(start 1.651 1.778)
			(end 1.651 -1.778)
			(stroke
				(width 0.1524)
				(type default)
			)
			(layer "F.SilkS")
		)
		(fp_poly
			(pts
				(xy -1.285748 2.159) (xy -1.285748 1.8796) (xy -1.778 1.8796) (xy -1.778 -1.8796) (xy 1.778 -1.8796)
				(xy 1.778 1.8796) (xy -0.694944 1.8796) (xy -0.694944 2.159)
			)
			(stroke
				(width 0)
				(type default)
			)
			(fill no)
			(layer "F.CrtYd")
		)
		(fp_poly
			(pts
				(xy -1.285748 2.159) (xy -1.285748 1.8796) (xy -1.778 1.8796) (xy -1.778 -1.8796) (xy 1.778 -1.8796)
				(xy 1.778 1.8796) (xy -0.694944 1.8796) (xy -0.694944 2.159)
			)
			(stroke
				(width 0)
				(type default)
			)
			(fill no)
			(layer "F.Fab")
		)
		(pad "1" smd rect
			(at -0.98425 0.9525)
			(size 0.762 1.143)
			(layers "F.Cu" "F.Mask" "F.Paste")
			(net "TEMP_ALM#_IN")
		)
		(pad "2" smd rect
			(at 0.98425 0.9525)
			(size 0.762 1.143)
			(layers "F.Cu" "F.Mask" "F.Paste")
			(net "GND")
		)
		(pad "3" smd rect
			(at 0 -0.9525)
			(size 0.762 1.143)
			(layers "F.Cu" "F.Mask" "F.Paste")
			(net "TEMP_ALM#_IN_D")
		)
	)
	(footprint ""
		(layer "F.Cu")
		(at 7.949946 -443.900052 -90)
		(property "Reference" "LED1"
			(at 0 0 270)
			(layer "F.SilkS")
			(hide yes)
			(effects
				(font
					(size 1.27 1.27)
				)
			)
		)
		(property "Value" "LED-RB-6-GP"
			(at -4.6736 3.8354 270)
			(unlocked yes)
			(layer "F.Fab")
			(hide yes)
			(effects
				(font
					(size 1.016 1.016)
					(thickness 0.1524)
				)
			)
		)
		(property "Device Type" "LED-100-3P-067106H325"
			(at -4.6736 2.3114 270)
			(unlocked yes)
			(layer "F.Fab")
			(hide yes)
			(effects
				(font
					(size 1.016 1.016)
					(thickness 0.1524)
				)
			)
		)
		(duplicate_pad_numbers_are_jumpers no)
		(fp_line
			(start -1.7526 10.414)
			(end -1.7526 6.6548)
			(stroke
				(width 0.1524)
				(type default)
			)
			(layer "F.SilkS")
		)
		(fp_line
			(start 1.7526 10.414)
			(end -1.7526 10.414)
			(stroke
				(width 0.1524)
				(type default)
			)
			(layer "F.SilkS")
		)
		(fp_line
			(start -3.6068 6.6548)
			(end -3.6068 -0.889)
			(stroke
				(width 0.1524)
				(type default)
			)
			(layer "F.SilkS")
		)
		(fp_line
			(start -1.7526 6.6548)
			(end -3.6068 6.6548)
			(stroke
				(width 0.1524)
				(type default)
			)
			(layer "F.SilkS")
		)
		(fp_line
			(start 1.7526 6.6548)
			(end 1.7526 10.414)
			(stroke
				(width 0.1524)
				(type default)
			)
			(layer "F.SilkS")
		)
		(fp_line
			(start 3.6068 6.6548)
			(end 1.7526 6.6548)
			(stroke
				(width 0.1524)
				(type default)
			)
			(layer "F.SilkS")
		)
		(fp_line
			(start -3.6068 -0.889)
			(end 3.6068 -0.889)
			(stroke
				(width 0.1524)
				(type default)
			)
			(layer "F.SilkS")
		)
		(fp_line
			(start 3.6068 -0.889)
			(end 3.6068 6.6548)
			(stroke
				(width 0.1524)
				(type default)
			)
			(layer "F.SilkS")
		)
		(fp_circle
			(center -2.54 0)
			(end -2.54 -0.9906)
			(stroke
				(width 0.3048)
				(type default)
			)
			(fill no)
			(layer "F.SilkS")
		)
		(fp_circle
			(center 0 0)
			(end 0 -0.9906)
			(stroke
				(width 0.3048)
				(type default)
			)
			(fill no)
			(layer "F.SilkS")
		)
		(fp_circle
			(center 2.54 0)
			(end 2.54 -0.9906)
			(stroke
				(width 0.3048)
				(type default)
			)
			(fill no)
			(layer "F.SilkS")
		)
		(fp_poly
			(pts
				(xy -1.4986 10.1473) (xy -1.4986 6.4008) (xy -3.3528 6.4008) (xy -3.3528 -0.3937) (xy 3.3528 -0.3937)
				(xy 3.3528 6.4008) (xy 1.4986 6.4008) (xy 1.4986 10.1473)
			)
			(stroke
				(width 0)
				(type default)
			)
			(fill no)
			(layer "F.CrtYd")
		)
		(fp_poly
			(pts
				(xy -2.0066 10.668) (xy 2.0066 10.668) (xy 2.0066 6.9088) (xy 3.8608 6.9088) (xy 3.8608 2.2098)
				(xy 3.3528 2.2098) (xy 3.3528 6.4008) (xy 1.4986 6.4008) (xy 1.4986 10.1473) (xy -1.4986 10.1473)
				(xy -1.4986 6.4008) (xy -3.3528 6.4008) (xy -3.3528 -0.3937) (xy 3.3528 -0.3937) (xy 3.3528 2.1971)
				(xy 3.8608 2.1971) (xy 3.8608 -1.143) (xy -3.8608 -1.143) (xy -3.8608 6.9088) (xy -2.0066 6.9088)
			)
			(stroke
				(width 0)
				(type default)
			)
			(fill no)
			(layer "F.CrtYd")
		)
		(fp_poly
			(pts
				(xy -2.0066 10.668) (xy -2.0066 6.9088) (xy -3.8608 6.9088) (xy -3.8608 -1.143) (xy 3.8608 -1.143)
				(xy 3.8608 6.9088) (xy 2.0066 6.9088) (xy 2.0066 10.668)
			)
			(stroke
				(width 0)
				(type default)
			)
			(fill no)
			(layer "F.Fab")
		)
		(pad "1" thru_hole circle
			(at 2.54 0 270)
			(size 1.27 1.27)
			(drill 0.889)
			(layers "*.Cu" "*.Mask")
			(remove_unused_layers no)
			(net "LED_DR_LED0_BLUE")
			(clearance 0.1651)
			(thermal_gap 0.1651)
		)
		(pad "2" thru_hole circle
			(at 0 0 270)
			(size 1.27 1.27)
			(drill 0.889)
			(layers "*.Cu" "*.Mask")
			(remove_unused_layers no)
			(net "LED_DR_LED0_K")
			(clearance 0.1651)
			(thermal_gap 0.1651)
		)
		(pad "3" thru_hole circle
			(at -2.54 0 270)
			(size 1.27 1.27)
			(drill 0.889)
			(layers "*.Cu" "*.Mask")
			(remove_unused_layers no)
			(net "LED_DR_LED0")
			(clearance 0.1651)
			(thermal_gap 0.1651)
		)
	)
	(footprint ""
		(layer "F.Cu")
		(at 36.7284 -478.4598 90)
		(property "Reference" "C49"
			(at 0 0 90)
			(layer "F.SilkS")
			(hide yes)
			(effects
				(font
					(size 1.27 1.27)
				)
			)
		)
		(property "Value" "SCD1U50V3KX-GP"
			(at 0 -2.8194 90)
			(unlocked yes)
			(layer "F.Fab")
			(hide yes)
			(effects
				(font
					(size 1.016 1.016)
					(thickness 0.1524)
				)
			)
		)
		(property "Device Type" "C603H36"
			(at 0 -4.3434 90)
			(unlocked yes)
			(layer "F.Fab")
			(hide yes)
			(effects
				(font
					(size 1.016 1.016)
					(thickness 0.1524)
				)
			)
		)
		(duplicate_pad_numbers_are_jumpers no)
		(fp_line
			(start 0.508 0)
			(end -0.508 0)
			(stroke
				(width 0.2032)
				(type default)
			)
			(layer "F.SilkS")
		)
		(fp_rect
			(start -0.5842 1.3335)
			(end 0.5842 -1.3335)
			(stroke
				(width 0)
				(type default)
			)
			(fill no)
			(layer "F.CrtYd")
		)
		(fp_rect
			(start -0.5842 1.3335)
			(end 0.5842 -1.3335)
			(stroke
				(width 0)
				(type default)
			)
			(fill no)
			(layer "F.Fab")
		)
		(pad "1" smd custom
			(at 0 -0.762 90)
			(size 0.2159 0.2159)
			(layers "F.Cu" "F.Mask" "F.Paste")
			(net "P12V")
			(options
				(clearance outline)
				(anchor circle)
			)
			(primitives
				(gr_poly
					(pts
						(arc
							(start -0.3302 -0.4318)
							(mid -0.402042 -0.402042)
							(end -0.4318 -0.3302)
						)
						(arc
							(start -0.4318 0.3302)
							(mid -0.402042 0.402042)
							(end -0.3302 0.4318)
						)
						(arc
							(start 0.3302 0.4318)
							(mid 0.402042 0.402042)
							(end 0.4318 0.3302)
						)
						(arc
							(start 0.4318 -0.3302)
							(mid 0.402042 -0.402042)
							(end 0.3302 -0.4318)
						)
					)
					(width 0)
					(fill yes)
				)
			)
		)
		(pad "2" smd custom
			(at 0 0.762 90)
			(size 0.2159 0.2159)
			(layers "F.Cu" "F.Mask" "F.Paste")
			(net "GND")
			(options
				(clearance outline)
				(anchor circle)
			)
			(primitives
				(gr_poly
					(pts
						(arc
							(start -0.3302 -0.4318)
							(mid -0.402042 -0.402042)
							(end -0.4318 -0.3302)
						)
						(arc
							(start -0.4318 0.3302)
							(mid -0.402042 0.402042)
							(end -0.3302 0.4318)
						)
						(arc
							(start 0.3302 0.4318)
							(mid 0.402042 0.402042)
							(end 0.4318 0.3302)
						)
						(arc
							(start 0.4318 -0.3302)
							(mid 0.402042 -0.402042)
							(end 0.3302 -0.4318)
						)
					)
					(width 0)
					(fill yes)
				)
			)
		)
	)
	(footprint ""
		(layer "F.Cu")
		(at 39.116 -252.603 -90)
		(property "Reference" "TP19"
			(at 0 0 270)
			(layer "F.SilkS")
			(hide yes)
			(effects
				(font
					(size 1.27 1.27)
				)
			)
		)
		(property "Value" "TPAD32-GP"
			(at 0 -3.166364 270)
			(unlocked yes)
			(layer "F.Fab")
			(hide yes)
			(effects
				(font
					(size 1.016 1.016)
					(thickness 0.1524)
				)
			)
		)
		(property "Device Type" "TPAD32"
			(at 0 -4.690618 270)
			(unlocked yes)
			(layer "F.Fab")
			(hide yes)
			(effects
				(font
					(size 1.016 1.016)
					(thickness 0.1524)
				)
			)
		)
		(duplicate_pad_numbers_are_jumpers no)
		(fp_poly
			(pts
				(arc
					(start 0.7112 0)
					(mid -0.7112 0)
					(end 0.7112 0)
				)
			)
			(stroke
				(width 0)
				(type default)
			)
			(fill no)
			(layer "F.CrtYd")
		)
		(fp_poly
			(pts
				(arc
					(start 0.7112 0)
					(mid -0.7112 0)
					(end 0.7112 0)
				)
			)
			(stroke
				(width 0)
				(type default)
			)
			(fill no)
			(layer "F.Fab")
		)
		(pad "1" smd circle
			(at 0 0 270)
			(size 0.8128 0.8128)
			(layers "F.Cu" "F.Mask" "F.Paste")
			(net "LED_DR_LED6_RESERVE")
		)
	)
	(footprint ""
		(layer "F.Cu")
		(at 21.463 -91.9226 -90)
		(property "Reference" "D15"
			(at 0 0 270)
			(layer "F.SilkS")
			(hide yes)
			(effects
				(font
					(size 1.27 1.27)
				)
			)
		)
		(property "Value" "MBRS340T3G-GP"
			(at 0 -10.6172 270)
			(unlocked yes)
			(layer "F.Fab")
			(hide yes)
			(effects
				(font
					(size 1.016 1.016)
					(thickness 0.1524)
				)
			)
		)
		(property "Device Type" "D8059AKH101"
			(at 0 -12.1412 270)
			(unlocked yes)
			(layer "F.Fab")
			(hide yes)
			(effects
				(font
					(size 1.016 1.016)
					(thickness 0.1524)
				)
			)
		)
		(duplicate_pad_numbers_are_jumpers no)
		(fp_line
			(start 3.175 5.2832)
			(end -3.175 5.2832)
			(stroke
				(width 0.508)
				(type default)
			)
			(layer "F.SilkS")
		)
		(fp_line
			(start -3.175 5.1054)
			(end -3.175 -5.1054)
			(stroke
				(width 0.1524)
				(type default)
			)
			(layer "F.SilkS")
		)
		(fp_line
			(start 3.175 5.1054)
			(end -3.175 5.1054)
			(stroke
				(width 0.1524)
				(type default)
			)
			(layer "F.SilkS")
		)
		(fp_line
			(start -3.175 -5.1054)
			(end 3.175 -5.1054)
			(stroke
				(width 0.1524)
				(type default)
			)
			(layer "F.SilkS")
		)
		(fp_line
			(start 3.175 -5.1054)
			(end 3.175 5.1054)
			(stroke
				(width 0.1524)
				(type default)
			)
			(layer "F.SilkS")
		)
		(fp_rect
			(start -3.429 5.1816)
			(end 3.429 -5.1816)
			(stroke
				(width 0)
				(type default)
			)
			(fill no)
			(layer "F.CrtYd")
		)
		(fp_poly
			(pts
				(xy -3.429 -5.1816) (xy 3.429 -5.1816) (xy 3.429 5.1816) (xy -3.429 5.1816)
			)
			(stroke
				(width 0)
				(type default)
			)
			(fill no)
			(layer "F.Fab")
		)
		(pad "A" smd rect
			(at 0 -3.77571 270)
			(size 3.2512 2.159)
			(layers "F.Cu" "F.Mask" "F.Paste")
			(net "GND")
		)
		(pad "K" smd rect
			(at 0 3.77571 270)
			(size 3.2512 2.159)
			(layers "F.Cu" "F.Mask" "F.Paste")
			(net "P12VU")
		)
	)
	(footprint ""
		(layer "F.Cu")
		(at 41.7576 -159.1818 -90)
		(property "Reference" "R15"
			(at 0 0 270)
			(layer "F.SilkS")
			(hide yes)
			(effects
				(font
					(size 1.27 1.27)
				)
			)
		)
		(property "Value" "10KR2F-2-GP"
			(at 0.064008 -3.993896 270)
			(unlocked yes)
			(layer "F.Fab")
			(hide yes)
			(effects
				(font
					(size 1.016 1.016)
					(thickness 0.1524)
				)
			)
		)
		(property "Device Type" "R402H16"
			(at 0.064008 -5.517896 270)
			(unlocked yes)
			(layer "F.Fab")
			(hide yes)
			(effects
				(font
					(size 1.016 1.016)
					(thickness 0.1524)
				)
			)
		)
		(duplicate_pad_numbers_are_jumpers no)
		(fp_line
			(start -0.508 -0.9398)
			(end -0.508 0.9398)
			(stroke
				(width 0.1524)
				(type default)
			)
			(layer "F.SilkS")
		)
		(fp_line
			(start 0.508 -0.9398)
			(end -0.508 -0.9398)
			(stroke
				(width 0.1524)
				(type default)
			)
			(layer "F.SilkS")
		)
		(fp_rect
			(start -0.508 0.9398)
			(end 0.508 -0.9398)
			(stroke
				(width 0)
				(type default)
			)
			(fill no)
			(layer "F.CrtYd")
		)
		(fp_rect
			(start -0.508 0.9398)
			(end 0.508 -0.9398)
			(stroke
				(width 0)
				(type default)
			)
			(fill no)
			(layer "F.Fab")
		)
		(pad "1" smd custom
			(at 0 -0.4445 270)
			(size 0.1397 0.1397)
			(layers "F.Cu" "F.Mask" "F.Paste")
			(net "NCT7904_VSEN_P12V_AUX")
			(options
				(clearance outline)
				(anchor circle)
			)
			(primitives
				(gr_poly
					(pts
						(arc
							(start -0.1778 -0.2794)
							(mid -0.249642 -0.249642)
							(end -0.2794 -0.1778)
						)
						(arc
							(start -0.2794 0.1778)
							(mid -0.249642 0.249642)
							(end -0.1778 0.2794)
						)
						(arc
							(start 0.1778 0.2794)
							(mid 0.249642 0.249642)
							(end 0.2794 0.1778)
						)
						(arc
							(start 0.2794 -0.1778)
							(mid 0.249642 -0.249642)
							(end 0.1778 -0.2794)
						)
					)
					(width 0)
					(fill yes)
				)
			)
		)
		(pad "2" smd custom
			(at 0 0.4445 270)
			(size 0.1397 0.1397)
			(layers "F.Cu" "F.Mask" "F.Paste")
			(net "GND")
			(options
				(clearance outline)
				(anchor circle)
			)
			(primitives
				(gr_poly
					(pts
						(arc
							(start -0.1778 -0.2794)
							(mid -0.249642 -0.249642)
							(end -0.2794 -0.1778)
						)
						(arc
							(start -0.2794 0.1778)
							(mid -0.249642 0.249642)
							(end -0.1778 0.2794)
						)
						(arc
							(start 0.1778 0.2794)
							(mid 0.249642 0.249642)
							(end 0.2794 0.1778)
						)
						(arc
							(start 0.2794 -0.1778)
							(mid 0.249642 -0.249642)
							(end 0.1778 -0.2794)
						)
					)
					(width 0)
					(fill yes)
				)
			)
		)
	)
	(footprint ""
		(layer "F.Cu")
		(at 36.9062 -147.447 180)
		(property "Reference" "PR115"
			(at 0 0 180)
			(layer "F.SilkS")
			(hide yes)
			(effects
				(font
					(size 1.27 1.27)
				)
			)
		)
		(property "Value" "20KR2F-L-GP"
			(at 0.064008 -3.993896 180)
			(unlocked yes)
			(layer "F.Fab")
			(hide yes)
			(effects
				(font
					(size 1.016 1.016)
					(thickness 0.1524)
				)
			)
		)
		(property "Device Type" "R402H16"
			(at 0.064008 -5.517896 180)
			(unlocked yes)
			(layer "F.Fab")
			(hide yes)
			(effects
				(font
					(size 1.016 1.016)
					(thickness 0.1524)
				)
			)
		)
		(duplicate_pad_numbers_are_jumpers no)
		(fp_line
			(start 0.508 -0.9398)
			(end -0.508 -0.9398)
			(stroke
				(width 0.1524)
				(type default)
			)
			(layer "F.SilkS")
		)
		(fp_line
			(start -0.508 -0.9398)
			(end -0.508 0.9398)
			(stroke
				(width 0.1524)
				(type default)
			)
			(layer "F.SilkS")
		)
		(fp_rect
			(start -0.508 0.9398)
			(end 0.508 -0.9398)
			(stroke
				(width 0)
				(type default)
			)
			(fill no)
			(layer "F.CrtYd")
		)
		(fp_rect
			(start -0.508 0.9398)
			(end 0.508 -0.9398)
			(stroke
				(width 0)
				(type default)
			)
			(fill no)
			(layer "F.Fab")
		)
		(pad "1" smd custom
			(at 0 -0.4445 180)
			(size 0.1397 0.1397)
			(layers "F.Cu" "F.Mask" "F.Paste")
			(net "P12VL_2490_PROG")
			(options
				(clearance outline)
				(anchor circle)
			)
			(primitives
				(gr_poly
					(pts
						(arc
							(start -0.1778 -0.2794)
							(mid -0.249642 -0.249642)
							(end -0.2794 -0.1778)
						)
						(arc
							(start -0.2794 0.1778)
							(mid -0.249642 0.249642)
							(end -0.1778 0.2794)
						)
						(arc
							(start 0.1778 0.2794)
							(mid 0.249642 0.249642)
							(end 0.2794 0.1778)
						)
						(arc
							(start 0.2794 -0.1778)
							(mid 0.249642 -0.249642)
							(end 0.1778 -0.2794)
						)
					)
					(width 0)
					(fill yes)
				)
			)
		)
		(pad "2" smd custom
			(at 0 0.4445 180)
			(size 0.1397 0.1397)
			(layers "F.Cu" "F.Mask" "F.Paste")
			(net "GND")
			(options
				(clearance outline)
				(anchor circle)
			)
			(primitives
				(gr_poly
					(pts
						(arc
							(start -0.1778 -0.2794)
							(mid -0.249642 -0.249642)
							(end -0.2794 -0.1778)
						)
						(arc
							(start -0.2794 0.1778)
							(mid -0.249642 0.249642)
							(end -0.1778 0.2794)
						)
						(arc
							(start 0.1778 0.2794)
							(mid 0.249642 0.249642)
							(end 0.2794 0.1778)
						)
						(arc
							(start 0.2794 -0.1778)
							(mid 0.249642 -0.249642)
							(end 0.1778 -0.2794)
						)
					)
					(width 0)
					(fill yes)
				)
			)
		)
	)
	(footprint ""
		(layer "F.Cu")
		(at 38.43909 -161.068766 180)
		(property "Reference" "R5"
			(at 0 0 180)
			(layer "F.SilkS")
			(hide yes)
			(effects
				(font
					(size 1.27 1.27)
				)
			)
		)
		(property "Value" "0R2J-2-GP"
			(at 0.064008 -3.993896 180)
			(unlocked yes)
			(layer "F.Fab")
			(hide yes)
			(effects
				(font
					(size 1.016 1.016)
					(thickness 0.1524)
				)
			)
		)
		(property "Device Type" "R402H16"
			(at 0.064008 -5.517896 180)
			(unlocked yes)
			(layer "F.Fab")
			(hide yes)
			(effects
				(font
					(size 1.016 1.016)
					(thickness 0.1524)
				)
			)
		)
		(duplicate_pad_numbers_are_jumpers no)
		(fp_line
			(start 0.508 -0.9398)
			(end -0.508 -0.9398)
			(stroke
				(width 0.1524)
				(type default)
			)
			(layer "F.SilkS")
		)
		(fp_line
			(start -0.508 -0.9398)
			(end -0.508 0.9398)
			(stroke
				(width 0.1524)
				(type default)
			)
			(layer "F.SilkS")
		)
		(fp_rect
			(start -0.508 0.9398)
			(end 0.508 -0.9398)
			(stroke
				(width 0)
				(type default)
			)
			(fill no)
			(layer "F.CrtYd")
		)
		(fp_rect
			(start -0.508 0.9398)
			(end 0.508 -0.9398)
			(stroke
				(width 0)
				(type default)
			)
			(fill no)
			(layer "F.Fab")
		)
		(pad "1" smd custom
			(at 0 -0.4445 180)
			(size 0.1397 0.1397)
			(layers "F.Cu" "F.Mask" "F.Paste")
			(net "NCT7904_CLKIN")
			(options
				(clearance outline)
				(anchor circle)
			)
			(primitives
				(gr_poly
					(pts
						(arc
							(start -0.1778 -0.2794)
							(mid -0.249642 -0.249642)
							(end -0.2794 -0.1778)
						)
						(arc
							(start -0.2794 0.1778)
							(mid -0.249642 0.249642)
							(end -0.1778 0.2794)
						)
						(arc
							(start 0.1778 0.2794)
							(mid 0.249642 0.249642)
							(end 0.2794 0.1778)
						)
						(arc
							(start 0.2794 -0.1778)
							(mid 0.249642 -0.249642)
							(end 0.1778 -0.2794)
						)
					)
					(width 0)
					(fill yes)
				)
			)
		)
		(pad "2" smd custom
			(at 0 0.4445 180)
			(size 0.1397 0.1397)
			(layers "F.Cu" "F.Mask" "F.Paste")
			(net "NCT7904_CLK")
			(options
				(clearance outline)
				(anchor circle)
			)
			(primitives
				(gr_poly
					(pts
						(arc
							(start -0.1778 -0.2794)
							(mid -0.249642 -0.249642)
							(end -0.2794 -0.1778)
						)
						(arc
							(start -0.2794 0.1778)
							(mid -0.249642 0.249642)
							(end -0.1778 0.2794)
						)
						(arc
							(start 0.1778 0.2794)
							(mid 0.249642 0.249642)
							(end 0.2794 0.1778)
						)
						(arc
							(start 0.2794 -0.1778)
							(mid 0.249642 -0.249642)
							(end 0.1778 -0.2794)
						)
					)
					(width 0)
					(fill yes)
				)
			)
		)
	)
	(footprint ""
		(layer "F.Cu")
		(at 31.9024 -91.8972 90)
		(property "Reference" "D16"
			(at 0 0 90)
			(layer "F.SilkS")
			(hide yes)
			(effects
				(font
					(size 1.27 1.27)
				)
			)
		)
		(property "Value" "MBRS340T3G-GP"
			(at 0 -10.6172 90)
			(unlocked yes)
			(layer "F.Fab")
			(hide yes)
			(effects
				(font
					(size 1.016 1.016)
					(thickness 0.1524)
				)
			)
		)
		(property "Device Type" "D8059AKH101"
			(at 0 -12.1412 90)
			(unlocked yes)
			(layer "F.Fab")
			(hide yes)
			(effects
				(font
					(size 1.016 1.016)
					(thickness 0.1524)
				)
			)
		)
		(duplicate_pad_numbers_are_jumpers no)
		(fp_line
			(start 3.175 -5.1054)
			(end 3.175 5.1054)
			(stroke
				(width 0.1524)
				(type default)
			)
			(layer "F.SilkS")
		)
		(fp_line
			(start -3.175 -5.1054)
			(end 3.175 -5.1054)
			(stroke
				(width 0.1524)
				(type default)
			)
			(layer "F.SilkS")
		)
		(fp_line
			(start 3.175 5.1054)
			(end -3.175 5.1054)
			(stroke
				(width 0.1524)
				(type default)
			)
			(layer "F.SilkS")
		)
		(fp_line
			(start -3.175 5.1054)
			(end -3.175 -5.1054)
			(stroke
				(width 0.1524)
				(type default)
			)
			(layer "F.SilkS")
		)
		(fp_line
			(start 3.175 5.2832)
			(end -3.175 5.2832)
			(stroke
				(width 0.508)
				(type default)
			)
			(layer "F.SilkS")
		)
		(fp_rect
			(start -3.429 5.1816)
			(end 3.429 -5.1816)
			(stroke
				(width 0)
				(type default)
			)
			(fill no)
			(layer "F.CrtYd")
		)
		(fp_poly
			(pts
				(xy -3.429 -5.1816) (xy 3.429 -5.1816) (xy 3.429 5.1816) (xy -3.429 5.1816)
			)
			(stroke
				(width 0)
				(type default)
			)
			(fill no)
			(layer "F.Fab")
		)
		(pad "A" smd rect
			(at 0 -3.77571 90)
			(size 3.2512 2.159)
			(layers "F.Cu" "F.Mask" "F.Paste")
			(net "GND")
		)
		(pad "K" smd rect
			(at 0 3.77571 90)
			(size 3.2512 2.159)
			(layers "F.Cu" "F.Mask" "F.Paste")
			(net "P12VL")
		)
	)
	(footprint ""
		(layer "F.Cu")
		(at 42.5958 -177.2666 180)
		(property "Reference" "PR47"
			(at 0 0 180)
			(layer "F.SilkS")
			(hide yes)
			(effects
				(font
					(size 1.27 1.27)
				)
			)
		)
		(property "Value" "4K7R2J-2-GP"
			(at 0.064008 -3.993896 180)
			(unlocked yes)
			(layer "F.Fab")
			(hide yes)
			(effects
				(font
					(size 1.016 1.016)
					(thickness 0.1524)
				)
			)
		)
		(property "Device Type" "R402H16"
			(at 0.064008 -5.517896 180)
			(unlocked yes)
			(layer "F.Fab")
			(hide yes)
			(effects
				(font
					(size 1.016 1.016)
					(thickness 0.1524)
				)
			)
		)
		(duplicate_pad_numbers_are_jumpers no)
		(fp_line
			(start 0.508 -0.9398)
			(end -0.508 -0.9398)
			(stroke
				(width 0.1524)
				(type default)
			)
			(layer "F.SilkS")
		)
		(fp_line
			(start -0.508 -0.9398)
			(end -0.508 0.9398)
			(stroke
				(width 0.1524)
				(type default)
			)
			(layer "F.SilkS")
		)
		(fp_rect
			(start -0.508 0.9398)
			(end 0.508 -0.9398)
			(stroke
				(width 0)
				(type default)
			)
			(fill no)
			(layer "F.CrtYd")
		)
		(fp_rect
			(start -0.508 0.9398)
			(end 0.508 -0.9398)
			(stroke
				(width 0)
				(type default)
			)
			(fill no)
			(layer "F.Fab")
		)
		(pad "1" smd custom
			(at 0 -0.4445 180)
			(size 0.1397 0.1397)
			(layers "F.Cu" "F.Mask" "F.Paste")
			(net "P3V3_AUX")
			(options
				(clearance outline)
				(anchor circle)
			)
			(primitives
				(gr_poly
					(pts
						(arc
							(start -0.1778 -0.2794)
							(mid -0.249642 -0.249642)
							(end -0.2794 -0.1778)
						)
						(arc
							(start -0.2794 0.1778)
							(mid -0.249642 0.249642)
							(end -0.1778 0.2794)
						)
						(arc
							(start 0.1778 0.2794)
							(mid 0.249642 0.249642)
							(end 0.2794 0.1778)
						)
						(arc
							(start 0.2794 -0.1778)
							(mid 0.249642 -0.249642)
							(end 0.1778 -0.2794)
						)
					)
					(width 0)
					(fill yes)
				)
			)
		)
		(pad "2" smd custom
			(at 0 0.4445 180)
			(size 0.1397 0.1397)
			(layers "F.Cu" "F.Mask" "F.Paste")
			(net "D_LATCH_Q")
			(options
				(clearance outline)
				(anchor circle)
			)
			(primitives
				(gr_poly
					(pts
						(arc
							(start -0.1778 -0.2794)
							(mid -0.249642 -0.249642)
							(end -0.2794 -0.1778)
						)
						(arc
							(start -0.2794 0.1778)
							(mid -0.249642 0.249642)
							(end -0.1778 0.2794)
						)
						(arc
							(start 0.1778 0.2794)
							(mid 0.249642 0.249642)
							(end 0.2794 0.1778)
						)
						(arc
							(start 0.2794 -0.1778)
							(mid 0.249642 -0.249642)
							(end 0.1778 -0.2794)
						)
					)
					(width 0)
					(fill yes)
				)
			)
		)
	)
	(footprint ""
		(layer "F.Cu")
		(at 37.719 -352.425 90)
		(property "Reference" "C261"
			(at 0 0 90)
			(layer "F.SilkS")
			(hide yes)
			(effects
				(font
					(size 1.27 1.27)
				)
			)
		)
		(property "Value" "SC10U25V6KX-1GP"
			(at -0.0762 -5.1308 90)
			(unlocked yes)
			(layer "F.Fab")
			(hide yes)
			(effects
				(font
					(size 1.016 1.016)
					(thickness 0.1524)
				)
			)
		)
		(property "Device Type" "C1206H71"
			(at -0.127 -6.6548 90)
			(unlocked yes)
			(layer "F.Fab")
			(hide yes)
			(effects
				(font
					(size 1.016 1.016)
					(thickness 0.1524)
				)
			)
		)
		(duplicate_pad_numbers_are_jumpers no)
		(fp_line
			(start 1.016 -2.2352)
			(end 1.016 -0.8382)
			(stroke
				(width 0.1524)
				(type default)
			)
			(layer "F.SilkS")
		)
		(fp_line
			(start -1.016 -2.2352)
			(end 1.016 -2.2352)
			(stroke
				(width 0.1524)
				(type default)
			)
			(layer "F.SilkS")
		)
		(fp_line
			(start -1.016 -0.8382)
			(end -1.016 -2.2352)
			(stroke
				(width 0.1524)
				(type default)
			)
			(layer "F.SilkS")
		)
		(fp_line
			(start 1.016 0.8382)
			(end 1.016 2.2352)
			(stroke
				(width 0.1524)
				(type default)
			)
			(layer "F.SilkS")
		)
		(fp_line
			(start 1.016 2.2352)
			(end -1.016 2.2352)
			(stroke
				(width 0.1524)
				(type default)
			)
			(layer "F.SilkS")
		)
		(fp_line
			(start -1.016 2.2352)
			(end -1.016 0.8382)
			(stroke
				(width 0.1524)
				(type default)
			)
			(layer "F.SilkS")
		)
		(fp_rect
			(start -1.0922 2.3114)
			(end 1.0922 -2.3114)
			(stroke
				(width 0)
				(type default)
			)
			(fill no)
			(layer "F.CrtYd")
		)
		(fp_poly
			(pts
				(xy 1.0922 -2.3114) (xy 1.0922 2.3114) (xy -1.0922 2.3114) (xy -1.0922 -2.3114)
			)
			(stroke
				(width 0)
				(type default)
			)
			(fill no)
			(layer "F.Fab")
		)
		(pad "1" smd rect
			(at 0 -1.397 90)
			(size 1.651 1.27)
			(layers "F.Cu" "F.Mask" "F.Paste")
			(net "OTP_RETRY_G")
		)
		(pad "2" smd rect
			(at 0 1.397 90)
			(size 1.651 1.27)
			(layers "F.Cu" "F.Mask" "F.Paste")
			(net "GND")
		)
	)
	(footprint ""
		(layer "F.Cu")
		(at 15.9258 -146.6088 90)
		(property "Reference" "R68"
			(at 0 0 90)
			(layer "F.SilkS")
			(hide yes)
			(effects
				(font
					(size 1.27 1.27)
				)
			)
		)
		(property "Value" "4K7R2F-GP"
			(at 0.064008 -3.993896 90)
			(unlocked yes)
			(layer "F.Fab")
			(hide yes)
			(effects
				(font
					(size 1.016 1.016)
					(thickness 0.1524)
				)
			)
		)
		(property "Device Type" "R402H16"
			(at 0.064008 -5.517896 90)
			(unlocked yes)
			(layer "F.Fab")
			(hide yes)
			(effects
				(font
					(size 1.016 1.016)
					(thickness 0.1524)
				)
			)
		)
		(duplicate_pad_numbers_are_jumpers no)
		(fp_line
			(start -0.508 -0.9398)
			(end -1.524 -0.9398)
			(stroke
				(width 0.1524)
				(type default)
			)
			(layer "F.SilkS")
		)
		(fp_line
			(start -1.524 -0.9398)
			(end -1.524 0.9398)
			(stroke
				(width 0.1524)
				(type default)
			)
			(layer "F.SilkS")
		)
		(fp_rect
			(start -0.508 0.9398)
			(end 0.508 -0.9398)
			(stroke
				(width 0)
				(type default)
			)
			(fill no)
			(layer "F.CrtYd")
		)
		(fp_rect
			(start -0.508 0.9398)
			(end 0.508 -0.9398)
			(stroke
				(width 0)
				(type default)
			)
			(fill no)
			(layer "F.Fab")
		)
		(pad "1" smd custom
			(at 0 -0.4445 90)
			(size 0.1397 0.1397)
			(layers "F.Cu" "F.Mask" "F.Paste")
			(net "P12V")
			(options
				(clearance outline)
				(anchor circle)
			)
			(primitives
				(gr_poly
					(pts
						(arc
							(start -0.1778 -0.2794)
							(mid -0.249642 -0.249642)
							(end -0.2794 -0.1778)
						)
						(arc
							(start -0.2794 0.1778)
							(mid -0.249642 0.249642)
							(end -0.1778 0.2794)
						)
						(arc
							(start 0.1778 0.2794)
							(mid 0.249642 0.249642)
							(end 0.2794 0.1778)
						)
						(arc
							(start 0.2794 -0.1778)
							(mid 0.249642 -0.249642)
							(end 0.1778 -0.2794)
						)
					)
					(width 0)
					(fill yes)
				)
			)
		)
		(pad "2" smd custom
			(at 0 0.4445 90)
			(size 0.1397 0.1397)
			(layers "F.Cu" "F.Mask" "F.Paste")
			(net "FAN_TACH9")
			(options
				(clearance outline)
				(anchor circle)
			)
			(primitives
				(gr_poly
					(pts
						(arc
							(start -0.1778 -0.2794)
							(mid -0.249642 -0.249642)
							(end -0.2794 -0.1778)
						)
						(arc
							(start -0.2794 0.1778)
							(mid -0.249642 0.249642)
							(end -0.1778 0.2794)
						)
						(arc
							(start 0.1778 0.2794)
							(mid 0.249642 0.249642)
							(end 0.2794 0.1778)
						)
						(arc
							(start 0.2794 -0.1778)
							(mid 0.249642 -0.249642)
							(end 0.1778 -0.2794)
						)
					)
					(width 0)
					(fill yes)
				)
			)
		)
	)
	(footprint ""
		(layer "F.Cu")
		(at 15.494 -167.0304 90)
		(property "Reference" "C33"
			(at 0 0 90)
			(layer "F.SilkS")
			(hide yes)
			(effects
				(font
					(size 1.27 1.27)
				)
			)
		)
		(property "Value" "SCD1U50V3KX-GP"
			(at 0 -2.8194 90)
			(unlocked yes)
			(layer "F.Fab")
			(hide yes)
			(effects
				(font
					(size 1.016 1.016)
					(thickness 0.1524)
				)
			)
		)
		(property "Device Type" "C603H36"
			(at 0 -4.3434 90)
			(unlocked yes)
			(layer "F.Fab")
			(hide yes)
			(effects
				(font
					(size 1.016 1.016)
					(thickness 0.1524)
				)
			)
		)
		(duplicate_pad_numbers_are_jumpers no)
		(fp_line
			(start 0.508 0)
			(end -0.508 0)
			(stroke
				(width 0.2032)
				(type default)
			)
			(layer "F.SilkS")
		)
		(fp_rect
			(start -0.5842 1.3335)
			(end 0.5842 -1.3335)
			(stroke
				(width 0)
				(type default)
			)
			(fill no)
			(layer "F.CrtYd")
		)
		(fp_rect
			(start -0.5842 1.3335)
			(end 0.5842 -1.3335)
			(stroke
				(width 0)
				(type default)
			)
			(fill no)
			(layer "F.Fab")
		)
		(pad "1" smd custom
			(at 0 -0.762 90)
			(size 0.2159 0.2159)
			(layers "F.Cu" "F.Mask" "F.Paste")
			(net "P12V")
			(options
				(clearance outline)
				(anchor circle)
			)
			(primitives
				(gr_poly
					(pts
						(arc
							(start -0.3302 -0.4318)
							(mid -0.402042 -0.402042)
							(end -0.4318 -0.3302)
						)
						(arc
							(start -0.4318 0.3302)
							(mid -0.402042 0.402042)
							(end -0.3302 0.4318)
						)
						(arc
							(start 0.3302 0.4318)
							(mid 0.402042 0.402042)
							(end 0.4318 0.3302)
						)
						(arc
							(start 0.4318 -0.3302)
							(mid 0.402042 -0.402042)
							(end 0.3302 -0.4318)
						)
					)
					(width 0)
					(fill yes)
				)
			)
		)
		(pad "2" smd custom
			(at 0 0.762 90)
			(size 0.2159 0.2159)
			(layers "F.Cu" "F.Mask" "F.Paste")
			(net "GND")
			(options
				(clearance outline)
				(anchor circle)
			)
			(primitives
				(gr_poly
					(pts
						(arc
							(start -0.3302 -0.4318)
							(mid -0.402042 -0.402042)
							(end -0.4318 -0.3302)
						)
						(arc
							(start -0.4318 0.3302)
							(mid -0.402042 0.402042)
							(end -0.3302 0.4318)
						)
						(arc
							(start 0.3302 0.4318)
							(mid 0.402042 0.402042)
							(end 0.4318 0.3302)
						)
						(arc
							(start 0.4318 -0.3302)
							(mid 0.402042 -0.402042)
							(end 0.3302 -0.4318)
						)
					)
					(width 0)
					(fill yes)
				)
			)
		)
	)
	(footprint ""
		(layer "F.Cu")
		(at 32.399224 -173.65091 90)
		(property "Reference" "R17"
			(at 0 0 90)
			(layer "F.SilkS")
			(hide yes)
			(effects
				(font
					(size 1.27 1.27)
				)
			)
		)
		(property "Value" "100KR2F-L1-GP"
			(at 0.064008 -3.993896 90)
			(unlocked yes)
			(layer "F.Fab")
			(hide yes)
			(effects
				(font
					(size 1.016 1.016)
					(thickness 0.1524)
				)
			)
		)
		(property "Device Type" "R402H16"
			(at 0.064008 -5.517896 90)
			(unlocked yes)
			(layer "F.Fab")
			(hide yes)
			(effects
				(font
					(size 1.016 1.016)
					(thickness 0.1524)
				)
			)
		)
		(duplicate_pad_numbers_are_jumpers no)
		(fp_line
			(start 0.508 -0.9398)
			(end -0.508 -0.9398)
			(stroke
				(width 0.1524)
				(type default)
			)
			(layer "F.SilkS")
		)
		(fp_line
			(start -0.508 -0.9398)
			(end -0.508 0.9398)
			(stroke
				(width 0.1524)
				(type default)
			)
			(layer "F.SilkS")
		)
		(fp_rect
			(start -0.508 0.9398)
			(end 0.508 -0.9398)
			(stroke
				(width 0)
				(type default)
			)
			(fill no)
			(layer "F.CrtYd")
		)
		(fp_rect
			(start -0.508 0.9398)
			(end 0.508 -0.9398)
			(stroke
				(width 0)
				(type default)
			)
			(fill no)
			(layer "F.Fab")
		)
		(pad "1" smd custom
			(at 0 -0.4445 90)
			(size 0.1397 0.1397)
			(layers "F.Cu" "F.Mask" "F.Paste")
			(net "PWM_EXP_1A")
			(options
				(clearance outline)
				(anchor circle)
			)
			(primitives
				(gr_poly
					(pts
						(arc
							(start -0.1778 -0.2794)
							(mid -0.249642 -0.249642)
							(end -0.2794 -0.1778)
						)
						(arc
							(start -0.2794 0.1778)
							(mid -0.249642 0.249642)
							(end -0.1778 0.2794)
						)
						(arc
							(start 0.1778 0.2794)
							(mid 0.249642 0.249642)
							(end 0.2794 0.1778)
						)
						(arc
							(start 0.2794 -0.1778)
							(mid 0.249642 -0.249642)
							(end 0.1778 -0.2794)
						)
					)
					(width 0)
					(fill yes)
				)
			)
		)
		(pad "2" smd custom
			(at 0 0.4445 90)
			(size 0.1397 0.1397)
			(layers "F.Cu" "F.Mask" "F.Paste")
			(net "GND")
			(options
				(clearance outline)
				(anchor circle)
			)
			(primitives
				(gr_poly
					(pts
						(arc
							(start -0.1778 -0.2794)
							(mid -0.249642 -0.249642)
							(end -0.2794 -0.1778)
						)
						(arc
							(start -0.2794 0.1778)
							(mid -0.249642 0.249642)
							(end -0.1778 0.2794)
						)
						(arc
							(start 0.1778 0.2794)
							(mid 0.249642 0.249642)
							(end 0.2794 0.1778)
						)
						(arc
							(start 0.2794 -0.1778)
							(mid 0.249642 -0.249642)
							(end 0.1778 -0.2794)
						)
					)
					(width 0)
					(fill yes)
				)
			)
		)
	)
	(footprint ""
		(layer "F.Cu")
		(at 7.3406 -174.7774 180)
		(property "Reference" "C52"
			(at 0 0 180)
			(layer "F.SilkS")
			(hide yes)
			(effects
				(font
					(size 1.27 1.27)
				)
			)
		)
		(property "Value" "SCD1U50V3KX-GP"
			(at 0 -2.8194 180)
			(unlocked yes)
			(layer "F.Fab")
			(hide yes)
			(effects
				(font
					(size 1.016 1.016)
					(thickness 0.1524)
				)
			)
		)
		(property "Device Type" "C603H36"
			(at 0 -4.3434 180)
			(unlocked yes)
			(layer "F.Fab")
			(hide yes)
			(effects
				(font
					(size 1.016 1.016)
					(thickness 0.1524)
				)
			)
		)
		(duplicate_pad_numbers_are_jumpers no)
		(fp_line
			(start 0.508 0)
			(end -0.508 0)
			(stroke
				(width 0.2032)
				(type default)
			)
			(layer "F.SilkS")
		)
		(fp_rect
			(start -0.5842 1.3335)
			(end 0.5842 -1.3335)
			(stroke
				(width 0)
				(type default)
			)
			(fill no)
			(layer "F.CrtYd")
		)
		(fp_rect
			(start -0.5842 1.3335)
			(end 0.5842 -1.3335)
			(stroke
				(width 0)
				(type default)
			)
			(fill no)
			(layer "F.Fab")
		)
		(pad "1" smd custom
			(at 0 -0.762 180)
			(size 0.2159 0.2159)
			(layers "F.Cu" "F.Mask" "F.Paste")
			(net "P3V3")
			(options
				(clearance outline)
				(anchor circle)
			)
			(primitives
				(gr_poly
					(pts
						(arc
							(start -0.3302 -0.4318)
							(mid -0.402042 -0.402042)
							(end -0.4318 -0.3302)
						)
						(arc
							(start -0.4318 0.3302)
							(mid -0.402042 0.402042)
							(end -0.3302 0.4318)
						)
						(arc
							(start 0.3302 0.4318)
							(mid 0.402042 0.402042)
							(end 0.4318 0.3302)
						)
						(arc
							(start 0.4318 -0.3302)
							(mid 0.402042 -0.402042)
							(end 0.3302 -0.4318)
						)
					)
					(width 0)
					(fill yes)
				)
			)
		)
		(pad "2" smd custom
			(at 0 0.762 180)
			(size 0.2159 0.2159)
			(layers "F.Cu" "F.Mask" "F.Paste")
			(net "GND")
			(options
				(clearance outline)
				(anchor circle)
			)
			(primitives
				(gr_poly
					(pts
						(arc
							(start -0.3302 -0.4318)
							(mid -0.402042 -0.402042)
							(end -0.4318 -0.3302)
						)
						(arc
							(start -0.4318 0.3302)
							(mid -0.402042 0.402042)
							(end -0.3302 0.4318)
						)
						(arc
							(start 0.3302 0.4318)
							(mid 0.402042 0.402042)
							(end 0.4318 0.3302)
						)
						(arc
							(start 0.4318 -0.3302)
							(mid 0.402042 -0.402042)
							(end 0.3302 -0.4318)
						)
					)
					(width 0)
					(fill yes)
				)
			)
		)
	)
	(footprint ""
		(layer "F.Cu")
		(at 18.288 -271.7038 90)
		(property "Reference" "R179"
			(at 0 0 90)
			(layer "F.SilkS")
			(hide yes)
			(effects
				(font
					(size 1.27 1.27)
				)
			)
		)
		(property "Value" "0R1206-PAD-1-GP"
			(at 0 -5.0292 90)
			(unlocked yes)
			(layer "F.Fab")
			(hide yes)
			(effects
				(font
					(size 1.016 1.016)
					(thickness 0.1524)
				)
			)
		)
		(property "Device Type" "0R1206-PAD-1"
			(at 0 -6.5532 90)
			(unlocked yes)
			(layer "F.Fab")
			(hide yes)
			(effects
				(font
					(size 1.016 1.016)
					(thickness 0.1524)
				)
			)
		)
		(duplicate_pad_numbers_are_jumpers no)
		(fp_line
			(start 1.016 -2.2352)
			(end -1.016 -2.2352)
			(stroke
				(width 0.1524)
				(type default)
			)
			(layer "F.SilkS")
		)
		(fp_line
			(start -1.016 -2.2352)
			(end -1.016 2.2352)
			(stroke
				(width 0.1524)
				(type default)
			)
			(layer "F.SilkS")
		)
		(fp_line
			(start 1.016 2.2352)
			(end 1.016 -2.2352)
			(stroke
				(width 0.1524)
				(type default)
			)
			(layer "F.SilkS")
		)
		(fp_line
			(start -1.016 2.2352)
			(end 1.016 2.2352)
			(stroke
				(width 0.1524)
				(type default)
			)
			(layer "F.SilkS")
		)
		(fp_rect
			(start -1.0922 2.3114)
			(end 1.0922 -2.3114)
			(stroke
				(width 0)
				(type default)
			)
			(fill no)
			(layer "F.CrtYd")
		)
		(fp_poly
			(pts
				(xy -1.0922 -2.3114) (xy 1.0922 -2.3114) (xy 1.0922 2.3114) (xy -1.0922 2.3114)
			)
			(stroke
				(width 0)
				(type default)
			)
			(fill no)
			(layer "F.Fab")
		)
		(pad "1" smd rect
			(at 0 -1.397 90)
			(size 1.651 2.0574)
			(drill
				(offset 0 0.3937)
			)
			(layers "F.Cu" "F.Mask" "F.Paste")
			(net "P12V_FAN3")
		)
		(pad "2" smd rect
			(at 0 1.397 90)
			(size 1.651 2.0574)
			(drill
				(offset 0 -0.3937)
			)
			(layers "F.Cu" "F.Mask" "F.Paste")
			(net "P12V")
		)
	)
	(footprint ""
		(layer "F.Cu")
		(at 21.7678 -217.7288 90)
		(property "Reference" "R133"
			(at 0 0 90)
			(layer "F.SilkS")
			(hide yes)
			(effects
				(font
					(size 1.27 1.27)
				)
			)
		)
		(property "Value" "4K7R2F-GP"
			(at 0.064008 -3.993896 90)
			(unlocked yes)
			(layer "F.Fab")
			(hide yes)
			(effects
				(font
					(size 1.016 1.016)
					(thickness 0.1524)
				)
			)
		)
		(property "Device Type" "R402H16"
			(at 0.064008 -5.517896 90)
			(unlocked yes)
			(layer "F.Fab")
			(hide yes)
			(effects
				(font
					(size 1.016 1.016)
					(thickness 0.1524)
				)
			)
		)
		(duplicate_pad_numbers_are_jumpers no)
		(fp_line
			(start 0.508 -0.9398)
			(end -0.508 -0.9398)
			(stroke
				(width 0.1524)
				(type default)
			)
			(layer "F.SilkS")
		)
		(fp_line
			(start -0.508 -0.9398)
			(end -0.508 0.9398)
			(stroke
				(width 0.1524)
				(type default)
			)
			(layer "F.SilkS")
		)
		(fp_rect
			(start -0.508 0.9398)
			(end 0.508 -0.9398)
			(stroke
				(width 0)
				(type default)
			)
			(fill no)
			(layer "F.CrtYd")
		)
		(fp_rect
			(start -0.508 0.9398)
			(end 0.508 -0.9398)
			(stroke
				(width 0)
				(type default)
			)
			(fill no)
			(layer "F.Fab")
		)
		(pad "1" smd custom
			(at 0 -0.4445 90)
			(size 0.1397 0.1397)
			(layers "F.Cu" "F.Mask" "F.Paste")
			(net "P3V3")
			(options
				(clearance outline)
				(anchor circle)
			)
			(primitives
				(gr_poly
					(pts
						(arc
							(start -0.1778 -0.2794)
							(mid -0.249642 -0.249642)
							(end -0.2794 -0.1778)
						)
						(arc
							(start -0.2794 0.1778)
							(mid -0.249642 0.249642)
							(end -0.1778 0.2794)
						)
						(arc
							(start 0.1778 0.2794)
							(mid 0.249642 0.249642)
							(end 0.2794 0.1778)
						)
						(arc
							(start 0.2794 -0.1778)
							(mid 0.249642 -0.249642)
							(end 0.1778 -0.2794)
						)
					)
					(width 0)
					(fill yes)
				)
			)
		)
		(pad "2" smd custom
			(at 0 0.4445 90)
			(size 0.1397 0.1397)
			(layers "F.Cu" "F.Mask" "F.Paste")
			(net "PWM_OUT_FAN3")
			(options
				(clearance outline)
				(anchor circle)
			)
			(primitives
				(gr_poly
					(pts
						(arc
							(start -0.1778 -0.2794)
							(mid -0.249642 -0.249642)
							(end -0.2794 -0.1778)
						)
						(arc
							(start -0.2794 0.1778)
							(mid -0.249642 0.249642)
							(end -0.1778 0.2794)
						)
						(arc
							(start 0.1778 0.2794)
							(mid 0.249642 0.249642)
							(end 0.2794 0.1778)
						)
						(arc
							(start 0.2794 -0.1778)
							(mid 0.249642 -0.249642)
							(end 0.1778 -0.2794)
						)
					)
					(width 0)
					(fill yes)
				)
			)
		)
	)
	(footprint ""
		(layer "F.Cu")
		(at 24.70531 -151.325834)
		(property "Reference" "R10"
			(at 0 0 0)
			(layer "F.SilkS")
			(hide yes)
			(effects
				(font
					(size 1.27 1.27)
				)
			)
		)
		(property "Value" "1MR2J-1-GP"
			(at 0.064008 -3.993896 0)
			(unlocked yes)
			(layer "F.Fab")
			(hide yes)
			(effects
				(font
					(size 1.016 1.016)
					(thickness 0.1524)
				)
			)
		)
		(property "Device Type" "R402H16"
			(at 0.064008 -5.517896 0)
			(unlocked yes)
			(layer "F.Fab")
			(hide yes)
			(effects
				(font
					(size 1.016 1.016)
					(thickness 0.1524)
				)
			)
		)
		(duplicate_pad_numbers_are_jumpers no)
		(fp_line
			(start -0.508 -0.9398)
			(end -0.508 0.9398)
			(stroke
				(width 0.1524)
				(type default)
			)
			(layer "F.SilkS")
		)
		(fp_line
			(start 0.508 -0.9398)
			(end -0.508 -0.9398)
			(stroke
				(width 0.1524)
				(type default)
			)
			(layer "F.SilkS")
		)
		(fp_rect
			(start -0.508 0.9398)
			(end 0.508 -0.9398)
			(stroke
				(width 0)
				(type default)
			)
			(fill no)
			(layer "F.CrtYd")
		)
		(fp_rect
			(start -0.508 0.9398)
			(end 0.508 -0.9398)
			(stroke
				(width 0)
				(type default)
			)
			(fill no)
			(layer "F.Fab")
		)
		(pad "1" smd custom
			(at 0 -0.4445)
			(size 0.1397 0.1397)
			(layers "F.Cu" "F.Mask" "F.Paste")
			(net "NCT7904_CASEOPEN")
			(options
				(clearance outline)
				(anchor circle)
			)
			(primitives
				(gr_poly
					(pts
						(arc
							(start -0.1778 -0.2794)
							(mid -0.249642 -0.249642)
							(end -0.2794 -0.1778)
						)
						(arc
							(start -0.2794 0.1778)
							(mid -0.249642 0.249642)
							(end -0.1778 0.2794)
						)
						(arc
							(start 0.1778 0.2794)
							(mid 0.249642 0.249642)
							(end 0.2794 0.1778)
						)
						(arc
							(start 0.2794 -0.1778)
							(mid 0.249642 -0.249642)
							(end 0.1778 -0.2794)
						)
					)
					(width 0)
					(fill yes)
				)
			)
		)
		(pad "2" smd custom
			(at 0 0.4445)
			(size 0.1397 0.1397)
			(layers "F.Cu" "F.Mask" "F.Paste")
			(net "NCT7904_3VSB")
			(options
				(clearance outline)
				(anchor circle)
			)
			(primitives
				(gr_poly
					(pts
						(arc
							(start -0.1778 -0.2794)
							(mid -0.249642 -0.249642)
							(end -0.2794 -0.1778)
						)
						(arc
							(start -0.2794 0.1778)
							(mid -0.249642 0.249642)
							(end -0.1778 0.2794)
						)
						(arc
							(start 0.1778 0.2794)
							(mid 0.249642 0.249642)
							(end 0.2794 0.1778)
						)
						(arc
							(start 0.2794 -0.1778)
							(mid 0.249642 -0.249642)
							(end 0.1778 -0.2794)
						)
					)
					(width 0)
					(fill yes)
				)
			)
		)
	)
	(footprint ""
		(layer "F.Cu")
		(at 19.3294 -277.0124 -90)
		(property "Reference" "TC16"
			(at 0 0 270)
			(layer "F.SilkS")
			(hide yes)
			(effects
				(font
					(size 1.27 1.27)
				)
			)
		)
		(property "Value" "ST15U25VDM-1-GP"
			(at 0 -9.6012 270)
			(unlocked yes)
			(layer "F.Fab")
			(hide yes)
			(effects
				(font
					(size 1.016 1.016)
					(thickness 0.1524)
				)
			)
		)
		(property "Device Type" "CT7343H79"
			(at 0 -11.1252 270)
			(unlocked yes)
			(layer "F.Fab")
			(hide yes)
			(effects
				(font
					(size 1.016 1.016)
					(thickness 0.1524)
				)
			)
		)
		(duplicate_pad_numbers_are_jumpers no)
		(fp_line
			(start -2.286 4.8768)
			(end -2.286 2.032)
			(stroke
				(width 0.1524)
				(type default)
			)
			(layer "F.SilkS")
		)
		(fp_line
			(start 2.286 4.8768)
			(end -2.286 4.8768)
			(stroke
				(width 0.1524)
				(type default)
			)
			(layer "F.SilkS")
		)
		(fp_line
			(start 2.286 2.032)
			(end 2.286 4.8768)
			(stroke
				(width 0.1524)
				(type default)
			)
			(layer "F.SilkS")
		)
		(fp_line
			(start 2.286 -2.032)
			(end 2.286 -4.8768)
			(stroke
				(width 0.1524)
				(type default)
			)
			(layer "F.SilkS")
		)
		(fp_line
			(start 2.1082 -4.699)
			(end -2.1082 -4.699)
			(stroke
				(width 0.508)
				(type default)
			)
			(layer "F.SilkS")
		)
		(fp_line
			(start -2.286 -4.8768)
			(end -2.286 -2.032)
			(stroke
				(width 0.1524)
				(type default)
			)
			(layer "F.SilkS")
		)
		(fp_line
			(start 2.286 -4.8768)
			(end -2.286 -4.8768)
			(stroke
				(width 0.1524)
				(type default)
			)
			(layer "F.SilkS")
		)
		(fp_rect
			(start -2.1463 3.6449)
			(end 2.1463 -3.6449)
			(stroke
				(width 0)
				(type default)
			)
			(fill no)
			(layer "F.CrtYd")
		)
		(fp_poly
			(pts
				(xy -2.54 4.953) (xy -2.54 4.2926) (xy -3.81 4.2926) (xy -3.81 -4.2926) (xy -2.54 -4.2926) (xy -2.54 -4.953)
				(xy 2.54 -4.953) (xy 2.54 -4.2926) (xy 3.81 -4.2926) (xy 3.81 -1.6256) (xy 2.1463 -1.6256) (xy 2.1463 -3.6449)
				(xy -2.1463 -3.6449) (xy -2.1463 3.6449) (xy 2.1463 3.6449) (xy 2.1463 -1.6129) (xy 3.81 -1.6129)
				(xy 3.81 4.2926) (xy 2.54 4.2926) (xy 2.54 4.953)
			)
			(stroke
				(width 0)
				(type default)
			)
			(fill no)
			(layer "F.CrtYd")
		)
		(fp_rect
			(start -2.54 4.953)
			(end 2.54 -4.953)
			(stroke
				(width 0)
				(type default)
			)
			(fill no)
			(layer "F.Fab")
		)
		(fp_rect
			(start -3.81 4.2926)
			(end -2.54 -4.2926)
			(stroke
				(width 0)
				(type default)
			)
			(fill no)
			(layer "F.Fab")
		)
		(fp_rect
			(start 2.54 4.2926)
			(end 3.81 -4.2926)
			(stroke
				(width 0)
				(type default)
			)
			(fill no)
			(layer "F.Fab")
		)
		(pad "1" smd rect
			(at 0 -3.1496 270)
			(size 2.413 2.286)
			(layers "F.Cu" "F.Mask" "F.Paste")
			(net "P12V")
		)
		(pad "2" smd rect
			(at 0 3.1496 270)
			(size 2.413 2.286)
			(layers "F.Cu" "F.Mask" "F.Paste")
			(net "GND")
		)
		(zone
			(layer "F.Cu")
			(hatch none 0.5)
			(connect_pads
				(clearance 0)
			)
			(min_thickness 0.25)
			(keepout
				(tracks allowed)
				(vias not_allowed)
				(pads allowed)
				(copperpour not_allowed)
				(footprints allowed)
			)
			(placement
				(enabled no)
				(sheetname "")
			)
			(fill
				(thermal_gap 0.5)
				(thermal_bridge_width 0.5)
				(island_removal_mode 0)
			)
			(polygon
				(pts
					(xy 14.732 -278.5237) (xy 14.732 -275.5011) (xy 17.6276 -275.5011) (xy 17.9578 -275.5011) (xy 17.9578 -278.5237)
					(xy 17.6276 -278.5237)
				)
			)
		)
		(zone
			(layer "F.Cu")
			(hatch none 0.5)
			(connect_pads
				(clearance 0)
			)
			(min_thickness 0.25)
			(keepout
				(tracks allowed)
				(vias not_allowed)
				(pads allowed)
				(copperpour not_allowed)
				(footprints allowed)
			)
			(placement
				(enabled no)
				(sheetname "")
			)
			(fill
				(thermal_gap 0.5)
				(thermal_bridge_width 0.5)
				(island_removal_mode 0)
			)
			(polygon
				(pts
					(xy 21.0185 -275.5011) (xy 23.9268 -275.5011) (xy 23.9268 -278.5237) (xy 21.0312 -278.5237) (xy 20.701 -278.5237)
					(xy 20.701 -275.5011)
				)
			)
		)
	)
	(footprint ""
		(layer "F.Cu")
		(at 45.83811 -160.825434)
		(property "Reference" "C6"
			(at 0 0 0)
			(layer "F.SilkS")
			(hide yes)
			(effects
				(font
					(size 1.27 1.27)
				)
			)
		)
		(property "Value" "SC4D7U6D3V2MX-GP-U"
			(at -1.524 -1.905 0)
			(unlocked yes)
			(layer "F.Fab")
			(hide yes)
			(effects
				(font
					(size 1.016 1.016)
					(thickness 0.1524)
				)
			)
		)
		(property "Device Type" "C402-TO0D2H26"
			(at -1.524 -3.429 0)
			(unlocked yes)
			(layer "F.Fab")
			(hide yes)
			(effects
				(font
					(size 1.016 1.016)
					(thickness 0.1524)
				)
			)
		)
		(duplicate_pad_numbers_are_jumpers no)
		(fp_rect
			(start -0.4826 0.889)
			(end 0.4826 -0.889)
			(stroke
				(width 0)
				(type default)
			)
			(fill no)
			(layer "F.CrtYd")
		)
		(fp_rect
			(start -0.4826 0.889)
			(end 0.4826 -0.889)
			(stroke
				(width 0)
				(type default)
			)
			(fill no)
			(layer "F.Fab")
		)
		(pad "1" smd custom
			(at 0 -0.4572)
			(size 0.1524 0.1524)
			(layers "F.Cu" "F.Mask" "F.Paste")
			(net "P3V3")
			(options
				(clearance outline)
				(anchor circle)
			)
			(primitives
				(gr_poly
					(pts
						(arc
							(start -0.254 0.3048)
							(mid -0.325842 0.275042)
							(end -0.3556 0.2032)
						)
						(arc
							(start -0.3556 -0.2032)
							(mid -0.325842 -0.275042)
							(end -0.254 -0.3048)
						)
						(arc
							(start 0.254 -0.3048)
							(mid 0.325842 -0.275042)
							(end 0.3556 -0.2032)
						)
						(arc
							(start 0.3556 0.2032)
							(mid 0.325842 0.275042)
							(end 0.254 0.3048)
						)
					)
					(width 0)
					(fill yes)
				)
			)
		)
		(pad "2" smd custom
			(at 0 0.4572)
			(size 0.1524 0.1524)
			(layers "F.Cu" "F.Mask" "F.Paste")
			(net "GND")
			(options
				(clearance outline)
				(anchor circle)
			)
			(primitives
				(gr_poly
					(pts
						(arc
							(start -0.254 0.3048)
							(mid -0.325842 0.275042)
							(end -0.3556 0.2032)
						)
						(arc
							(start -0.3556 -0.2032)
							(mid -0.325842 -0.275042)
							(end -0.254 -0.3048)
						)
						(arc
							(start 0.254 -0.3048)
							(mid 0.325842 -0.275042)
							(end 0.3556 -0.2032)
						)
						(arc
							(start 0.3556 0.2032)
							(mid 0.325842 0.275042)
							(end 0.254 0.3048)
						)
					)
					(width 0)
					(fill yes)
				)
			)
		)
	)
	(footprint ""
		(layer "F.Cu")
		(at 23.749 -101.219 90)
		(property "Reference" "TC4"
			(at 0 0 90)
			(layer "F.SilkS")
			(hide yes)
			(effects
				(font
					(size 1.27 1.27)
				)
			)
		)
		(property "Value" "ST15U25VDM-1-GP"
			(at 0 -9.6012 90)
			(unlocked yes)
			(layer "F.Fab")
			(hide yes)
			(effects
				(font
					(size 1.016 1.016)
					(thickness 0.1524)
				)
			)
		)
		(property "Device Type" "CT7343H79"
			(at 0 -11.1252 90)
			(unlocked yes)
			(layer "F.Fab")
			(hide yes)
			(effects
				(font
					(size 1.016 1.016)
					(thickness 0.1524)
				)
			)
		)
		(duplicate_pad_numbers_are_jumpers no)
		(fp_line
			(start 2.286 -4.8768)
			(end -2.286 -4.8768)
			(stroke
				(width 0.1524)
				(type default)
			)
			(layer "F.SilkS")
		)
		(fp_line
			(start -2.286 -4.8768)
			(end -2.286 -2.032)
			(stroke
				(width 0.1524)
				(type default)
			)
			(layer "F.SilkS")
		)
		(fp_line
			(start 2.1082 -4.699)
			(end -2.1082 -4.699)
			(stroke
				(width 0.508)
				(type default)
			)
			(layer "F.SilkS")
		)
		(fp_line
			(start 2.286 -2.032)
			(end 2.286 -4.8768)
			(stroke
				(width 0.1524)
				(type default)
			)
			(layer "F.SilkS")
		)
		(fp_line
			(start 2.286 2.032)
			(end 2.286 4.8768)
			(stroke
				(width 0.1524)
				(type default)
			)
			(layer "F.SilkS")
		)
		(fp_line
			(start 2.286 4.8768)
			(end -2.286 4.8768)
			(stroke
				(width 0.1524)
				(type default)
			)
			(layer "F.SilkS")
		)
		(fp_line
			(start -2.286 4.8768)
			(end -2.286 2.032)
			(stroke
				(width 0.1524)
				(type default)
			)
			(layer "F.SilkS")
		)
		(fp_rect
			(start -2.1463 3.6449)
			(end 2.1463 -3.6449)
			(stroke
				(width 0)
				(type default)
			)
			(fill no)
			(layer "F.CrtYd")
		)
		(fp_poly
			(pts
				(xy -2.54 4.953) (xy -2.54 4.2926) (xy -3.81 4.2926) (xy -3.81 -4.2926) (xy -2.54 -4.2926) (xy -2.54 -4.953)
				(xy 2.54 -4.953) (xy 2.54 -4.2926) (xy 3.81 -4.2926) (xy 3.81 -1.6256) (xy 2.1463 -1.6256) (xy 2.1463 -3.6449)
				(xy -2.1463 -3.6449) (xy -2.1463 3.6449) (xy 2.1463 3.6449) (xy 2.1463 -1.6129) (xy 3.81 -1.6129)
				(xy 3.81 4.2926) (xy 2.54 4.2926) (xy 2.54 4.953)
			)
			(stroke
				(width 0)
				(type default)
			)
			(fill no)
			(layer "F.CrtYd")
		)
		(fp_rect
			(start 2.54 4.2926)
			(end 3.81 -4.2926)
			(stroke
				(width 0)
				(type default)
			)
			(fill no)
			(layer "F.Fab")
		)
		(fp_rect
			(start -3.81 4.2926)
			(end -2.54 -4.2926)
			(stroke
				(width 0)
				(type default)
			)
			(fill no)
			(layer "F.Fab")
		)
		(fp_rect
			(start -2.54 4.953)
			(end 2.54 -4.953)
			(stroke
				(width 0)
				(type default)
			)
			(fill no)
			(layer "F.Fab")
		)
		(pad "1" smd rect
			(at 0 -3.1496 90)
			(size 2.413 2.286)
			(layers "F.Cu" "F.Mask" "F.Paste")
			(net "P12VU")
		)
		(pad "2" smd rect
			(at 0 3.1496 90)
			(size 2.413 2.286)
			(layers "F.Cu" "F.Mask" "F.Paste")
			(net "GND")
		)
		(zone
			(layer "F.Cu")
			(hatch none 0.5)
			(connect_pads
				(clearance 0)
			)
			(min_thickness 0.25)
			(keepout
				(tracks allowed)
				(vias not_allowed)
				(pads allowed)
				(copperpour not_allowed)
				(footprints allowed)
			)
			(placement
				(enabled no)
				(sheetname "")
			)
			(fill
				(thermal_gap 0.5)
				(thermal_bridge_width 0.5)
				(island_removal_mode 0)
			)
			(polygon
				(pts
					(xy 22.0599 -102.7303) (xy 19.1516 -102.7303) (xy 19.1516 -99.7077) (xy 22.0472 -99.7077) (xy 22.3774 -99.7077)
					(xy 22.3774 -102.7303)
				)
			)
		)
		(zone
			(layer "F.Cu")
			(hatch none 0.5)
			(connect_pads
				(clearance 0)
			)
			(min_thickness 0.25)
			(keepout
				(tracks allowed)
				(vias not_allowed)
				(pads allowed)
				(copperpour not_allowed)
				(footprints allowed)
			)
			(placement
				(enabled no)
				(sheetname "")
			)
			(fill
				(thermal_gap 0.5)
				(thermal_bridge_width 0.5)
				(island_removal_mode 0)
			)
			(polygon
				(pts
					(xy 28.3464 -99.7077) (xy 28.3464 -102.7303) (xy 25.4508 -102.7303) (xy 25.1206 -102.7303) (xy 25.1206 -99.7077)
					(xy 25.4508 -99.7077)
				)
			)
		)
	)
	(footprint ""
		(layer "F.Cu")
		(at 5.4102 -431.5968 90)
		(property "Reference" "R127"
			(at 0 0 90)
			(layer "F.SilkS")
			(hide yes)
			(effects
				(font
					(size 1.27 1.27)
				)
			)
		)
		(property "Value" "1K8R6J-GP"
			(at -0.0508 -4.8514 90)
			(unlocked yes)
			(layer "F.Fab")
			(hide yes)
			(effects
				(font
					(size 1.016 1.016)
					(thickness 0.1524)
				)
			)
		)
		(property "Device Type" "R1206H28"
			(at 0 -6.3754 90)
			(unlocked yes)
			(layer "F.Fab")
			(hide yes)
			(effects
				(font
					(size 1.016 1.016)
					(thickness 0.1524)
				)
			)
		)
		(duplicate_pad_numbers_are_jumpers no)
		(fp_line
			(start 1.016 -2.2352)
			(end 1.016 2.2352)
			(stroke
				(width 0.1524)
				(type default)
			)
			(layer "F.SilkS")
		)
		(fp_line
			(start -1.016 -2.2352)
			(end 1.016 -2.2352)
			(stroke
				(width 0.1524)
				(type default)
			)
			(layer "F.SilkS")
		)
		(fp_line
			(start 1.016 2.2352)
			(end -1.016 2.2352)
			(stroke
				(width 0.1524)
				(type default)
			)
			(layer "F.SilkS")
		)
		(fp_line
			(start -1.016 2.2352)
			(end -1.016 -2.2352)
			(stroke
				(width 0.1524)
				(type default)
			)
			(layer "F.SilkS")
		)
		(fp_rect
			(start -1.0922 2.3114)
			(end 1.0922 -2.3114)
			(stroke
				(width 0)
				(type default)
			)
			(fill no)
			(layer "F.CrtYd")
		)
		(fp_poly
			(pts
				(xy -1.0922 -2.3114) (xy 1.0922 -2.3114) (xy 1.0922 2.3114) (xy -1.0922 2.3114)
			)
			(stroke
				(width 0)
				(type default)
			)
			(fill no)
			(layer "F.Fab")
		)
		(pad "1" smd rect
			(at 0 -1.397 90)
			(size 1.651 1.27)
			(layers "F.Cu" "F.Mask" "F.Paste")
			(net "P12V")
		)
		(pad "2" smd rect
			(at 0 1.397 90)
			(size 1.651 1.27)
			(layers "F.Cu" "F.Mask" "F.Paste")
			(net "LED_DR_LED0_BLUE")
		)
	)
	(footprint ""
		(layer "F.Cu")
		(at 25.146 -248.412 180)
		(property "Reference" "PR55"
			(at 0 0 180)
			(layer "F.SilkS")
			(hide yes)
			(effects
				(font
					(size 1.27 1.27)
				)
			)
		)
		(property "Value" "100KR2F-L1-GP"
			(at 0.064008 -3.993896 180)
			(unlocked yes)
			(layer "F.Fab")
			(hide yes)
			(effects
				(font
					(size 1.016 1.016)
					(thickness 0.1524)
				)
			)
		)
		(property "Device Type" "R402H16"
			(at 0.064008 -5.517896 180)
			(unlocked yes)
			(layer "F.Fab")
			(hide yes)
			(effects
				(font
					(size 1.016 1.016)
					(thickness 0.1524)
				)
			)
		)
		(duplicate_pad_numbers_are_jumpers no)
		(fp_line
			(start 0.508 -0.9398)
			(end -0.508 -0.9398)
			(stroke
				(width 0.1524)
				(type default)
			)
			(layer "F.SilkS")
		)
		(fp_line
			(start -0.508 -0.9398)
			(end -0.508 0.9398)
			(stroke
				(width 0.1524)
				(type default)
			)
			(layer "F.SilkS")
		)
		(fp_rect
			(start -0.508 0.9398)
			(end 0.508 -0.9398)
			(stroke
				(width 0)
				(type default)
			)
			(fill no)
			(layer "F.CrtYd")
		)
		(fp_rect
			(start -0.508 0.9398)
			(end 0.508 -0.9398)
			(stroke
				(width 0)
				(type default)
			)
			(fill no)
			(layer "F.Fab")
		)
		(pad "1" smd custom
			(at 0 -0.4445 180)
			(size 0.1397 0.1397)
			(layers "F.Cu" "F.Mask" "F.Paste")
			(net "P3V3_LX_REV")
			(options
				(clearance outline)
				(anchor circle)
			)
			(primitives
				(gr_poly
					(pts
						(arc
							(start -0.1778 -0.2794)
							(mid -0.249642 -0.249642)
							(end -0.2794 -0.1778)
						)
						(arc
							(start -0.2794 0.1778)
							(mid -0.249642 0.249642)
							(end -0.1778 0.2794)
						)
						(arc
							(start 0.1778 0.2794)
							(mid 0.249642 0.249642)
							(end 0.2794 0.1778)
						)
						(arc
							(start 0.2794 -0.1778)
							(mid 0.249642 -0.249642)
							(end 0.1778 -0.2794)
						)
					)
					(width 0)
					(fill yes)
				)
			)
		)
		(pad "2" smd custom
			(at 0 0.4445 180)
			(size 0.1397 0.1397)
			(layers "F.Cu" "F.Mask" "F.Paste")
			(net "P3V3_FB")
			(options
				(clearance outline)
				(anchor circle)
			)
			(primitives
				(gr_poly
					(pts
						(arc
							(start -0.1778 -0.2794)
							(mid -0.249642 -0.249642)
							(end -0.2794 -0.1778)
						)
						(arc
							(start -0.2794 0.1778)
							(mid -0.249642 0.249642)
							(end -0.1778 0.2794)
						)
						(arc
							(start 0.1778 0.2794)
							(mid 0.249642 0.249642)
							(end 0.2794 0.1778)
						)
						(arc
							(start 0.2794 -0.1778)
							(mid 0.249642 -0.249642)
							(end 0.1778 -0.2794)
						)
					)
					(width 0)
					(fill yes)
				)
			)
		)
	)
	(footprint ""
		(layer "F.Cu")
		(at 37.4904 -252.6284)
		(property "Reference" "TP26"
			(at 0 0 0)
			(layer "F.SilkS")
			(hide yes)
			(effects
				(font
					(size 1.27 1.27)
				)
			)
		)
		(property "Value" "TPAD32-GP"
			(at 0 -3.166364 0)
			(unlocked yes)
			(layer "F.Fab")
			(hide yes)
			(effects
				(font
					(size 1.016 1.016)
					(thickness 0.1524)
				)
			)
		)
		(property "Device Type" "TPAD32"
			(at 0 -4.690618 0)
			(unlocked yes)
			(layer "F.Fab")
			(hide yes)
			(effects
				(font
					(size 1.016 1.016)
					(thickness 0.1524)
				)
			)
		)
		(duplicate_pad_numbers_are_jumpers no)
		(fp_poly
			(pts
				(arc
					(start 0.7112 0)
					(mid -0.7112 0)
					(end 0.7112 0)
				)
			)
			(stroke
				(width 0)
				(type default)
			)
			(fill no)
			(layer "F.CrtYd")
		)
		(fp_poly
			(pts
				(arc
					(start 0.7112 0)
					(mid -0.7112 0)
					(end 0.7112 0)
				)
			)
			(stroke
				(width 0)
				(type default)
			)
			(fill no)
			(layer "F.Fab")
		)
		(pad "1" smd circle
			(at 0 0)
			(size 0.8128 0.8128)
			(layers "F.Cu" "F.Mask" "F.Paste")
			(net "LED_DR_LED7_RESERVE")
		)
	)
	(footprint ""
		(layer "F.Cu")
		(at 20.675092 -288.278062 180)
		(property "Reference" "R99"
			(at 0 0 180)
			(layer "F.SilkS")
			(hide yes)
			(effects
				(font
					(size 1.27 1.27)
				)
			)
		)
		(property "Value" "27KR3F-GP"
			(at -0.0254 -2.5146 180)
			(unlocked yes)
			(layer "F.Fab")
			(hide yes)
			(effects
				(font
					(size 1.016 1.016)
					(thickness 0.1524)
				)
			)
		)
		(property "Device Type" "R603H22"
			(at -0.0254 -4.0386 180)
			(unlocked yes)
			(layer "F.Fab")
			(hide yes)
			(effects
				(font
					(size 1.016 1.016)
					(thickness 0.1524)
				)
			)
		)
		(duplicate_pad_numbers_are_jumpers no)
		(fp_line
			(start 0.2032 0)
			(end 0.4826 0)
			(stroke
				(width 0.2032)
				(type default)
			)
			(layer "F.SilkS")
		)
		(fp_line
			(start -0.4826 0)
			(end -0.2032 0)
			(stroke
				(width 0.2032)
				(type default)
			)
			(layer "F.SilkS")
		)
		(fp_rect
			(start -0.5842 1.3335)
			(end 0.5842 -1.3335)
			(stroke
				(width 0)
				(type default)
			)
			(fill no)
			(layer "F.CrtYd")
		)
		(fp_rect
			(start -0.5842 1.3335)
			(end 0.5842 -1.3335)
			(stroke
				(width 0)
				(type default)
			)
			(fill no)
			(layer "F.Fab")
		)
		(pad "1" smd custom
			(at 0 -0.762 180)
			(size 0.2159 0.2159)
			(layers "F.Cu" "F.Mask" "F.Paste")
			(net "FAN_TACH4")
			(options
				(clearance outline)
				(anchor circle)
			)
			(primitives
				(gr_poly
					(pts
						(arc
							(start -0.3302 -0.4318)
							(mid -0.402042 -0.402042)
							(end -0.4318 -0.3302)
						)
						(arc
							(start -0.4318 0.3302)
							(mid -0.402042 0.402042)
							(end -0.3302 0.4318)
						)
						(arc
							(start 0.3302 0.4318)
							(mid 0.402042 0.402042)
							(end 0.4318 0.3302)
						)
						(arc
							(start 0.4318 -0.3302)
							(mid 0.402042 -0.402042)
							(end 0.3302 -0.4318)
						)
					)
					(width 0)
					(fill yes)
				)
			)
		)
		(pad "2" smd custom
			(at 0 0.762 180)
			(size 0.2159 0.2159)
			(layers "F.Cu" "F.Mask" "F.Paste")
			(net "FANIN_4")
			(options
				(clearance outline)
				(anchor circle)
			)
			(primitives
				(gr_poly
					(pts
						(arc
							(start -0.3302 -0.4318)
							(mid -0.402042 -0.402042)
							(end -0.4318 -0.3302)
						)
						(arc
							(start -0.4318 0.3302)
							(mid -0.402042 0.402042)
							(end -0.3302 0.4318)
						)
						(arc
							(start 0.3302 0.4318)
							(mid 0.402042 0.402042)
							(end 0.4318 0.3302)
						)
						(arc
							(start 0.4318 -0.3302)
							(mid 0.402042 -0.402042)
							(end 0.3302 -0.4318)
						)
					)
					(width 0)
					(fill yes)
				)
			)
		)
	)
	(footprint ""
		(layer "F.Cu")
		(at 26.1366 -210.844384 180)
		(property "Reference" "R136"
			(at 0 0 180)
			(layer "F.SilkS")
			(hide yes)
			(effects
				(font
					(size 1.27 1.27)
				)
			)
		)
		(property "Value" "0R2J-2-GP"
			(at 0.064008 -3.993896 180)
			(unlocked yes)
			(layer "F.Fab")
			(hide yes)
			(effects
				(font
					(size 1.016 1.016)
					(thickness 0.1524)
				)
			)
		)
		(property "Device Type" "R402H16"
			(at 0.064008 -5.517896 180)
			(unlocked yes)
			(layer "F.Fab")
			(hide yes)
			(effects
				(font
					(size 1.016 1.016)
					(thickness 0.1524)
				)
			)
		)
		(duplicate_pad_numbers_are_jumpers no)
		(fp_line
			(start 0.508 -0.9398)
			(end -0.508 -0.9398)
			(stroke
				(width 0.1524)
				(type default)
			)
			(layer "F.SilkS")
		)
		(fp_line
			(start -0.508 -0.9398)
			(end -0.508 0.9398)
			(stroke
				(width 0.1524)
				(type default)
			)
			(layer "F.SilkS")
		)
		(fp_rect
			(start -0.508 0.9398)
			(end 0.508 -0.9398)
			(stroke
				(width 0)
				(type default)
			)
			(fill no)
			(layer "F.CrtYd")
		)
		(fp_rect
			(start -0.508 0.9398)
			(end 0.508 -0.9398)
			(stroke
				(width 0)
				(type default)
			)
			(fill no)
			(layer "F.Fab")
		)
		(pad "1" smd custom
			(at 0 -0.4445 180)
			(size 0.1397 0.1397)
			(layers "F.Cu" "F.Mask" "F.Paste")
			(net "PWM_OUT_FAN6_NET")
			(options
				(clearance outline)
				(anchor circle)
			)
			(primitives
				(gr_poly
					(pts
						(arc
							(start -0.1778 -0.2794)
							(mid -0.249642 -0.249642)
							(end -0.2794 -0.1778)
						)
						(arc
							(start -0.2794 0.1778)
							(mid -0.249642 0.249642)
							(end -0.1778 0.2794)
						)
						(arc
							(start 0.1778 0.2794)
							(mid 0.249642 0.249642)
							(end 0.2794 0.1778)
						)
						(arc
							(start 0.2794 -0.1778)
							(mid 0.249642 -0.249642)
							(end 0.1778 -0.2794)
						)
					)
					(width 0)
					(fill yes)
				)
			)
		)
		(pad "2" smd custom
			(at 0 0.4445 180)
			(size 0.1397 0.1397)
			(layers "F.Cu" "F.Mask" "F.Paste")
			(net "PWM_OUT_FAN6")
			(options
				(clearance outline)
				(anchor circle)
			)
			(primitives
				(gr_poly
					(pts
						(arc
							(start -0.1778 -0.2794)
							(mid -0.249642 -0.249642)
							(end -0.2794 -0.1778)
						)
						(arc
							(start -0.2794 0.1778)
							(mid -0.249642 0.249642)
							(end -0.1778 0.2794)
						)
						(arc
							(start 0.1778 0.2794)
							(mid 0.249642 0.249642)
							(end 0.2794 0.1778)
						)
						(arc
							(start 0.2794 -0.1778)
							(mid 0.249642 -0.249642)
							(end 0.1778 -0.2794)
						)
					)
					(width 0)
					(fill yes)
				)
			)
		)
	)
	(footprint ""
		(layer "F.Cu")
		(at 12.5984 -146.1008)
		(property "Reference" "R74"
			(at 0 0 0)
			(layer "F.SilkS")
			(hide yes)
			(effects
				(font
					(size 1.27 1.27)
				)
			)
		)
		(property "Value" "10KR2F-2-GP"
			(at 0.064008 -3.993896 0)
			(unlocked yes)
			(layer "F.Fab")
			(hide yes)
			(effects
				(font
					(size 1.016 1.016)
					(thickness 0.1524)
				)
			)
		)
		(property "Device Type" "R402H16"
			(at 0.064008 -5.517896 0)
			(unlocked yes)
			(layer "F.Fab")
			(hide yes)
			(effects
				(font
					(size 1.016 1.016)
					(thickness 0.1524)
				)
			)
		)
		(duplicate_pad_numbers_are_jumpers no)
		(fp_line
			(start -0.508 -0.9398)
			(end -0.508 0.9398)
			(stroke
				(width 0.1524)
				(type default)
			)
			(layer "F.SilkS")
		)
		(fp_line
			(start 0.508 -0.9398)
			(end -0.508 -0.9398)
			(stroke
				(width 0.1524)
				(type default)
			)
			(layer "F.SilkS")
		)
		(fp_rect
			(start -0.508 0.9398)
			(end 0.508 -0.9398)
			(stroke
				(width 0)
				(type default)
			)
			(fill no)
			(layer "F.CrtYd")
		)
		(fp_rect
			(start -0.508 0.9398)
			(end 0.508 -0.9398)
			(stroke
				(width 0)
				(type default)
			)
			(fill no)
			(layer "F.Fab")
		)
		(pad "1" smd custom
			(at 0 -0.4445)
			(size 0.1397 0.1397)
			(layers "F.Cu" "F.Mask" "F.Paste")
			(net "FANIN_10")
			(options
				(clearance outline)
				(anchor circle)
			)
			(primitives
				(gr_poly
					(pts
						(arc
							(start -0.1778 -0.2794)
							(mid -0.249642 -0.249642)
							(end -0.2794 -0.1778)
						)
						(arc
							(start -0.2794 0.1778)
							(mid -0.249642 0.249642)
							(end -0.1778 0.2794)
						)
						(arc
							(start 0.1778 0.2794)
							(mid 0.249642 0.249642)
							(end 0.2794 0.1778)
						)
						(arc
							(start 0.2794 -0.1778)
							(mid 0.249642 -0.249642)
							(end 0.1778 -0.2794)
						)
					)
					(width 0)
					(fill yes)
				)
			)
		)
		(pad "2" smd custom
			(at 0 0.4445)
			(size 0.1397 0.1397)
			(layers "F.Cu" "F.Mask" "F.Paste")
			(net "GND")
			(options
				(clearance outline)
				(anchor circle)
			)
			(primitives
				(gr_poly
					(pts
						(arc
							(start -0.1778 -0.2794)
							(mid -0.249642 -0.249642)
							(end -0.2794 -0.1778)
						)
						(arc
							(start -0.2794 0.1778)
							(mid -0.249642 0.249642)
							(end -0.1778 0.2794)
						)
						(arc
							(start 0.1778 0.2794)
							(mid 0.249642 0.249642)
							(end 0.2794 0.1778)
						)
						(arc
							(start 0.2794 -0.1778)
							(mid 0.249642 -0.249642)
							(end 0.1778 -0.2794)
						)
					)
					(width 0)
					(fill yes)
				)
			)
		)
	)
	(footprint ""
		(layer "F.Cu")
		(at 36.1188 -370.4336 90)
		(property "Reference" "PR8"
			(at 0 0 90)
			(layer "F.SilkS")
			(hide yes)
			(effects
				(font
					(size 1.27 1.27)
				)
			)
		)
		(property "Value" "11KR2F-L-GP"
			(at 0.064008 -3.993896 90)
			(unlocked yes)
			(layer "F.Fab")
			(hide yes)
			(effects
				(font
					(size 1.016 1.016)
					(thickness 0.1524)
				)
			)
		)
		(property "Device Type" "R402H16"
			(at 0.064008 -5.517896 90)
			(unlocked yes)
			(layer "F.Fab")
			(hide yes)
			(effects
				(font
					(size 1.016 1.016)
					(thickness 0.1524)
				)
			)
		)
		(duplicate_pad_numbers_are_jumpers no)
		(fp_line
			(start 0.508 -0.9398)
			(end -0.508 -0.9398)
			(stroke
				(width 0.1524)
				(type default)
			)
			(layer "F.SilkS")
		)
		(fp_line
			(start -0.508 -0.9398)
			(end -0.508 0.9398)
			(stroke
				(width 0.1524)
				(type default)
			)
			(layer "F.SilkS")
		)
		(fp_rect
			(start -0.508 0.9398)
			(end 0.508 -0.9398)
			(stroke
				(width 0)
				(type default)
			)
			(fill no)
			(layer "F.CrtYd")
		)
		(fp_rect
			(start -0.508 0.9398)
			(end 0.508 -0.9398)
			(stroke
				(width 0)
				(type default)
			)
			(fill no)
			(layer "F.Fab")
		)
		(pad "1" smd custom
			(at 0 -0.4445 90)
			(size 0.1397 0.1397)
			(layers "F.Cu" "F.Mask" "F.Paste")
			(net "ADM1276_FLB")
			(options
				(clearance outline)
				(anchor circle)
			)
			(primitives
				(gr_poly
					(pts
						(arc
							(start -0.1778 -0.2794)
							(mid -0.249642 -0.249642)
							(end -0.2794 -0.1778)
						)
						(arc
							(start -0.2794 0.1778)
							(mid -0.249642 0.249642)
							(end -0.1778 0.2794)
						)
						(arc
							(start 0.1778 0.2794)
							(mid 0.249642 0.249642)
							(end 0.2794 0.1778)
						)
						(arc
							(start 0.2794 -0.1778)
							(mid 0.249642 -0.249642)
							(end 0.1778 -0.2794)
						)
					)
					(width 0)
					(fill yes)
				)
			)
		)
		(pad "2" smd custom
			(at 0 0.4445 90)
			(size 0.1397 0.1397)
			(layers "F.Cu" "F.Mask" "F.Paste")
			(net "GND")
			(options
				(clearance outline)
				(anchor circle)
			)
			(primitives
				(gr_poly
					(pts
						(arc
							(start -0.1778 -0.2794)
							(mid -0.249642 -0.249642)
							(end -0.2794 -0.1778)
						)
						(arc
							(start -0.2794 0.1778)
							(mid -0.249642 0.249642)
							(end -0.1778 0.2794)
						)
						(arc
							(start 0.1778 0.2794)
							(mid 0.249642 0.249642)
							(end 0.2794 0.1778)
						)
						(arc
							(start 0.2794 -0.1778)
							(mid 0.249642 -0.249642)
							(end 0.1778 -0.2794)
						)
					)
					(width 0)
					(fill yes)
				)
			)
		)
	)
	(footprint ""
		(layer "F.Cu")
		(at 33.147 -376.428 90)
		(property "Reference" "PR14"
			(at 0 0 90)
			(layer "F.SilkS")
			(hide yes)
			(effects
				(font
					(size 1.27 1.27)
				)
			)
		)
		(property "Value" "0R2J-2-GP"
			(at 0.064008 -3.993896 90)
			(unlocked yes)
			(layer "F.Fab")
			(hide yes)
			(effects
				(font
					(size 1.016 1.016)
					(thickness 0.1524)
				)
			)
		)
		(property "Device Type" "R402H16"
			(at 0.064008 -5.517896 90)
			(unlocked yes)
			(layer "F.Fab")
			(hide yes)
			(effects
				(font
					(size 1.016 1.016)
					(thickness 0.1524)
				)
			)
		)
		(duplicate_pad_numbers_are_jumpers no)
		(fp_line
			(start 0.508 -0.9398)
			(end -0.508 -0.9398)
			(stroke
				(width 0.1524)
				(type default)
			)
			(layer "F.SilkS")
		)
		(fp_line
			(start -0.508 -0.9398)
			(end -0.508 0.9398)
			(stroke
				(width 0.1524)
				(type default)
			)
			(layer "F.SilkS")
		)
		(fp_rect
			(start -0.508 0.9398)
			(end 0.508 -0.9398)
			(stroke
				(width 0)
				(type default)
			)
			(fill no)
			(layer "F.CrtYd")
		)
		(fp_rect
			(start -0.508 0.9398)
			(end 0.508 -0.9398)
			(stroke
				(width 0)
				(type default)
			)
			(fill no)
			(layer "F.Fab")
		)
		(pad "1" smd custom
			(at 0 -0.4445 90)
			(size 0.1397 0.1397)
			(layers "F.Cu" "F.Mask" "F.Paste")
			(net "ADM1276_GATE")
			(options
				(clearance outline)
				(anchor circle)
			)
			(primitives
				(gr_poly
					(pts
						(arc
							(start -0.1778 -0.2794)
							(mid -0.249642 -0.249642)
							(end -0.2794 -0.1778)
						)
						(arc
							(start -0.2794 0.1778)
							(mid -0.249642 0.249642)
							(end -0.1778 0.2794)
						)
						(arc
							(start 0.1778 0.2794)
							(mid 0.249642 0.249642)
							(end 0.2794 0.1778)
						)
						(arc
							(start 0.2794 -0.1778)
							(mid 0.249642 -0.249642)
							(end 0.1778 -0.2794)
						)
					)
					(width 0)
					(fill yes)
				)
			)
		)
		(pad "2" smd custom
			(at 0 0.4445 90)
			(size 0.1397 0.1397)
			(layers "F.Cu" "F.Mask" "F.Paste")
			(net "ADM1276_GATE_RC")
			(options
				(clearance outline)
				(anchor circle)
			)
			(primitives
				(gr_poly
					(pts
						(arc
							(start -0.1778 -0.2794)
							(mid -0.249642 -0.249642)
							(end -0.2794 -0.1778)
						)
						(arc
							(start -0.2794 0.1778)
							(mid -0.249642 0.249642)
							(end -0.1778 0.2794)
						)
						(arc
							(start 0.1778 0.2794)
							(mid 0.249642 0.249642)
							(end 0.2794 0.1778)
						)
						(arc
							(start 0.2794 -0.1778)
							(mid 0.249642 -0.249642)
							(end 0.1778 -0.2794)
						)
					)
					(width 0)
					(fill yes)
				)
			)
		)
	)
	(footprint ""
		(layer "F.Cu")
		(at 29.9212 -247.4214)
		(property "Reference" "U5"
			(at 0 0 0)
			(layer "F.SilkS")
			(hide yes)
			(effects
				(font
					(size 1.27 1.27)
				)
			)
		)
		(property "Value" "24LC64T-I-GP"
			(at 0 -12.1412 0)
			(unlocked yes)
			(layer "F.Fab")
			(hide yes)
			(effects
				(font
					(size 1.016 1.016)
					(thickness 0.1524)
				)
			)
		)
		(property "Device Type" "SSOIC8-1H44"
			(at 0 -13.6652 0)
			(unlocked yes)
			(layer "F.Fab")
			(hide yes)
			(effects
				(font
					(size 1.016 1.016)
					(thickness 0.1524)
				)
			)
		)
		(duplicate_pad_numbers_are_jumpers no)
		(fp_line
			(start -1.778 -1.778)
			(end -1.778 2.667)
			(stroke
				(width 0.2032)
				(type default)
			)
			(layer "F.SilkS")
		)
		(fp_line
			(start -1.778 -1.778)
			(end 1.397 -1.778)
			(stroke
				(width 0.2032)
				(type default)
			)
			(layer "F.SilkS")
		)
		(fp_line
			(start -1.778 1.778)
			(end -1.778 3.81)
			(stroke
				(width 0.508)
				(type default)
			)
			(layer "F.SilkS")
		)
		(fp_line
			(start -1.143 0)
			(end -1.778 -0.635)
			(stroke
				(width 0.2032)
				(type default)
			)
			(layer "F.SilkS")
		)
		(fp_line
			(start -1.143 0)
			(end -1.778 0.635)
			(stroke
				(width 0.2032)
				(type default)
			)
			(layer "F.SilkS")
		)
		(fp_line
			(start 1.397 -1.778)
			(end 1.397 1.778)
			(stroke
				(width 0.2032)
				(type default)
			)
			(layer "F.SilkS")
		)
		(fp_line
			(start 1.397 1.778)
			(end -1.778 1.778)
			(stroke
				(width 0.2032)
				(type default)
			)
			(layer "F.SilkS")
		)
		(fp_poly
			(pts
				(xy -2.032 3.81) (xy 2.032 3.81) (xy 2.032 -3.81) (xy -2.032 -3.81)
			)
			(stroke
				(width 0)
				(type default)
			)
			(fill no)
			(layer "F.CrtYd")
		)
		(fp_poly
			(pts
				(xy -2.032 -3.81) (xy 2.032 -3.81) (xy 2.032 3.81) (xy -2.032 3.81)
			)
			(stroke
				(width 0)
				(type default)
			)
			(fill no)
			(layer "F.Fab")
		)
		(pad "1" smd rect
			(at -0.97536 2.8194)
			(size 0.3556 1.524)
			(layers "F.Cu" "F.Mask" "F.Paste")
			(net "FCB_EEPROM_A0")
		)
		(pad "2" smd rect
			(at -0.32512 2.8194)
			(size 0.3556 1.524)
			(layers "F.Cu" "F.Mask" "F.Paste")
			(net "FCB_EEPROM_A1")
		)
		(pad "3" smd rect
			(at 0.32512 2.8194)
			(size 0.3556 1.524)
			(layers "F.Cu" "F.Mask" "F.Paste")
			(net "FCB_EEPROM_A2")
		)
		(pad "4" smd rect
			(at 0.97536 2.8194)
			(size 0.3556 1.524)
			(layers "F.Cu" "F.Mask" "F.Paste")
			(net "GND")
		)
		(pad "5" smd rect
			(at 0.97536 -2.8194)
			(size 0.3556 1.524)
			(layers "F.Cu" "F.Mask" "F.Paste")
			(net "I2C_C_SDA_EEPROM")
		)
		(pad "6" smd rect
			(at 0.32512 -2.8194)
			(size 0.3556 1.524)
			(layers "F.Cu" "F.Mask" "F.Paste")
			(net "I2C_C_SCL_EEPROM")
		)
		(pad "7" smd rect
			(at -0.32512 -2.8194)
			(size 0.3556 1.524)
			(layers "F.Cu" "F.Mask" "F.Paste")
			(net "EEPROM_WP")
		)
		(pad "8" smd rect
			(at -0.97536 -2.8194)
			(size 0.3556 1.524)
			(layers "F.Cu" "F.Mask" "F.Paste")
			(net "P3V3")
		)
	)
	(footprint ""
		(layer "F.Cu")
		(at 33.71469 -150.730966 180)
		(property "Reference" "TP9"
			(at 0 0 180)
			(layer "F.SilkS")
			(hide yes)
			(effects
				(font
					(size 1.27 1.27)
				)
			)
		)
		(property "Value" "TPAD32-GP"
			(at 0 -3.166364 180)
			(unlocked yes)
			(layer "F.Fab")
			(hide yes)
			(effects
				(font
					(size 1.016 1.016)
					(thickness 0.1524)
				)
			)
		)
		(property "Device Type" "TPAD32"
			(at 0 -4.690618 180)
			(unlocked yes)
			(layer "F.Fab")
			(hide yes)
			(effects
				(font
					(size 1.016 1.016)
					(thickness 0.1524)
				)
			)
		)
		(duplicate_pad_numbers_are_jumpers no)
		(fp_poly
			(pts
				(arc
					(start 0.7112 0)
					(mid -0.7112 0)
					(end 0.7112 0)
				)
			)
			(stroke
				(width 0)
				(type default)
			)
			(fill no)
			(layer "F.CrtYd")
		)
		(fp_poly
			(pts
				(arc
					(start 0.7112 0)
					(mid -0.7112 0)
					(end 0.7112 0)
				)
			)
			(stroke
				(width 0)
				(type default)
			)
			(fill no)
			(layer "F.Fab")
		)
		(pad "1" smd circle
			(at 0 0 180)
			(size 0.8128 0.8128)
			(layers "F.Cu" "F.Mask" "F.Paste")
			(net "NCT7904_VSEN10")
		)
	)
	(footprint ""
		(layer "F.Cu")
		(at 21.844 -202.7936 -90)
		(property "Reference" "TC15"
			(at 0 0 270)
			(layer "F.SilkS")
			(hide yes)
			(effects
				(font
					(size 1.27 1.27)
				)
			)
		)
		(property "Value" "ST15U25VDM-1-GP"
			(at 0 -9.6012 270)
			(unlocked yes)
			(layer "F.Fab")
			(hide yes)
			(effects
				(font
					(size 1.016 1.016)
					(thickness 0.1524)
				)
			)
		)
		(property "Device Type" "CT7343H79"
			(at 0 -11.1252 270)
			(unlocked yes)
			(layer "F.Fab")
			(hide yes)
			(effects
				(font
					(size 1.016 1.016)
					(thickness 0.1524)
				)
			)
		)
		(duplicate_pad_numbers_are_jumpers no)
		(fp_line
			(start -2.286 4.8768)
			(end -2.286 2.032)
			(stroke
				(width 0.1524)
				(type default)
			)
			(layer "F.SilkS")
		)
		(fp_line
			(start 2.286 4.8768)
			(end -2.286 4.8768)
			(stroke
				(width 0.1524)
				(type default)
			)
			(layer "F.SilkS")
		)
		(fp_line
			(start 2.286 2.032)
			(end 2.286 4.8768)
			(stroke
				(width 0.1524)
				(type default)
			)
			(layer "F.SilkS")
		)
		(fp_line
			(start 2.286 -2.032)
			(end 2.286 -4.8768)
			(stroke
				(width 0.1524)
				(type default)
			)
			(layer "F.SilkS")
		)
		(fp_line
			(start 2.1082 -4.699)
			(end -2.1082 -4.699)
			(stroke
				(width 0.508)
				(type default)
			)
			(layer "F.SilkS")
		)
		(fp_line
			(start -2.286 -4.8768)
			(end -2.286 -2.032)
			(stroke
				(width 0.1524)
				(type default)
			)
			(layer "F.SilkS")
		)
		(fp_line
			(start 2.286 -4.8768)
			(end -2.286 -4.8768)
			(stroke
				(width 0.1524)
				(type default)
			)
			(layer "F.SilkS")
		)
		(fp_rect
			(start -2.1463 3.6449)
			(end 2.1463 -3.6449)
			(stroke
				(width 0)
				(type default)
			)
			(fill no)
			(layer "F.CrtYd")
		)
		(fp_poly
			(pts
				(xy -2.54 4.953) (xy -2.54 4.2926) (xy -3.81 4.2926) (xy -3.81 -4.2926) (xy -2.54 -4.2926) (xy -2.54 -4.953)
				(xy 2.54 -4.953) (xy 2.54 -4.2926) (xy 3.81 -4.2926) (xy 3.81 -1.6256) (xy 2.1463 -1.6256) (xy 2.1463 -3.6449)
				(xy -2.1463 -3.6449) (xy -2.1463 3.6449) (xy 2.1463 3.6449) (xy 2.1463 -1.6129) (xy 3.81 -1.6129)
				(xy 3.81 4.2926) (xy 2.54 4.2926) (xy 2.54 4.953)
			)
			(stroke
				(width 0)
				(type default)
			)
			(fill no)
			(layer "F.CrtYd")
		)
		(fp_rect
			(start -2.54 4.953)
			(end 2.54 -4.953)
			(stroke
				(width 0)
				(type default)
			)
			(fill no)
			(layer "F.Fab")
		)
		(fp_rect
			(start -3.81 4.2926)
			(end -2.54 -4.2926)
			(stroke
				(width 0)
				(type default)
			)
			(fill no)
			(layer "F.Fab")
		)
		(fp_rect
			(start 2.54 4.2926)
			(end 3.81 -4.2926)
			(stroke
				(width 0)
				(type default)
			)
			(fill no)
			(layer "F.Fab")
		)
		(pad "1" smd rect
			(at 0 -3.1496 270)
			(size 2.413 2.286)
			(layers "F.Cu" "F.Mask" "F.Paste")
			(net "P12V")
		)
		(pad "2" smd rect
			(at 0 3.1496 270)
			(size 2.413 2.286)
			(layers "F.Cu" "F.Mask" "F.Paste")
			(net "GND")
		)
		(zone
			(layer "F.Cu")
			(hatch none 0.5)
			(connect_pads
				(clearance 0)
			)
			(min_thickness 0.25)
			(keepout
				(tracks allowed)
				(vias not_allowed)
				(pads allowed)
				(copperpour not_allowed)
				(footprints allowed)
			)
			(placement
				(enabled no)
				(sheetname "")
			)
			(fill
				(thermal_gap 0.5)
				(thermal_bridge_width 0.5)
				(island_removal_mode 0)
			)
			(polygon
				(pts
					(xy 17.2466 -204.3049) (xy 17.2466 -201.2823) (xy 20.1422 -201.2823) (xy 20.4724 -201.2823) (xy 20.4724 -204.3049)
					(xy 20.1422 -204.3049)
				)
			)
		)
		(zone
			(layer "F.Cu")
			(hatch none 0.5)
			(connect_pads
				(clearance 0)
			)
			(min_thickness 0.25)
			(keepout
				(tracks allowed)
				(vias not_allowed)
				(pads allowed)
				(copperpour not_allowed)
				(footprints allowed)
			)
			(placement
				(enabled no)
				(sheetname "")
			)
			(fill
				(thermal_gap 0.5)
				(thermal_bridge_width 0.5)
				(island_removal_mode 0)
			)
			(polygon
				(pts
					(xy 23.5331 -201.2823) (xy 26.4414 -201.2823) (xy 26.4414 -204.3049) (xy 23.5458 -204.3049) (xy 23.2156 -204.3049)
					(xy 23.2156 -201.2823)
				)
			)
		)
	)
	(footprint ""
		(layer "F.Cu")
		(at 32.749998 -451.820026)
		(property "Reference" "CN8"
			(at 0 0 0)
			(layer "F.SilkS")
			(hide yes)
			(effects
				(font
					(size 1.27 1.27)
				)
			)
		)
		(property "Value" "JWT-CON3-S11-GP"
			(at 5.715 1.1684 0)
			(unlocked yes)
			(layer "F.Fab")
			(hide yes)
			(effects
				(font
					(size 1.016 1.016)
					(thickness 0.1524)
				)
			)
		)
		(property "Device Type" "A2541WV0-1QX3PA-6T"
			(at 5.715 -0.3556 0)
			(unlocked yes)
			(layer "F.Fab")
			(hide yes)
			(effects
				(font
					(size 1.016 1.016)
					(thickness 0.1524)
				)
			)
		)
		(duplicate_pad_numbers_are_jumpers no)
		(fp_line
			(start -4.190746 -1.651)
			(end -2.920746 -1.651)
			(stroke
				(width 0.4064)
				(type default)
			)
			(layer "F.SilkS")
		)
		(fp_line
			(start -4.190746 -0.381)
			(end -4.190746 -1.651)
			(stroke
				(width 0.4064)
				(type default)
			)
			(layer "F.SilkS")
		)
		(fp_line
			(start -4.064 -1.524)
			(end -4.064 1.524)
			(stroke
				(width 0.1524)
				(type default)
			)
			(layer "F.SilkS")
		)
		(fp_line
			(start -4.064 1.524)
			(end 4.064 1.524)
			(stroke
				(width 0.1524)
				(type default)
			)
			(layer "F.SilkS")
		)
		(fp_line
			(start 4.064 -1.524)
			(end -4.064 -1.524)
			(stroke
				(width 0.1524)
				(type default)
			)
			(layer "F.SilkS")
		)
		(fp_line
			(start 4.064 1.524)
			(end 4.064 -1.524)
			(stroke
				(width 0.1524)
				(type default)
			)
			(layer "F.SilkS")
		)
		(fp_circle
			(center -2.54 0)
			(end -1.4732 0)
			(stroke
				(width 0.3048)
				(type default)
			)
			(fill no)
			(layer "F.SilkS")
		)
		(fp_circle
			(center 0 0)
			(end 1.0668 0)
			(stroke
				(width 0.3048)
				(type default)
			)
			(fill no)
			(layer "F.SilkS")
		)
		(fp_circle
			(center 2.54 0)
			(end 3.6068 0)
			(stroke
				(width 0.3048)
				(type default)
			)
			(fill no)
			(layer "F.SilkS")
		)
		(fp_rect
			(start -3.81 1.27)
			(end 3.81 -1.27)
			(stroke
				(width 0)
				(type default)
			)
			(fill no)
			(layer "F.CrtYd")
		)
		(fp_poly
			(pts
				(xy -4.318 1.778) (xy -4.318 -1.778) (xy 4.318 -1.778) (xy 4.318 -1.27) (xy -3.81 -1.27) (xy -3.81 1.27)
				(xy 3.81 1.27) (xy 3.81 -1.2573) (xy 4.318 -1.2573) (xy 4.318 1.778)
			)
			(stroke
				(width 0)
				(type default)
			)
			(fill no)
			(layer "F.CrtYd")
		)
		(fp_rect
			(start -4.318 1.778)
			(end 4.318 -1.778)
			(stroke
				(width 0)
				(type default)
			)
			(fill no)
			(layer "F.Fab")
		)
		(pad "1" thru_hole circle
			(at -2.54 0)
			(size 1.4224 1.4224)
			(drill 1.016)
			(layers "*.Cu" "*.Mask")
			(remove_unused_layers no)
			(net "Net_4")
			(clearance 0.1524)
			(thermal_gap 0.1524)
		)
		(pad "2" thru_hole circle
			(at 0 0)
			(size 1.4224 1.4224)
			(drill 1.016)
			(layers "*.Cu" "*.Mask")
			(remove_unused_layers no)
			(net "Net_3")
			(clearance 0.1524)
			(thermal_gap 0.1524)
		)
		(pad "3" thru_hole circle
			(at 2.54 0)
			(size 1.4224 1.4224)
			(drill 1.016)
			(layers "*.Cu" "*.Mask")
			(remove_unused_layers no)
			(net "Net_2")
			(clearance 0.1524)
			(thermal_gap 0.1524)
		)
	)
	(footprint ""
		(layer "F.Cu")
		(at 26.035 -267.6398 90)
		(property "Reference" "C39"
			(at 0 0 90)
			(layer "F.SilkS")
			(hide yes)
			(effects
				(font
					(size 1.27 1.27)
				)
			)
		)
		(property "Value" "SCD1U50V3KX-GP"
			(at 0 -2.8194 90)
			(unlocked yes)
			(layer "F.Fab")
			(hide yes)
			(effects
				(font
					(size 1.016 1.016)
					(thickness 0.1524)
				)
			)
		)
		(property "Device Type" "C603H36"
			(at 0 -4.3434 90)
			(unlocked yes)
			(layer "F.Fab")
			(hide yes)
			(effects
				(font
					(size 1.016 1.016)
					(thickness 0.1524)
				)
			)
		)
		(duplicate_pad_numbers_are_jumpers no)
		(fp_line
			(start 0.508 0)
			(end -0.508 0)
			(stroke
				(width 0.2032)
				(type default)
			)
			(layer "F.SilkS")
		)
		(fp_rect
			(start -0.5842 1.3335)
			(end 0.5842 -1.3335)
			(stroke
				(width 0)
				(type default)
			)
			(fill no)
			(layer "F.CrtYd")
		)
		(fp_rect
			(start -0.5842 1.3335)
			(end 0.5842 -1.3335)
			(stroke
				(width 0)
				(type default)
			)
			(fill no)
			(layer "F.Fab")
		)
		(pad "1" smd custom
			(at 0 -0.762 90)
			(size 0.2159 0.2159)
			(layers "F.Cu" "F.Mask" "F.Paste")
			(net "P12V")
			(options
				(clearance outline)
				(anchor circle)
			)
			(primitives
				(gr_poly
					(pts
						(arc
							(start -0.3302 -0.4318)
							(mid -0.402042 -0.402042)
							(end -0.4318 -0.3302)
						)
						(arc
							(start -0.4318 0.3302)
							(mid -0.402042 0.402042)
							(end -0.3302 0.4318)
						)
						(arc
							(start 0.3302 0.4318)
							(mid 0.402042 0.402042)
							(end 0.4318 0.3302)
						)
						(arc
							(start 0.4318 -0.3302)
							(mid 0.402042 -0.402042)
							(end 0.3302 -0.4318)
						)
					)
					(width 0)
					(fill yes)
				)
			)
		)
		(pad "2" smd custom
			(at 0 0.762 90)
			(size 0.2159 0.2159)
			(layers "F.Cu" "F.Mask" "F.Paste")
			(net "GND")
			(options
				(clearance outline)
				(anchor circle)
			)
			(primitives
				(gr_poly
					(pts
						(arc
							(start -0.3302 -0.4318)
							(mid -0.402042 -0.402042)
							(end -0.4318 -0.3302)
						)
						(arc
							(start -0.4318 0.3302)
							(mid -0.402042 0.402042)
							(end -0.3302 0.4318)
						)
						(arc
							(start 0.3302 0.4318)
							(mid 0.402042 0.402042)
							(end 0.4318 0.3302)
						)
						(arc
							(start 0.4318 -0.3302)
							(mid 0.402042 -0.402042)
							(end 0.3302 -0.4318)
						)
					)
					(width 0)
					(fill yes)
				)
			)
		)
	)
	(footprint ""
		(layer "F.Cu")
		(at 23.876 -243.84 180)
		(property "Reference" "PR54"
			(at 0 0 180)
			(layer "F.SilkS")
			(hide yes)
			(effects
				(font
					(size 1.27 1.27)
				)
			)
		)
		(property "Value" "0R3J-0-U-GP"
			(at -0.0254 -2.5146 180)
			(unlocked yes)
			(layer "F.Fab")
			(hide yes)
			(effects
				(font
					(size 1.016 1.016)
					(thickness 0.1524)
				)
			)
		)
		(property "Device Type" "R603H22"
			(at -0.0254 -4.0386 180)
			(unlocked yes)
			(layer "F.Fab")
			(hide yes)
			(effects
				(font
					(size 1.016 1.016)
					(thickness 0.1524)
				)
			)
		)
		(duplicate_pad_numbers_are_jumpers no)
		(fp_line
			(start 0.2032 0)
			(end 0.4826 0)
			(stroke
				(width 0.2032)
				(type default)
			)
			(layer "F.SilkS")
		)
		(fp_line
			(start -0.4826 0)
			(end -0.2032 0)
			(stroke
				(width 0.2032)
				(type default)
			)
			(layer "F.SilkS")
		)
		(fp_rect
			(start -0.5842 1.3335)
			(end 0.5842 -1.3335)
			(stroke
				(width 0)
				(type default)
			)
			(fill no)
			(layer "F.CrtYd")
		)
		(fp_rect
			(start -0.5842 1.3335)
			(end 0.5842 -1.3335)
			(stroke
				(width 0)
				(type default)
			)
			(fill no)
			(layer "F.Fab")
		)
		(pad "1" smd custom
			(at 0 -0.762 180)
			(size 0.2159 0.2159)
			(layers "F.Cu" "F.Mask" "F.Paste")
			(net "P3V3_LX_COPPER")
			(options
				(clearance outline)
				(anchor circle)
			)
			(primitives
				(gr_poly
					(pts
						(arc
							(start -0.3302 -0.4318)
							(mid -0.402042 -0.402042)
							(end -0.4318 -0.3302)
						)
						(arc
							(start -0.4318 0.3302)
							(mid -0.402042 0.402042)
							(end -0.3302 0.4318)
						)
						(arc
							(start 0.3302 0.4318)
							(mid 0.402042 0.402042)
							(end 0.4318 0.3302)
						)
						(arc
							(start 0.4318 -0.3302)
							(mid 0.402042 -0.402042)
							(end 0.3302 -0.4318)
						)
					)
					(width 0)
					(fill yes)
				)
			)
		)
		(pad "2" smd custom
			(at 0 0.762 180)
			(size 0.2159 0.2159)
			(layers "F.Cu" "F.Mask" "F.Paste")
			(net "P3V3_LX_REV")
			(options
				(clearance outline)
				(anchor circle)
			)
			(primitives
				(gr_poly
					(pts
						(arc
							(start -0.3302 -0.4318)
							(mid -0.402042 -0.402042)
							(end -0.4318 -0.3302)
						)
						(arc
							(start -0.4318 0.3302)
							(mid -0.402042 0.402042)
							(end -0.3302 0.4318)
						)
						(arc
							(start 0.3302 0.4318)
							(mid 0.402042 0.402042)
							(end 0.4318 0.3302)
						)
						(arc
							(start 0.4318 -0.3302)
							(mid 0.402042 -0.402042)
							(end 0.3302 -0.4318)
						)
					)
					(width 0)
					(fill yes)
				)
			)
		)
	)
	(footprint ""
		(layer "F.Cu")
		(at 26.6954 -289.433)
		(property "Reference" "R178"
			(at 0 0 0)
			(layer "F.SilkS")
			(hide yes)
			(effects
				(font
					(size 1.27 1.27)
				)
			)
		)
		(property "Value" "0R1206-PAD-1-GP"
			(at 0 -5.0292 0)
			(unlocked yes)
			(layer "F.Fab")
			(hide yes)
			(effects
				(font
					(size 1.016 1.016)
					(thickness 0.1524)
				)
			)
		)
		(property "Device Type" "0R1206-PAD-1"
			(at 0 -6.5532 0)
			(unlocked yes)
			(layer "F.Fab")
			(hide yes)
			(effects
				(font
					(size 1.016 1.016)
					(thickness 0.1524)
				)
			)
		)
		(duplicate_pad_numbers_are_jumpers no)
		(fp_line
			(start -1.016 -2.2352)
			(end -1.016 2.2352)
			(stroke
				(width 0.1524)
				(type default)
			)
			(layer "F.SilkS")
		)
		(fp_line
			(start -1.016 2.2352)
			(end 1.016 2.2352)
			(stroke
				(width 0.1524)
				(type default)
			)
			(layer "F.SilkS")
		)
		(fp_line
			(start 1.016 -2.2352)
			(end -1.016 -2.2352)
			(stroke
				(width 0.1524)
				(type default)
			)
			(layer "F.SilkS")
		)
		(fp_line
			(start 1.016 2.2352)
			(end 1.016 -2.2352)
			(stroke
				(width 0.1524)
				(type default)
			)
			(layer "F.SilkS")
		)
		(fp_rect
			(start -1.0922 2.3114)
			(end 1.0922 -2.3114)
			(stroke
				(width 0)
				(type default)
			)
			(fill no)
			(layer "F.CrtYd")
		)
		(fp_poly
			(pts
				(xy -1.0922 -2.3114) (xy 1.0922 -2.3114) (xy 1.0922 2.3114) (xy -1.0922 2.3114)
			)
			(stroke
				(width 0)
				(type default)
			)
			(fill no)
			(layer "F.Fab")
		)
		(pad "1" smd rect
			(at 0 -1.397)
			(size 1.651 2.0574)
			(drill
				(offset 0 0.3937)
			)
			(layers "F.Cu" "F.Mask" "F.Paste")
			(net "P12V_FAN2")
		)
		(pad "2" smd rect
			(at 0 1.397)
			(size 1.651 2.0574)
			(drill
				(offset 0 -0.3937)
			)
			(layers "F.Cu" "F.Mask" "F.Paste")
			(net "P12V")
		)
	)
	(footprint ""
		(layer "F.Cu")
		(at 16.2052 -249.1994 180)
		(property "Reference" "PC40"
			(at 0 0 180)
			(layer "F.SilkS")
			(hide yes)
			(effects
				(font
					(size 1.27 1.27)
				)
			)
		)
		(property "Value" "SC4D7U50V6KX-L2-GP"
			(at 0 -6.8072 180)
			(unlocked yes)
			(layer "F.Fab")
			(hide yes)
			(effects
				(font
					(size 1.016 1.016)
					(thickness 0.1524)
				)
			)
		)
		(property "Device Type" "C1206H38"
			(at 0 -8.7122 180)
			(unlocked yes)
			(layer "F.Fab")
			(hide yes)
			(effects
				(font
					(size 1.016 1.016)
					(thickness 0.1524)
				)
			)
		)
		(duplicate_pad_numbers_are_jumpers no)
		(fp_line
			(start 1.016 2.2352)
			(end -1.016 2.2352)
			(stroke
				(width 0.1524)
				(type default)
			)
			(layer "F.SilkS")
		)
		(fp_line
			(start 1.016 0.8382)
			(end 1.016 2.2352)
			(stroke
				(width 0.1524)
				(type default)
			)
			(layer "F.SilkS")
		)
		(fp_line
			(start 1.016 -2.2352)
			(end 1.016 -0.8382)
			(stroke
				(width 0.1524)
				(type default)
			)
			(layer "F.SilkS")
		)
		(fp_line
			(start 1.016 -2.2352)
			(end -1.016 -2.2352)
			(stroke
				(width 0.1524)
				(type default)
			)
			(layer "F.SilkS")
		)
		(fp_line
			(start -1.016 2.2352)
			(end -1.016 0.8128)
			(stroke
				(width 0.1524)
				(type default)
			)
			(layer "F.SilkS")
		)
		(fp_line
			(start -1.016 -2.2352)
			(end -1.016 -0.8382)
			(stroke
				(width 0.1524)
				(type default)
			)
			(layer "F.SilkS")
		)
		(fp_rect
			(start -1.0922 2.3114)
			(end 1.0922 -2.3114)
			(stroke
				(width 0)
				(type default)
			)
			(fill no)
			(layer "F.CrtYd")
		)
		(fp_poly
			(pts
				(xy -1.0922 -2.3114) (xy 1.0922 -2.3114) (xy 1.0922 2.3114) (xy -1.0922 2.3114)
			)
			(stroke
				(width 0)
				(type default)
			)
			(fill no)
			(layer "F.Fab")
		)
		(pad "1" smd rect
			(at 0 -1.397 180)
			(size 1.651 1.27)
			(layers "F.Cu" "F.Mask" "F.Paste")
			(net "P3V3_IN")
		)
		(pad "2" smd rect
			(at 0 1.397 180)
			(size 1.651 1.27)
			(layers "F.Cu" "F.Mask" "F.Paste")
			(net "GND")
		)
	)
	(footprint ""
		(layer "F.Cu")
		(at 15.9258 -145.542 -90)
		(property "Reference" "C30"
			(at 0 0 270)
			(layer "F.SilkS")
			(hide yes)
			(effects
				(font
					(size 1.27 1.27)
				)
			)
		)
		(property "Value" "SCD1U16V2KX-3GP"
			(at 1.1811 -2.7051 270)
			(unlocked yes)
			(layer "F.Fab")
			(hide yes)
			(effects
				(font
					(size 1.016 1.016)
					(thickness 0.1524)
				)
			)
		)
		(property "Device Type" "C402H22"
			(at 1.1811 -4.2291 270)
			(unlocked yes)
			(layer "F.Fab")
			(hide yes)
			(effects
				(font
					(size 1.016 1.016)
					(thickness 0.1524)
				)
			)
		)
		(duplicate_pad_numbers_are_jumpers no)
		(fp_rect
			(start -0.4318 0.9525)
			(end 0.4318 -0.9525)
			(stroke
				(width 0)
				(type default)
			)
			(fill no)
			(layer "F.CrtYd")
		)
		(fp_rect
			(start -0.4318 0.9525)
			(end 0.4318 -0.9525)
			(stroke
				(width 0)
				(type default)
			)
			(fill no)
			(layer "F.Fab")
		)
		(pad "1" smd custom
			(at 0 -0.4445 270)
			(size 0.1524 0.1524)
			(layers "F.Cu" "F.Mask" "F.Paste")
			(net "FAN_TACH9")
			(options
				(clearance outline)
				(anchor circle)
			)
			(primitives
				(gr_poly
					(pts
						(arc
							(start 0.3048 -0.2032)
							(mid 0.275042 -0.275042)
							(end 0.2032 -0.3048)
						)
						(arc
							(start -0.2032 -0.3048)
							(mid -0.275042 -0.275042)
							(end -0.3048 -0.2032)
						)
						(arc
							(start -0.3048 0.2032)
							(mid -0.275042 0.275042)
							(end -0.2032 0.3048)
						)
						(arc
							(start 0.2032 0.3048)
							(mid 0.275042 0.275042)
							(end 0.3048 0.2032)
						)
					)
					(width 0)
					(fill yes)
				)
			)
		)
		(pad "2" smd custom
			(at 0 0.4445 270)
			(size 0.1524 0.1524)
			(layers "F.Cu" "F.Mask" "F.Paste")
			(net "GND")
			(options
				(clearance outline)
				(anchor circle)
			)
			(primitives
				(gr_poly
					(pts
						(arc
							(start 0.3048 -0.2032)
							(mid 0.275042 -0.275042)
							(end 0.2032 -0.3048)
						)
						(arc
							(start -0.2032 -0.3048)
							(mid -0.275042 -0.275042)
							(end -0.3048 -0.2032)
						)
						(arc
							(start -0.3048 0.2032)
							(mid -0.275042 0.275042)
							(end -0.2032 0.3048)
						)
						(arc
							(start 0.2032 0.3048)
							(mid 0.275042 0.275042)
							(end 0.3048 0.2032)
						)
					)
					(width 0)
					(fill yes)
				)
			)
		)
	)
	(footprint ""
		(layer "F.Cu")
		(at 43.18 -400.177)
		(property "Reference" "PQ3"
			(at 0 0 0)
			(layer "F.SilkS")
			(hide yes)
			(effects
				(font
					(size 1.27 1.27)
				)
			)
		)
		(property "Value" "PH0925CL-GP"
			(at -4.2799 -0.4572 0)
			(unlocked yes)
			(layer "F.Fab")
			(hide yes)
			(effects
				(font
					(size 1.016 1.016)
					(thickness 0.1524)
				)
			)
		)
		(property "Device Type" "LFPAK-5PH48-U"
			(at -4.2799 -1.9812 0)
			(unlocked yes)
			(layer "F.Fab")
			(hide yes)
			(effects
				(font
					(size 1.016 1.016)
					(thickness 0.1524)
				)
			)
		)
		(duplicate_pad_numbers_are_jumpers no)
		(fp_line
			(start -2.7559 -6.5532)
			(end -2.7559 1.0668)
			(stroke
				(width 0.1524)
				(type default)
			)
			(layer "F.SilkS")
		)
		(fp_line
			(start -2.7559 1.0668)
			(end 2.7559 1.0668)
			(stroke
				(width 0.1524)
				(type default)
			)
			(layer "F.SilkS")
		)
		(fp_line
			(start -1.7272 1.1684)
			(end -2.1082 1.1684)
			(stroke
				(width 0.3302)
				(type default)
			)
			(layer "F.SilkS")
		)
		(fp_line
			(start 2.7559 -6.5532)
			(end -2.7559 -6.5532)
			(stroke
				(width 0.1524)
				(type default)
			)
			(layer "F.SilkS")
		)
		(fp_line
			(start 2.7559 1.0668)
			(end 2.7559 -6.5532)
			(stroke
				(width 0.1524)
				(type default)
			)
			(layer "F.SilkS")
		)
		(fp_poly
			(pts
				(xy -2.3368 1.5748) (xy -1.905 1.143) (xy -1.4732 1.5748)
			)
			(stroke
				(width 0)
				(type default)
			)
			(fill yes)
			(layer "F.SilkS")
		)
		(fp_poly
			(pts
				(xy -2.5019 -4.02971) (xy -0.3302 -4.02971) (xy -0.3302 -6.30301) (xy -2.5019 -6.30301)
			)
			(stroke
				(width 0)
				(type default)
			)
			(fill yes)
			(layer "F.Paste")
		)
		(fp_poly
			(pts
				(xy -2.5019 -1.09601) (xy -0.3302 -1.09601) (xy -0.3302 -3.36931) (xy -2.5019 -3.36931)
			)
			(stroke
				(width 0)
				(type default)
			)
			(fill yes)
			(layer "F.Paste")
		)
		(fp_poly
			(pts
				(xy 0.3302 -4.02971) (xy 2.5019 -4.02971) (xy 2.5019 -6.30301) (xy 0.3302 -6.30301)
			)
			(stroke
				(width 0)
				(type default)
			)
			(fill yes)
			(layer "F.Paste")
		)
		(fp_poly
			(pts
				(xy 0.3302 -1.09601) (xy 2.5019 -1.09601) (xy 2.5019 -3.36931) (xy 0.3302 -3.36931)
			)
			(stroke
				(width 0)
				(type default)
			)
			(fill yes)
			(layer "F.Paste")
		)
		(fp_rect
			(start -2.4511 0.3048)
			(end 2.4511 -5.6896)
			(stroke
				(width 0)
				(type default)
			)
			(fill no)
			(layer "F.CrtYd")
		)
		(fp_poly
			(pts
				(xy -3.0099 1.3208) (xy -3.0099 -6.8072) (xy 3.0099 -6.8072) (xy 3.0099 -1.016) (xy 2.4511 -1.016)
				(xy 2.4511 -5.6896) (xy -2.4511 -5.6896) (xy -2.4511 0.3048) (xy 2.4511 0.3048) (xy 2.4511 -1.0033)
				(xy 3.0099 -1.0033) (xy 3.0099 1.3208)
			)
			(stroke
				(width 0)
				(type default)
			)
			(fill no)
			(layer "F.CrtYd")
		)
		(fp_rect
			(start -3.0099 1.3208)
			(end 3.0099 -6.8072)
			(stroke
				(width 0)
				(type default)
			)
			(fill no)
			(layer "F.Fab")
		)
		(pad "1" smd rect
			(at -1.905 0)
			(size 0.762 1.6256)
			(layers "F.Cu" "F.Mask" "F.Paste")
			(net "P12V")
		)
		(pad "2" smd rect
			(at -0.635 0)
			(size 0.762 1.6256)
			(layers "F.Cu" "F.Mask" "F.Paste")
			(net "P12V")
		)
		(pad "3" smd rect
			(at 0.635 0)
			(size 0.762 1.6256)
			(layers "F.Cu" "F.Mask" "F.Paste")
			(net "P12V")
		)
		(pad "4" smd rect
			(at 1.905 0)
			(size 0.762 1.6256)
			(layers "F.Cu" "F.Mask" "F.Paste")
			(net "ADM1276_GATE_DRV3")
		)
		(pad "5" smd rect
			(at 0 -3.69951)
			(size 5.0038 5.207)
			(layers "F.Cu" "F.Mask" "F.Paste")
			(net "P12V_SENSE_TRACE")
		)
	)
	(footprint ""
		(layer "F.Cu")
		(at 6.999986 -39.99992)
		(property "Reference" "H2"
			(at 0 0 0)
			(layer "F.SilkS")
			(hide yes)
			(effects
				(font
					(size 1.27 1.27)
				)
			)
		)
		(property "Value" "HOLE315R158"
			(at -5.08 -0.4572 0)
			(unlocked yes)
			(layer "F.Fab")
			(hide yes)
			(effects
				(font
					(size 1.016 1.016)
					(thickness 0.1524)
				)
			)
		)
		(property "Device Type" "HOLE315R158"
			(at -5.08 -1.9812 0)
			(unlocked yes)
			(layer "F.Fab")
			(hide yes)
			(effects
				(font
					(size 1.016 1.016)
					(thickness 0.1524)
				)
			)
		)
		(duplicate_pad_numbers_are_jumpers no)
		(fp_poly
			(pts
				(arc
					(start -4.3053 0)
					(mid 4.3053 0)
					(end -4.3053 0)
				)
			)
			(stroke
				(width 0)
				(type default)
			)
			(fill no)
			(layer "B.CrtYd")
		)
		(fp_poly
			(pts
				(arc
					(start -4.3053 0)
					(mid 4.3053 0)
					(end -4.3053 0)
				)
			)
			(stroke
				(width 0)
				(type default)
			)
			(fill no)
			(layer "F.CrtYd")
		)
		(fp_poly
			(pts
				(arc
					(start -4.3053 0)
					(mid 4.3053 0)
					(end -4.3053 0)
				)
			)
			(stroke
				(width 0)
				(type default)
			)
			(fill no)
			(layer "B.Fab")
		)
		(fp_poly
			(pts
				(arc
					(start -4.3053 0)
					(mid 4.3053 0)
					(end -4.3053 0)
				)
			)
			(stroke
				(width 0)
				(type default)
			)
			(fill no)
			(layer "F.Fab")
		)
		(pad "1" thru_hole circle
			(at 0 0)
			(size 8.001 8.001)
			(drill 4.0132)
			(layers "*.Cu" "*.Mask")
			(remove_unused_layers no)
			(net "GND")
			(clearance -1.4859)
			(thermal_gap 0.3048)
			(padstack
				(mode front_inner_back)
				(layer "Inner"
					(shape circle)
					(size 4.4196 4.4196)
					(clearance 0.3048)
				)
				(layer "B.Cu"
					(shape circle)
					(size 8.001 8.001)
					(clearance -1.4859)
				)
			)
		)
	)
	(footprint ""
		(layer "F.Cu")
		(at 23.622 -365.506 90)
		(property "Reference" "PR1"
			(at 0 0 90)
			(layer "F.SilkS")
			(hide yes)
			(effects
				(font
					(size 1.27 1.27)
				)
			)
		)
		(property "Value" "100KR2F-L1-GP"
			(at 0.064008 -3.993896 90)
			(unlocked yes)
			(layer "F.Fab")
			(hide yes)
			(effects
				(font
					(size 1.016 1.016)
					(thickness 0.1524)
				)
			)
		)
		(property "Device Type" "R402H16"
			(at 0.064008 -5.517896 90)
			(unlocked yes)
			(layer "F.Fab")
			(hide yes)
			(effects
				(font
					(size 1.016 1.016)
					(thickness 0.1524)
				)
			)
		)
		(duplicate_pad_numbers_are_jumpers no)
		(fp_line
			(start 0.508 -0.9398)
			(end -0.508 -0.9398)
			(stroke
				(width 0.1524)
				(type default)
			)
			(layer "F.SilkS")
		)
		(fp_line
			(start -0.508 -0.9398)
			(end -0.508 0.9398)
			(stroke
				(width 0.1524)
				(type default)
			)
			(layer "F.SilkS")
		)
		(fp_rect
			(start -0.508 0.9398)
			(end 0.508 -0.9398)
			(stroke
				(width 0)
				(type default)
			)
			(fill no)
			(layer "F.CrtYd")
		)
		(fp_rect
			(start -0.508 0.9398)
			(end 0.508 -0.9398)
			(stroke
				(width 0)
				(type default)
			)
			(fill no)
			(layer "F.Fab")
		)
		(pad "1" smd custom
			(at 0 -0.4445 90)
			(size 0.1397 0.1397)
			(layers "F.Cu" "F.Mask" "F.Paste")
			(net "ADM1276_VCAP")
			(options
				(clearance outline)
				(anchor circle)
			)
			(primitives
				(gr_poly
					(pts
						(arc
							(start -0.1778 -0.2794)
							(mid -0.249642 -0.249642)
							(end -0.2794 -0.1778)
						)
						(arc
							(start -0.2794 0.1778)
							(mid -0.249642 0.249642)
							(end -0.1778 0.2794)
						)
						(arc
							(start 0.1778 0.2794)
							(mid 0.249642 0.249642)
							(end 0.2794 0.1778)
						)
						(arc
							(start 0.2794 -0.1778)
							(mid 0.249642 -0.249642)
							(end 0.1778 -0.2794)
						)
					)
					(width 0)
					(fill yes)
				)
			)
		)
		(pad "2" smd custom
			(at 0 0.4445 90)
			(size 0.1397 0.1397)
			(layers "F.Cu" "F.Mask" "F.Paste")
			(net "ADM1276_ISET")
			(options
				(clearance outline)
				(anchor circle)
			)
			(primitives
				(gr_poly
					(pts
						(arc
							(start -0.1778 -0.2794)
							(mid -0.249642 -0.249642)
							(end -0.2794 -0.1778)
						)
						(arc
							(start -0.2794 0.1778)
							(mid -0.249642 0.249642)
							(end -0.1778 0.2794)
						)
						(arc
							(start 0.1778 0.2794)
							(mid 0.249642 0.249642)
							(end 0.2794 0.1778)
						)
						(arc
							(start 0.2794 -0.1778)
							(mid 0.249642 -0.249642)
							(end 0.1778 -0.2794)
						)
					)
					(width 0)
					(fill yes)
				)
			)
		)
	)
	(footprint ""
		(layer "F.Cu")
		(at 24.003 -248.793)
		(property "Reference" "PR56"
			(at 0 0 0)
			(layer "F.SilkS")
			(hide yes)
			(effects
				(font
					(size 1.27 1.27)
				)
			)
		)
		(property "Value" "22K1R3F-GP"
			(at -0.0254 -2.5146 0)
			(unlocked yes)
			(layer "F.Fab")
			(hide yes)
			(effects
				(font
					(size 1.016 1.016)
					(thickness 0.1524)
				)
			)
		)
		(property "Device Type" "R603H22"
			(at -0.0254 -4.0386 0)
			(unlocked yes)
			(layer "F.Fab")
			(hide yes)
			(effects
				(font
					(size 1.016 1.016)
					(thickness 0.1524)
				)
			)
		)
		(duplicate_pad_numbers_are_jumpers no)
		(fp_line
			(start -0.4826 0)
			(end -0.2032 0)
			(stroke
				(width 0.2032)
				(type default)
			)
			(layer "F.SilkS")
		)
		(fp_line
			(start 0.2032 0)
			(end 0.4826 0)
			(stroke
				(width 0.2032)
				(type default)
			)
			(layer "F.SilkS")
		)
		(fp_rect
			(start -0.5842 1.3335)
			(end 0.5842 -1.3335)
			(stroke
				(width 0)
				(type default)
			)
			(fill no)
			(layer "F.CrtYd")
		)
		(fp_rect
			(start -0.5842 1.3335)
			(end 0.5842 -1.3335)
			(stroke
				(width 0)
				(type default)
			)
			(fill no)
			(layer "F.Fab")
		)
		(pad "1" smd custom
			(at 0 -0.762)
			(size 0.2159 0.2159)
			(layers "F.Cu" "F.Mask" "F.Paste")
			(net "P3V3_FB")
			(options
				(clearance outline)
				(anchor circle)
			)
			(primitives
				(gr_poly
					(pts
						(arc
							(start -0.3302 -0.4318)
							(mid -0.402042 -0.402042)
							(end -0.4318 -0.3302)
						)
						(arc
							(start -0.4318 0.3302)
							(mid -0.402042 0.402042)
							(end -0.3302 0.4318)
						)
						(arc
							(start 0.3302 0.4318)
							(mid 0.402042 0.402042)
							(end 0.4318 0.3302)
						)
						(arc
							(start 0.4318 -0.3302)
							(mid 0.402042 -0.402042)
							(end 0.3302 -0.4318)
						)
					)
					(width 0)
					(fill yes)
				)
			)
		)
		(pad "2" smd custom
			(at 0 0.762)
			(size 0.2159 0.2159)
			(layers "F.Cu" "F.Mask" "F.Paste")
			(net "GND")
			(options
				(clearance outline)
				(anchor circle)
			)
			(primitives
				(gr_poly
					(pts
						(arc
							(start -0.3302 -0.4318)
							(mid -0.402042 -0.402042)
							(end -0.4318 -0.3302)
						)
						(arc
							(start -0.4318 0.3302)
							(mid -0.402042 0.402042)
							(end -0.3302 0.4318)
						)
						(arc
							(start 0.3302 0.4318)
							(mid 0.402042 0.402042)
							(end 0.4318 0.3302)
						)
						(arc
							(start 0.4318 -0.3302)
							(mid 0.402042 -0.402042)
							(end 0.3302 -0.4318)
						)
					)
					(width 0)
					(fill yes)
				)
			)
		)
	)
	(footprint ""
		(layer "F.Cu")
		(at 13.2588 -61.3918)
		(property "Reference" "C31"
			(at 0 0 0)
			(layer "F.SilkS")
			(hide yes)
			(effects
				(font
					(size 1.27 1.27)
				)
			)
		)
		(property "Value" "SCD1U50V3KX-GP"
			(at 0 -2.8194 0)
			(unlocked yes)
			(layer "F.Fab")
			(hide yes)
			(effects
				(font
					(size 1.016 1.016)
					(thickness 0.1524)
				)
			)
		)
		(property "Device Type" "C603H36"
			(at 0 -4.3434 0)
			(unlocked yes)
			(layer "F.Fab")
			(hide yes)
			(effects
				(font
					(size 1.016 1.016)
					(thickness 0.1524)
				)
			)
		)
		(duplicate_pad_numbers_are_jumpers no)
		(fp_line
			(start 0.508 0)
			(end -0.508 0)
			(stroke
				(width 0.2032)
				(type default)
			)
			(layer "F.SilkS")
		)
		(fp_rect
			(start -0.5842 1.3335)
			(end 0.5842 -1.3335)
			(stroke
				(width 0)
				(type default)
			)
			(fill no)
			(layer "F.CrtYd")
		)
		(fp_rect
			(start -0.5842 1.3335)
			(end 0.5842 -1.3335)
			(stroke
				(width 0)
				(type default)
			)
			(fill no)
			(layer "F.Fab")
		)
		(pad "1" smd custom
			(at 0 -0.762)
			(size 0.2159 0.2159)
			(layers "F.Cu" "F.Mask" "F.Paste")
			(net "P12V")
			(options
				(clearance outline)
				(anchor circle)
			)
			(primitives
				(gr_poly
					(pts
						(arc
							(start -0.3302 -0.4318)
							(mid -0.402042 -0.402042)
							(end -0.4318 -0.3302)
						)
						(arc
							(start -0.4318 0.3302)
							(mid -0.402042 0.402042)
							(end -0.3302 0.4318)
						)
						(arc
							(start 0.3302 0.4318)
							(mid 0.402042 0.402042)
							(end 0.4318 0.3302)
						)
						(arc
							(start 0.4318 -0.3302)
							(mid 0.402042 -0.402042)
							(end 0.3302 -0.4318)
						)
					)
					(width 0)
					(fill yes)
				)
			)
		)
		(pad "2" smd custom
			(at 0 0.762)
			(size 0.2159 0.2159)
			(layers "F.Cu" "F.Mask" "F.Paste")
			(net "GND")
			(options
				(clearance outline)
				(anchor circle)
			)
			(primitives
				(gr_poly
					(pts
						(arc
							(start -0.3302 -0.4318)
							(mid -0.402042 -0.402042)
							(end -0.4318 -0.3302)
						)
						(arc
							(start -0.4318 0.3302)
							(mid -0.402042 0.402042)
							(end -0.3302 0.4318)
						)
						(arc
							(start 0.3302 0.4318)
							(mid 0.402042 0.402042)
							(end 0.4318 0.3302)
						)
						(arc
							(start 0.4318 -0.3302)
							(mid 0.402042 -0.402042)
							(end 0.3302 -0.4318)
						)
					)
					(width 0)
					(fill yes)
				)
			)
		)
	)
	(footprint ""
		(layer "F.Cu")
		(at 23.48611 -154.602434)
		(property "Reference" "R4"
			(at 0 0 0)
			(layer "F.SilkS")
			(hide yes)
			(effects
				(font
					(size 1.27 1.27)
				)
			)
		)
		(property "Value" "0R2J-2-GP"
			(at 0.064008 -3.993896 0)
			(unlocked yes)
			(layer "F.Fab")
			(hide yes)
			(effects
				(font
					(size 1.016 1.016)
					(thickness 0.1524)
				)
			)
		)
		(property "Device Type" "R402H16"
			(at 0.064008 -5.517896 0)
			(unlocked yes)
			(layer "F.Fab")
			(hide yes)
			(effects
				(font
					(size 1.016 1.016)
					(thickness 0.1524)
				)
			)
		)
		(duplicate_pad_numbers_are_jumpers no)
		(fp_line
			(start -0.508 -0.9398)
			(end -0.508 0.9398)
			(stroke
				(width 0.1524)
				(type default)
			)
			(layer "F.SilkS")
		)
		(fp_line
			(start 0.508 -0.9398)
			(end -0.508 -0.9398)
			(stroke
				(width 0.1524)
				(type default)
			)
			(layer "F.SilkS")
		)
		(fp_rect
			(start -0.508 0.9398)
			(end 0.508 -0.9398)
			(stroke
				(width 0)
				(type default)
			)
			(fill no)
			(layer "F.CrtYd")
		)
		(fp_rect
			(start -0.508 0.9398)
			(end 0.508 -0.9398)
			(stroke
				(width 0)
				(type default)
			)
			(fill no)
			(layer "F.Fab")
		)
		(pad "1" smd custom
			(at 0 -0.4445)
			(size 0.1397 0.1397)
			(layers "F.Cu" "F.Mask" "F.Paste")
			(net "NCT7904_TMPALM")
			(options
				(clearance outline)
				(anchor circle)
			)
			(primitives
				(gr_poly
					(pts
						(arc
							(start -0.1778 -0.2794)
							(mid -0.249642 -0.249642)
							(end -0.2794 -0.1778)
						)
						(arc
							(start -0.2794 0.1778)
							(mid -0.249642 0.249642)
							(end -0.1778 0.2794)
						)
						(arc
							(start 0.1778 0.2794)
							(mid 0.249642 0.249642)
							(end 0.2794 0.1778)
						)
						(arc
							(start 0.2794 -0.1778)
							(mid 0.249642 -0.249642)
							(end 0.1778 -0.2794)
						)
					)
					(width 0)
					(fill yes)
				)
			)
		)
		(pad "2" smd custom
			(at 0 0.4445)
			(size 0.1397 0.1397)
			(layers "F.Cu" "F.Mask" "F.Paste")
			(net "TEMP_ALM#")
			(options
				(clearance outline)
				(anchor circle)
			)
			(primitives
				(gr_poly
					(pts
						(arc
							(start -0.1778 -0.2794)
							(mid -0.249642 -0.249642)
							(end -0.2794 -0.1778)
						)
						(arc
							(start -0.2794 0.1778)
							(mid -0.249642 0.249642)
							(end -0.1778 0.2794)
						)
						(arc
							(start 0.1778 0.2794)
							(mid 0.249642 0.249642)
							(end 0.2794 0.1778)
						)
						(arc
							(start 0.2794 -0.1778)
							(mid 0.249642 -0.249642)
							(end 0.1778 -0.2794)
						)
					)
					(width 0)
					(fill yes)
				)
			)
		)
	)
	(footprint ""
		(layer "F.Cu")
		(at 32.766 -381 180)
		(property "Reference" "PR22"
			(at 0 0 180)
			(layer "F.SilkS")
			(hide yes)
			(effects
				(font
					(size 1.27 1.27)
				)
			)
		)
		(property "Value" "10R2F-L-GP"
			(at 0.064008 -3.993896 180)
			(unlocked yes)
			(layer "F.Fab")
			(hide yes)
			(effects
				(font
					(size 1.016 1.016)
					(thickness 0.1524)
				)
			)
		)
		(property "Device Type" "R402H14"
			(at 0.064008 -5.517896 180)
			(unlocked yes)
			(layer "F.Fab")
			(hide yes)
			(effects
				(font
					(size 1.016 1.016)
					(thickness 0.1524)
				)
			)
		)
		(duplicate_pad_numbers_are_jumpers no)
		(fp_line
			(start 0.508 -0.9398)
			(end -0.508 -0.9398)
			(stroke
				(width 0.1524)
				(type default)
			)
			(layer "F.SilkS")
		)
		(fp_line
			(start -0.508 -0.9398)
			(end -0.508 0.9398)
			(stroke
				(width 0.1524)
				(type default)
			)
			(layer "F.SilkS")
		)
		(fp_rect
			(start -0.508 0.9398)
			(end 0.508 -0.9398)
			(stroke
				(width 0)
				(type default)
			)
			(fill no)
			(layer "F.CrtYd")
		)
		(fp_rect
			(start -0.508 0.9398)
			(end 0.508 -0.9398)
			(stroke
				(width 0)
				(type default)
			)
			(fill no)
			(layer "F.Fab")
		)
		(pad "1" smd custom
			(at 0 -0.4445 180)
			(size 0.1397 0.1397)
			(layers "F.Cu" "F.Mask" "F.Paste")
			(net "ADM1276_SENSE-")
			(options
				(clearance outline)
				(anchor circle)
			)
			(primitives
				(gr_poly
					(pts
						(arc
							(start -0.1778 -0.2794)
							(mid -0.249642 -0.249642)
							(end -0.2794 -0.1778)
						)
						(arc
							(start -0.2794 0.1778)
							(mid -0.249642 0.249642)
							(end -0.1778 0.2794)
						)
						(arc
							(start 0.1778 0.2794)
							(mid 0.249642 0.249642)
							(end 0.2794 0.1778)
						)
						(arc
							(start 0.2794 -0.1778)
							(mid 0.249642 -0.249642)
							(end 0.1778 -0.2794)
						)
					)
					(width 0)
					(fill yes)
				)
			)
		)
		(pad "2" smd custom
			(at 0 0.4445 180)
			(size 0.1397 0.1397)
			(layers "F.Cu" "F.Mask" "F.Paste")
			(net "SENSE-_R2")
			(options
				(clearance outline)
				(anchor circle)
			)
			(primitives
				(gr_poly
					(pts
						(arc
							(start -0.1778 -0.2794)
							(mid -0.249642 -0.249642)
							(end -0.2794 -0.1778)
						)
						(arc
							(start -0.2794 0.1778)
							(mid -0.249642 0.249642)
							(end -0.1778 0.2794)
						)
						(arc
							(start 0.1778 0.2794)
							(mid 0.249642 0.249642)
							(end 0.2794 0.1778)
						)
						(arc
							(start 0.2794 -0.1778)
							(mid 0.249642 -0.249642)
							(end 0.1778 -0.2794)
						)
					)
					(width 0)
					(fill yes)
				)
			)
		)
	)
	(footprint ""
		(layer "F.Cu")
		(at 28.702 -381 180)
		(property "Reference" "PR18"
			(at 0 0 180)
			(layer "F.SilkS")
			(hide yes)
			(effects
				(font
					(size 1.27 1.27)
				)
			)
		)
		(property "Value" "10R2F-L-GP"
			(at 0.064008 -3.993896 180)
			(unlocked yes)
			(layer "F.Fab")
			(hide yes)
			(effects
				(font
					(size 1.016 1.016)
					(thickness 0.1524)
				)
			)
		)
		(property "Device Type" "R402H14"
			(at 0.064008 -5.517896 180)
			(unlocked yes)
			(layer "F.Fab")
			(hide yes)
			(effects
				(font
					(size 1.016 1.016)
					(thickness 0.1524)
				)
			)
		)
		(duplicate_pad_numbers_are_jumpers no)
		(fp_line
			(start 0.508 -0.9398)
			(end -0.508 -0.9398)
			(stroke
				(width 0.1524)
				(type default)
			)
			(layer "F.SilkS")
		)
		(fp_line
			(start -0.508 -0.9398)
			(end -0.508 0.9398)
			(stroke
				(width 0.1524)
				(type default)
			)
			(layer "F.SilkS")
		)
		(fp_rect
			(start -0.508 0.9398)
			(end 0.508 -0.9398)
			(stroke
				(width 0)
				(type default)
			)
			(fill no)
			(layer "F.CrtYd")
		)
		(fp_rect
			(start -0.508 0.9398)
			(end 0.508 -0.9398)
			(stroke
				(width 0)
				(type default)
			)
			(fill no)
			(layer "F.Fab")
		)
		(pad "1" smd custom
			(at 0 -0.4445 180)
			(size 0.1397 0.1397)
			(layers "F.Cu" "F.Mask" "F.Paste")
			(net "ADM1276_SENSE+")
			(options
				(clearance outline)
				(anchor circle)
			)
			(primitives
				(gr_poly
					(pts
						(arc
							(start -0.1778 -0.2794)
							(mid -0.249642 -0.249642)
							(end -0.2794 -0.1778)
						)
						(arc
							(start -0.2794 0.1778)
							(mid -0.249642 0.249642)
							(end -0.1778 0.2794)
						)
						(arc
							(start 0.1778 0.2794)
							(mid 0.249642 0.249642)
							(end 0.2794 0.1778)
						)
						(arc
							(start 0.2794 -0.1778)
							(mid 0.249642 -0.249642)
							(end 0.1778 -0.2794)
						)
					)
					(width 0)
					(fill yes)
				)
			)
		)
		(pad "2" smd custom
			(at 0 0.4445 180)
			(size 0.1397 0.1397)
			(layers "F.Cu" "F.Mask" "F.Paste")
			(net "SENSE+_R3")
			(options
				(clearance outline)
				(anchor circle)
			)
			(primitives
				(gr_poly
					(pts
						(arc
							(start -0.1778 -0.2794)
							(mid -0.249642 -0.249642)
							(end -0.2794 -0.1778)
						)
						(arc
							(start -0.2794 0.1778)
							(mid -0.249642 0.249642)
							(end -0.1778 0.2794)
						)
						(arc
							(start 0.1778 0.2794)
							(mid 0.249642 0.249642)
							(end 0.2794 0.1778)
						)
						(arc
							(start 0.2794 -0.1778)
							(mid 0.249642 -0.249642)
							(end 0.1778 -0.2794)
						)
					)
					(width 0)
					(fill yes)
				)
			)
		)
	)
	(footprint ""
		(layer "F.Cu")
		(at 20.381976 -176.43729 -90)
		(property "Reference" "R24"
			(at 0 0 270)
			(layer "F.SilkS")
			(hide yes)
			(effects
				(font
					(size 1.27 1.27)
				)
			)
		)
		(property "Value" "4K7R2F-GP"
			(at 0.064008 -3.993896 270)
			(unlocked yes)
			(layer "F.Fab")
			(hide yes)
			(effects
				(font
					(size 1.016 1.016)
					(thickness 0.1524)
				)
			)
		)
		(property "Device Type" "R402H16"
			(at 0.064008 -5.517896 270)
			(unlocked yes)
			(layer "F.Fab")
			(hide yes)
			(effects
				(font
					(size 1.016 1.016)
					(thickness 0.1524)
				)
			)
		)
		(duplicate_pad_numbers_are_jumpers no)
		(fp_line
			(start -0.508 -0.9398)
			(end -0.508 0.9398)
			(stroke
				(width 0.1524)
				(type default)
			)
			(layer "F.SilkS")
		)
		(fp_line
			(start 0.508 -0.9398)
			(end -0.508 -0.9398)
			(stroke
				(width 0.1524)
				(type default)
			)
			(layer "F.SilkS")
		)
		(fp_rect
			(start -0.508 0.9398)
			(end 0.508 -0.9398)
			(stroke
				(width 0)
				(type default)
			)
			(fill no)
			(layer "F.CrtYd")
		)
		(fp_rect
			(start -0.508 0.9398)
			(end 0.508 -0.9398)
			(stroke
				(width 0)
				(type default)
			)
			(fill no)
			(layer "F.Fab")
		)
		(pad "1" smd custom
			(at 0 -0.4445 270)
			(size 0.1397 0.1397)
			(layers "F.Cu" "F.Mask" "F.Paste")
			(net "NCT7368S_SEL")
			(options
				(clearance outline)
				(anchor circle)
			)
			(primitives
				(gr_poly
					(pts
						(arc
							(start -0.1778 -0.2794)
							(mid -0.249642 -0.249642)
							(end -0.2794 -0.1778)
						)
						(arc
							(start -0.2794 0.1778)
							(mid -0.249642 0.249642)
							(end -0.1778 0.2794)
						)
						(arc
							(start 0.1778 0.2794)
							(mid 0.249642 0.249642)
							(end 0.2794 0.1778)
						)
						(arc
							(start 0.2794 -0.1778)
							(mid 0.249642 -0.249642)
							(end 0.1778 -0.2794)
						)
					)
					(width 0)
					(fill yes)
				)
			)
		)
		(pad "2" smd custom
			(at 0 0.4445 270)
			(size 0.1397 0.1397)
			(layers "F.Cu" "F.Mask" "F.Paste")
			(net "GND")
			(options
				(clearance outline)
				(anchor circle)
			)
			(primitives
				(gr_poly
					(pts
						(arc
							(start -0.1778 -0.2794)
							(mid -0.249642 -0.249642)
							(end -0.2794 -0.1778)
						)
						(arc
							(start -0.2794 0.1778)
							(mid -0.249642 0.249642)
							(end -0.1778 0.2794)
						)
						(arc
							(start 0.1778 0.2794)
							(mid 0.249642 0.249642)
							(end 0.2794 0.1778)
						)
						(arc
							(start 0.2794 -0.1778)
							(mid 0.249642 -0.249642)
							(end 0.1778 -0.2794)
						)
					)
					(width 0)
					(fill yes)
				)
			)
		)
	)
	(footprint ""
		(layer "F.Cu")
		(at 34.925 -366.268)
		(property "Reference" "PR38"
			(at 0 0 0)
			(layer "F.SilkS")
			(hide yes)
			(effects
				(font
					(size 1.27 1.27)
				)
			)
		)
		(property "Value" "1KR2F-3-GP"
			(at 0.064008 -3.993896 0)
			(unlocked yes)
			(layer "F.Fab")
			(hide yes)
			(effects
				(font
					(size 1.016 1.016)
					(thickness 0.1524)
				)
			)
		)
		(property "Device Type" "R402H16"
			(at 0.064008 -5.517896 0)
			(unlocked yes)
			(layer "F.Fab")
			(hide yes)
			(effects
				(font
					(size 1.016 1.016)
					(thickness 0.1524)
				)
			)
		)
		(duplicate_pad_numbers_are_jumpers no)
		(fp_line
			(start -0.508 -0.9398)
			(end -0.508 0.9398)
			(stroke
				(width 0.1524)
				(type default)
			)
			(layer "F.SilkS")
		)
		(fp_line
			(start 0.508 -0.9398)
			(end -0.508 -0.9398)
			(stroke
				(width 0.1524)
				(type default)
			)
			(layer "F.SilkS")
		)
		(fp_rect
			(start -0.508 0.9398)
			(end 0.508 -0.9398)
			(stroke
				(width 0)
				(type default)
			)
			(fill no)
			(layer "F.CrtYd")
		)
		(fp_rect
			(start -0.508 0.9398)
			(end 0.508 -0.9398)
			(stroke
				(width 0)
				(type default)
			)
			(fill no)
			(layer "F.Fab")
		)
		(pad "1" smd custom
			(at 0 -0.4445)
			(size 0.1397 0.1397)
			(layers "F.Cu" "F.Mask" "F.Paste")
			(net "ADM1276_EN_NET")
			(options
				(clearance outline)
				(anchor circle)
			)
			(primitives
				(gr_poly
					(pts
						(arc
							(start -0.1778 -0.2794)
							(mid -0.249642 -0.249642)
							(end -0.2794 -0.1778)
						)
						(arc
							(start -0.2794 0.1778)
							(mid -0.249642 0.249642)
							(end -0.1778 0.2794)
						)
						(arc
							(start 0.1778 0.2794)
							(mid 0.249642 0.249642)
							(end 0.2794 0.1778)
						)
						(arc
							(start 0.2794 -0.1778)
							(mid 0.249642 -0.249642)
							(end 0.1778 -0.2794)
						)
					)
					(width 0)
					(fill yes)
				)
			)
		)
		(pad "2" smd custom
			(at 0 0.4445)
			(size 0.1397 0.1397)
			(layers "F.Cu" "F.Mask" "F.Paste")
			(net "ADM1276_EN")
			(options
				(clearance outline)
				(anchor circle)
			)
			(primitives
				(gr_poly
					(pts
						(arc
							(start -0.1778 -0.2794)
							(mid -0.249642 -0.249642)
							(end -0.2794 -0.1778)
						)
						(arc
							(start -0.2794 0.1778)
							(mid -0.249642 0.249642)
							(end -0.1778 0.2794)
						)
						(arc
							(start 0.1778 0.2794)
							(mid 0.249642 0.249642)
							(end 0.2794 0.1778)
						)
						(arc
							(start 0.2794 -0.1778)
							(mid 0.249642 -0.249642)
							(end 0.1778 -0.2794)
						)
					)
					(width 0)
					(fill yes)
				)
			)
		)
	)
	(footprint ""
		(layer "F.Cu")
		(at 19.431 -111.76)
		(property "Reference" "PQ11"
			(at 0 0 0)
			(layer "F.SilkS")
			(hide yes)
			(effects
				(font
					(size 1.27 1.27)
				)
			)
		)
		(property "Value" "PH0925CL-GP"
			(at -4.2799 -0.4572 0)
			(unlocked yes)
			(layer "F.Fab")
			(hide yes)
			(effects
				(font
					(size 1.016 1.016)
					(thickness 0.1524)
				)
			)
		)
		(property "Device Type" "LFPAK-5PH48-U"
			(at -4.2799 -1.9812 0)
			(unlocked yes)
			(layer "F.Fab")
			(hide yes)
			(effects
				(font
					(size 1.016 1.016)
					(thickness 0.1524)
				)
			)
		)
		(duplicate_pad_numbers_are_jumpers no)
		(fp_line
			(start -2.7559 -6.5532)
			(end -2.7559 1.0668)
			(stroke
				(width 0.1524)
				(type default)
			)
			(layer "F.SilkS")
		)
		(fp_line
			(start -2.7559 1.0668)
			(end 2.7559 1.0668)
			(stroke
				(width 0.1524)
				(type default)
			)
			(layer "F.SilkS")
		)
		(fp_line
			(start -1.7272 1.1684)
			(end -2.1082 1.1684)
			(stroke
				(width 0.3302)
				(type default)
			)
			(layer "F.SilkS")
		)
		(fp_line
			(start 2.7559 -6.5532)
			(end -2.7559 -6.5532)
			(stroke
				(width 0.1524)
				(type default)
			)
			(layer "F.SilkS")
		)
		(fp_line
			(start 2.7559 1.0668)
			(end 2.7559 -6.5532)
			(stroke
				(width 0.1524)
				(type default)
			)
			(layer "F.SilkS")
		)
		(fp_poly
			(pts
				(xy -2.3368 1.5748) (xy -1.905 1.143) (xy -1.4732 1.5748)
			)
			(stroke
				(width 0)
				(type default)
			)
			(fill yes)
			(layer "F.SilkS")
		)
		(fp_poly
			(pts
				(xy -2.5019 -4.02971) (xy -0.3302 -4.02971) (xy -0.3302 -6.30301) (xy -2.5019 -6.30301)
			)
			(stroke
				(width 0)
				(type default)
			)
			(fill yes)
			(layer "F.Paste")
		)
		(fp_poly
			(pts
				(xy -2.5019 -1.09601) (xy -0.3302 -1.09601) (xy -0.3302 -3.36931) (xy -2.5019 -3.36931)
			)
			(stroke
				(width 0)
				(type default)
			)
			(fill yes)
			(layer "F.Paste")
		)
		(fp_poly
			(pts
				(xy 0.3302 -4.02971) (xy 2.5019 -4.02971) (xy 2.5019 -6.30301) (xy 0.3302 -6.30301)
			)
			(stroke
				(width 0)
				(type default)
			)
			(fill yes)
			(layer "F.Paste")
		)
		(fp_poly
			(pts
				(xy 0.3302 -1.09601) (xy 2.5019 -1.09601) (xy 2.5019 -3.36931) (xy 0.3302 -3.36931)
			)
			(stroke
				(width 0)
				(type default)
			)
			(fill yes)
			(layer "F.Paste")
		)
		(fp_rect
			(start -2.4511 0.3048)
			(end 2.4511 -5.6896)
			(stroke
				(width 0)
				(type default)
			)
			(fill no)
			(layer "F.CrtYd")
		)
		(fp_poly
			(pts
				(xy -3.0099 1.3208) (xy -3.0099 -6.8072) (xy 3.0099 -6.8072) (xy 3.0099 -1.016) (xy 2.4511 -1.016)
				(xy 2.4511 -5.6896) (xy -2.4511 -5.6896) (xy -2.4511 0.3048) (xy 2.4511 0.3048) (xy 2.4511 -1.0033)
				(xy 3.0099 -1.0033) (xy 3.0099 1.3208)
			)
			(stroke
				(width 0)
				(type default)
			)
			(fill no)
			(layer "F.CrtYd")
		)
		(fp_rect
			(start -3.0099 1.3208)
			(end 3.0099 -6.8072)
			(stroke
				(width 0)
				(type default)
			)
			(fill no)
			(layer "F.Fab")
		)
		(pad "1" smd rect
			(at -1.905 0)
			(size 0.762 1.6256)
			(layers "F.Cu" "F.Mask" "F.Paste")
			(net "P12VU")
		)
		(pad "2" smd rect
			(at -0.635 0)
			(size 0.762 1.6256)
			(layers "F.Cu" "F.Mask" "F.Paste")
			(net "P12VU")
		)
		(pad "3" smd rect
			(at 0.635 0)
			(size 0.762 1.6256)
			(layers "F.Cu" "F.Mask" "F.Paste")
			(net "P12VU")
		)
		(pad "4" smd rect
			(at 1.905 0)
			(size 0.762 1.6256)
			(layers "F.Cu" "F.Mask" "F.Paste")
			(net "P12VU_2490_GATE_DRV_2")
		)
		(pad "5" smd rect
			(at 0 -3.69951)
			(size 5.0038 5.207)
			(layers "F.Cu" "F.Mask" "F.Paste")
			(net "P12VU_NET")
		)
	)
	(footprint ""
		(layer "F.Cu")
		(at 8.9662 -101.0412 -90)
		(property "Reference" "TC1"
			(at 0 0 270)
			(layer "F.SilkS")
			(hide yes)
			(effects
				(font
					(size 1.27 1.27)
				)
			)
		)
		(property "Value" "ST68U16VDM-1-GP"
			(at 0 -9.6012 270)
			(unlocked yes)
			(layer "F.Fab")
			(hide yes)
			(effects
				(font
					(size 1.016 1.016)
					(thickness 0.1524)
				)
			)
		)
		(property "Device Type" "CT7343H79"
			(at 0 -11.1252 270)
			(unlocked yes)
			(layer "F.Fab")
			(hide yes)
			(effects
				(font
					(size 1.016 1.016)
					(thickness 0.1524)
				)
			)
		)
		(duplicate_pad_numbers_are_jumpers no)
		(fp_line
			(start -2.286 4.8768)
			(end -2.286 2.032)
			(stroke
				(width 0.1524)
				(type default)
			)
			(layer "F.SilkS")
		)
		(fp_line
			(start 2.286 4.8768)
			(end -2.286 4.8768)
			(stroke
				(width 0.1524)
				(type default)
			)
			(layer "F.SilkS")
		)
		(fp_line
			(start 2.286 2.032)
			(end 2.286 4.8768)
			(stroke
				(width 0.1524)
				(type default)
			)
			(layer "F.SilkS")
		)
		(fp_line
			(start 2.286 -2.032)
			(end 2.286 -4.8768)
			(stroke
				(width 0.1524)
				(type default)
			)
			(layer "F.SilkS")
		)
		(fp_line
			(start 2.1082 -4.699)
			(end -2.1082 -4.699)
			(stroke
				(width 0.508)
				(type default)
			)
			(layer "F.SilkS")
		)
		(fp_line
			(start -2.286 -4.8768)
			(end -2.286 -2.032)
			(stroke
				(width 0.1524)
				(type default)
			)
			(layer "F.SilkS")
		)
		(fp_line
			(start 2.286 -4.8768)
			(end -2.286 -4.8768)
			(stroke
				(width 0.1524)
				(type default)
			)
			(layer "F.SilkS")
		)
		(fp_rect
			(start -2.1463 3.6449)
			(end 2.1463 -3.6449)
			(stroke
				(width 0)
				(type default)
			)
			(fill no)
			(layer "F.CrtYd")
		)
		(fp_poly
			(pts
				(xy -2.54 4.953) (xy -2.54 4.2926) (xy -3.81 4.2926) (xy -3.81 -4.2926) (xy -2.54 -4.2926) (xy -2.54 -4.953)
				(xy 2.54 -4.953) (xy 2.54 -4.2926) (xy 3.81 -4.2926) (xy 3.81 -1.6256) (xy 2.1463 -1.6256) (xy 2.1463 -3.6449)
				(xy -2.1463 -3.6449) (xy -2.1463 3.6449) (xy 2.1463 3.6449) (xy 2.1463 -1.6129) (xy 3.81 -1.6129)
				(xy 3.81 4.2926) (xy 2.54 4.2926) (xy 2.54 4.953)
			)
			(stroke
				(width 0)
				(type default)
			)
			(fill no)
			(layer "F.CrtYd")
		)
		(fp_rect
			(start -2.54 4.953)
			(end 2.54 -4.953)
			(stroke
				(width 0)
				(type default)
			)
			(fill no)
			(layer "F.Fab")
		)
		(fp_rect
			(start -3.81 4.2926)
			(end -2.54 -4.2926)
			(stroke
				(width 0)
				(type default)
			)
			(fill no)
			(layer "F.Fab")
		)
		(fp_rect
			(start 2.54 4.2926)
			(end 3.81 -4.2926)
			(stroke
				(width 0)
				(type default)
			)
			(fill no)
			(layer "F.Fab")
		)
		(pad "1" smd rect
			(at 0 -3.1496 270)
			(size 2.413 2.286)
			(layers "F.Cu" "F.Mask" "F.Paste")
			(net "P12VU")
		)
		(pad "2" smd rect
			(at 0 3.1496 270)
			(size 2.413 2.286)
			(layers "F.Cu" "F.Mask" "F.Paste")
			(net "GND")
		)
		(zone
			(layer "F.Cu")
			(hatch none 0.5)
			(connect_pads
				(clearance 0)
			)
			(min_thickness 0.25)
			(keepout
				(tracks allowed)
				(vias not_allowed)
				(pads allowed)
				(copperpour not_allowed)
				(footprints allowed)
			)
			(placement
				(enabled no)
				(sheetname "")
			)
			(fill
				(thermal_gap 0.5)
				(thermal_bridge_width 0.5)
				(island_removal_mode 0)
			)
			(polygon
				(pts
					(xy 4.3688 -102.5525) (xy 4.3688 -99.5299) (xy 7.2644 -99.5299) (xy 7.5946 -99.5299) (xy 7.5946 -102.5525)
					(xy 7.2644 -102.5525)
				)
			)
		)
		(zone
			(layer "F.Cu")
			(hatch none 0.5)
			(connect_pads
				(clearance 0)
			)
			(min_thickness 0.25)
			(keepout
				(tracks allowed)
				(vias not_allowed)
				(pads allowed)
				(copperpour not_allowed)
				(footprints allowed)
			)
			(placement
				(enabled no)
				(sheetname "")
			)
			(fill
				(thermal_gap 0.5)
				(thermal_bridge_width 0.5)
				(island_removal_mode 0)
			)
			(polygon
				(pts
					(xy 10.6553 -99.5299) (xy 13.5636 -99.5299) (xy 13.5636 -102.5525) (xy 10.668 -102.5525) (xy 10.3378 -102.5525)
					(xy 10.3378 -99.5299)
				)
			)
		)
	)
	(footprint ""
		(layer "F.Cu")
		(at 33.51149 -152.889966 180)
		(property "Reference" "TP10"
			(at 0 0 180)
			(layer "F.SilkS")
			(hide yes)
			(effects
				(font
					(size 1.27 1.27)
				)
			)
		)
		(property "Value" "TPAD32-GP"
			(at 0 -3.166364 180)
			(unlocked yes)
			(layer "F.Fab")
			(hide yes)
			(effects
				(font
					(size 1.016 1.016)
					(thickness 0.1524)
				)
			)
		)
		(property "Device Type" "TPAD32"
			(at 0 -4.690618 180)
			(unlocked yes)
			(layer "F.Fab")
			(hide yes)
			(effects
				(font
					(size 1.016 1.016)
					(thickness 0.1524)
				)
			)
		)
		(duplicate_pad_numbers_are_jumpers no)
		(fp_poly
			(pts
				(arc
					(start 0.7112 0)
					(mid -0.7112 0)
					(end 0.7112 0)
				)
			)
			(stroke
				(width 0)
				(type default)
			)
			(fill no)
			(layer "F.CrtYd")
		)
		(fp_poly
			(pts
				(arc
					(start 0.7112 0)
					(mid -0.7112 0)
					(end 0.7112 0)
				)
			)
			(stroke
				(width 0)
				(type default)
			)
			(fill no)
			(layer "F.Fab")
		)
		(pad "1" smd circle
			(at 0 0 180)
			(size 0.8128 0.8128)
			(layers "F.Cu" "F.Mask" "F.Paste")
			(net "NCT7904_VSEN11")
		)
	)
	(footprint ""
		(layer "F.Cu")
		(at 37.719 -373.9896 180)
		(property "Reference" "PR25"
			(at 0 0 180)
			(layer "F.SilkS")
			(hide yes)
			(effects
				(font
					(size 1.27 1.27)
				)
			)
		)
		(property "Value" "0R2J-2-GP"
			(at 0.064008 -3.993896 180)
			(unlocked yes)
			(layer "F.Fab")
			(hide yes)
			(effects
				(font
					(size 1.016 1.016)
					(thickness 0.1524)
				)
			)
		)
		(property "Device Type" "R402H16"
			(at 0.064008 -5.517896 180)
			(unlocked yes)
			(layer "F.Fab")
			(hide yes)
			(effects
				(font
					(size 1.016 1.016)
					(thickness 0.1524)
				)
			)
		)
		(duplicate_pad_numbers_are_jumpers no)
		(fp_line
			(start 0.508 -0.9398)
			(end -0.508 -0.9398)
			(stroke
				(width 0.1524)
				(type default)
			)
			(layer "F.SilkS")
		)
		(fp_line
			(start -0.508 -0.9398)
			(end -0.508 0.9398)
			(stroke
				(width 0.1524)
				(type default)
			)
			(layer "F.SilkS")
		)
		(fp_rect
			(start -0.508 0.9398)
			(end 0.508 -0.9398)
			(stroke
				(width 0)
				(type default)
			)
			(fill no)
			(layer "F.CrtYd")
		)
		(fp_rect
			(start -0.508 0.9398)
			(end 0.508 -0.9398)
			(stroke
				(width 0)
				(type default)
			)
			(fill no)
			(layer "F.Fab")
		)
		(pad "1" smd custom
			(at 0 -0.4445 180)
			(size 0.1397 0.1397)
			(layers "F.Cu" "F.Mask" "F.Paste")
			(net "P12V")
			(options
				(clearance outline)
				(anchor circle)
			)
			(primitives
				(gr_poly
					(pts
						(arc
							(start -0.1778 -0.2794)
							(mid -0.249642 -0.249642)
							(end -0.2794 -0.1778)
						)
						(arc
							(start -0.2794 0.1778)
							(mid -0.249642 0.249642)
							(end -0.1778 0.2794)
						)
						(arc
							(start 0.1778 0.2794)
							(mid 0.249642 0.249642)
							(end 0.2794 0.1778)
						)
						(arc
							(start 0.2794 -0.1778)
							(mid 0.249642 -0.249642)
							(end 0.1778 -0.2794)
						)
					)
					(width 0)
					(fill yes)
				)
			)
		)
		(pad "2" smd custom
			(at 0 0.4445 180)
			(size 0.1397 0.1397)
			(layers "F.Cu" "F.Mask" "F.Paste")
			(net "ADM1276_GATE_RSV")
			(options
				(clearance outline)
				(anchor circle)
			)
			(primitives
				(gr_poly
					(pts
						(arc
							(start -0.1778 -0.2794)
							(mid -0.249642 -0.249642)
							(end -0.2794 -0.1778)
						)
						(arc
							(start -0.2794 0.1778)
							(mid -0.249642 0.249642)
							(end -0.1778 0.2794)
						)
						(arc
							(start 0.1778 0.2794)
							(mid 0.249642 0.249642)
							(end 0.2794 0.1778)
						)
						(arc
							(start 0.2794 -0.1778)
							(mid 0.249642 -0.249642)
							(end 0.1778 -0.2794)
						)
					)
					(width 0)
					(fill yes)
				)
			)
		)
	)
	(footprint ""
		(layer "F.Cu")
		(at 38.6334 -254.381)
		(property "Reference" "R58"
			(at 0 0 0)
			(layer "F.SilkS")
			(hide yes)
			(effects
				(font
					(size 1.27 1.27)
				)
			)
		)
		(property "Value" "330R2J-3-GP"
			(at 0.064008 -3.993896 0)
			(unlocked yes)
			(layer "F.Fab")
			(hide yes)
			(effects
				(font
					(size 1.016 1.016)
					(thickness 0.1524)
				)
			)
		)
		(property "Device Type" "R402H16"
			(at 0.064008 -5.517896 0)
			(unlocked yes)
			(layer "F.Fab")
			(hide yes)
			(effects
				(font
					(size 1.016 1.016)
					(thickness 0.1524)
				)
			)
		)
		(duplicate_pad_numbers_are_jumpers no)
		(fp_line
			(start -0.508 -0.9398)
			(end -0.508 0.9398)
			(stroke
				(width 0.1524)
				(type default)
			)
			(layer "F.SilkS")
		)
		(fp_line
			(start 0.508 -0.9398)
			(end -0.508 -0.9398)
			(stroke
				(width 0.1524)
				(type default)
			)
			(layer "F.SilkS")
		)
		(fp_rect
			(start -0.508 0.9398)
			(end 0.508 -0.9398)
			(stroke
				(width 0)
				(type default)
			)
			(fill no)
			(layer "F.CrtYd")
		)
		(fp_rect
			(start -0.508 0.9398)
			(end 0.508 -0.9398)
			(stroke
				(width 0)
				(type default)
			)
			(fill no)
			(layer "F.Fab")
		)
		(pad "1" smd custom
			(at 0 -0.4445)
			(size 0.1397 0.1397)
			(layers "F.Cu" "F.Mask" "F.Paste")
			(net "P3V3")
			(options
				(clearance outline)
				(anchor circle)
			)
			(primitives
				(gr_poly
					(pts
						(arc
							(start -0.1778 -0.2794)
							(mid -0.249642 -0.249642)
							(end -0.2794 -0.1778)
						)
						(arc
							(start -0.2794 0.1778)
							(mid -0.249642 0.249642)
							(end -0.1778 0.2794)
						)
						(arc
							(start 0.1778 0.2794)
							(mid 0.249642 0.249642)
							(end 0.2794 0.1778)
						)
						(arc
							(start 0.2794 -0.1778)
							(mid 0.249642 -0.249642)
							(end 0.1778 -0.2794)
						)
					)
					(width 0)
					(fill yes)
				)
			)
		)
		(pad "2" smd custom
			(at 0 0.4445)
			(size 0.1397 0.1397)
			(layers "F.Cu" "F.Mask" "F.Paste")
			(net "LED_DR_LED6_RESERVE")
			(options
				(clearance outline)
				(anchor circle)
			)
			(primitives
				(gr_poly
					(pts
						(arc
							(start -0.1778 -0.2794)
							(mid -0.249642 -0.249642)
							(end -0.2794 -0.1778)
						)
						(arc
							(start -0.2794 0.1778)
							(mid -0.249642 0.249642)
							(end -0.1778 0.2794)
						)
						(arc
							(start 0.1778 0.2794)
							(mid 0.249642 0.249642)
							(end 0.2794 0.1778)
						)
						(arc
							(start 0.2794 -0.1778)
							(mid 0.249642 -0.249642)
							(end 0.1778 -0.2794)
						)
					)
					(width 0)
					(fill yes)
				)
			)
		)
	)
	(footprint ""
		(layer "F.Cu")
		(at 38.5572 -109.4232 -90)
		(property "Reference" "PR103"
			(at 0 0 270)
			(layer "F.SilkS")
			(hide yes)
			(effects
				(font
					(size 1.27 1.27)
				)
			)
		)
		(property "Value" "10R2F-L-GP"
			(at 0.064008 -3.993896 270)
			(unlocked yes)
			(layer "F.Fab")
			(hide yes)
			(effects
				(font
					(size 1.016 1.016)
					(thickness 0.1524)
				)
			)
		)
		(property "Device Type" "R402H14"
			(at 0.064008 -5.517896 270)
			(unlocked yes)
			(layer "F.Fab")
			(hide yes)
			(effects
				(font
					(size 1.016 1.016)
					(thickness 0.1524)
				)
			)
		)
		(duplicate_pad_numbers_are_jumpers no)
		(fp_line
			(start -0.508 -0.9398)
			(end -0.508 0.9398)
			(stroke
				(width 0.1524)
				(type default)
			)
			(layer "F.SilkS")
		)
		(fp_line
			(start 0.508 -0.9398)
			(end -0.508 -0.9398)
			(stroke
				(width 0.1524)
				(type default)
			)
			(layer "F.SilkS")
		)
		(fp_rect
			(start -0.508 0.9398)
			(end 0.508 -0.9398)
			(stroke
				(width 0)
				(type default)
			)
			(fill no)
			(layer "F.CrtYd")
		)
		(fp_rect
			(start -0.508 0.9398)
			(end 0.508 -0.9398)
			(stroke
				(width 0)
				(type default)
			)
			(fill no)
			(layer "F.Fab")
		)
		(pad "1" smd custom
			(at 0 -0.4445 270)
			(size 0.1397 0.1397)
			(layers "F.Cu" "F.Mask" "F.Paste")
			(net "P12VL_2490_GATE_DRV")
			(options
				(clearance outline)
				(anchor circle)
			)
			(primitives
				(gr_poly
					(pts
						(arc
							(start -0.1778 -0.2794)
							(mid -0.249642 -0.249642)
							(end -0.2794 -0.1778)
						)
						(arc
							(start -0.2794 0.1778)
							(mid -0.249642 0.249642)
							(end -0.1778 0.2794)
						)
						(arc
							(start 0.1778 0.2794)
							(mid 0.249642 0.249642)
							(end 0.2794 0.1778)
						)
						(arc
							(start 0.2794 -0.1778)
							(mid 0.249642 -0.249642)
							(end 0.1778 -0.2794)
						)
					)
					(width 0)
					(fill yes)
				)
			)
		)
		(pad "2" smd custom
			(at 0 0.4445 270)
			(size 0.1397 0.1397)
			(layers "F.Cu" "F.Mask" "F.Paste")
			(net "P12VL_2490_GATE")
			(options
				(clearance outline)
				(anchor circle)
			)
			(primitives
				(gr_poly
					(pts
						(arc
							(start -0.1778 -0.2794)
							(mid -0.249642 -0.249642)
							(end -0.2794 -0.1778)
						)
						(arc
							(start -0.2794 0.1778)
							(mid -0.249642 0.249642)
							(end -0.1778 0.2794)
						)
						(arc
							(start 0.1778 0.2794)
							(mid 0.249642 0.249642)
							(end 0.2794 0.1778)
						)
						(arc
							(start 0.2794 -0.1778)
							(mid 0.249642 -0.249642)
							(end 0.1778 -0.2794)
						)
					)
					(width 0)
					(fill yes)
				)
			)
		)
	)
	(footprint ""
		(layer "F.Cu")
		(at 29.718 -381 180)
		(property "Reference" "PR19"
			(at 0 0 180)
			(layer "F.SilkS")
			(hide yes)
			(effects
				(font
					(size 1.27 1.27)
				)
			)
		)
		(property "Value" "10R2F-L-GP"
			(at 0.064008 -3.993896 180)
			(unlocked yes)
			(layer "F.Fab")
			(hide yes)
			(effects
				(font
					(size 1.016 1.016)
					(thickness 0.1524)
				)
			)
		)
		(property "Device Type" "R402H14"
			(at 0.064008 -5.517896 180)
			(unlocked yes)
			(layer "F.Fab")
			(hide yes)
			(effects
				(font
					(size 1.016 1.016)
					(thickness 0.1524)
				)
			)
		)
		(duplicate_pad_numbers_are_jumpers no)
		(fp_line
			(start 0.508 -0.9398)
			(end -0.508 -0.9398)
			(stroke
				(width 0.1524)
				(type default)
			)
			(layer "F.SilkS")
		)
		(fp_line
			(start -0.508 -0.9398)
			(end -0.508 0.9398)
			(stroke
				(width 0.1524)
				(type default)
			)
			(layer "F.SilkS")
		)
		(fp_rect
			(start -0.508 0.9398)
			(end 0.508 -0.9398)
			(stroke
				(width 0)
				(type default)
			)
			(fill no)
			(layer "F.CrtYd")
		)
		(fp_rect
			(start -0.508 0.9398)
			(end 0.508 -0.9398)
			(stroke
				(width 0)
				(type default)
			)
			(fill no)
			(layer "F.Fab")
		)
		(pad "1" smd custom
			(at 0 -0.4445 180)
			(size 0.1397 0.1397)
			(layers "F.Cu" "F.Mask" "F.Paste")
			(net "ADM1276_SENSE+")
			(options
				(clearance outline)
				(anchor circle)
			)
			(primitives
				(gr_poly
					(pts
						(arc
							(start -0.1778 -0.2794)
							(mid -0.249642 -0.249642)
							(end -0.2794 -0.1778)
						)
						(arc
							(start -0.2794 0.1778)
							(mid -0.249642 0.249642)
							(end -0.1778 0.2794)
						)
						(arc
							(start 0.1778 0.2794)
							(mid 0.249642 0.249642)
							(end 0.2794 0.1778)
						)
						(arc
							(start 0.2794 -0.1778)
							(mid 0.249642 -0.249642)
							(end 0.1778 -0.2794)
						)
					)
					(width 0)
					(fill yes)
				)
			)
		)
		(pad "2" smd custom
			(at 0 0.4445 180)
			(size 0.1397 0.1397)
			(layers "F.Cu" "F.Mask" "F.Paste")
			(net "SENSE+_R2")
			(options
				(clearance outline)
				(anchor circle)
			)
			(primitives
				(gr_poly
					(pts
						(arc
							(start -0.1778 -0.2794)
							(mid -0.249642 -0.249642)
							(end -0.2794 -0.1778)
						)
						(arc
							(start -0.2794 0.1778)
							(mid -0.249642 0.249642)
							(end -0.1778 0.2794)
						)
						(arc
							(start 0.1778 0.2794)
							(mid 0.249642 0.249642)
							(end 0.2794 0.1778)
						)
						(arc
							(start 0.2794 -0.1778)
							(mid 0.249642 -0.249642)
							(end 0.1778 -0.2794)
						)
					)
					(width 0)
					(fill yes)
				)
			)
		)
	)
	(footprint ""
		(layer "F.Cu")
		(at 7.949946 -232.134918 -90)
		(property "Reference" "LED4"
			(at 0 0 270)
			(layer "F.SilkS")
			(hide yes)
			(effects
				(font
					(size 1.27 1.27)
				)
			)
		)
		(property "Value" "LED-RB-6-GP"
			(at -4.6736 3.8354 270)
			(unlocked yes)
			(layer "F.Fab")
			(hide yes)
			(effects
				(font
					(size 1.016 1.016)
					(thickness 0.1524)
				)
			)
		)
		(property "Device Type" "LED-100-3P-067106H325"
			(at -4.6736 2.3114 270)
			(unlocked yes)
			(layer "F.Fab")
			(hide yes)
			(effects
				(font
					(size 1.016 1.016)
					(thickness 0.1524)
				)
			)
		)
		(duplicate_pad_numbers_are_jumpers no)
		(fp_line
			(start -1.7526 10.414)
			(end -1.7526 6.6548)
			(stroke
				(width 0.1524)
				(type default)
			)
			(layer "F.SilkS")
		)
		(fp_line
			(start 1.7526 10.414)
			(end -1.7526 10.414)
			(stroke
				(width 0.1524)
				(type default)
			)
			(layer "F.SilkS")
		)
		(fp_line
			(start -3.6068 6.6548)
			(end -3.6068 -0.889)
			(stroke
				(width 0.1524)
				(type default)
			)
			(layer "F.SilkS")
		)
		(fp_line
			(start -1.7526 6.6548)
			(end -3.6068 6.6548)
			(stroke
				(width 0.1524)
				(type default)
			)
			(layer "F.SilkS")
		)
		(fp_line
			(start 1.7526 6.6548)
			(end 1.7526 10.414)
			(stroke
				(width 0.1524)
				(type default)
			)
			(layer "F.SilkS")
		)
		(fp_line
			(start 3.6068 6.6548)
			(end 1.7526 6.6548)
			(stroke
				(width 0.1524)
				(type default)
			)
			(layer "F.SilkS")
		)
		(fp_line
			(start -3.6068 -0.889)
			(end 3.6068 -0.889)
			(stroke
				(width 0.1524)
				(type default)
			)
			(layer "F.SilkS")
		)
		(fp_line
			(start 3.6068 -0.889)
			(end 3.6068 6.6548)
			(stroke
				(width 0.1524)
				(type default)
			)
			(layer "F.SilkS")
		)
		(fp_circle
			(center -2.54 0)
			(end -2.54 -0.9906)
			(stroke
				(width 0.3048)
				(type default)
			)
			(fill no)
			(layer "F.SilkS")
		)
		(fp_circle
			(center 0 0)
			(end 0 -0.9906)
			(stroke
				(width 0.3048)
				(type default)
			)
			(fill no)
			(layer "F.SilkS")
		)
		(fp_circle
			(center 2.54 0)
			(end 2.54 -0.9906)
			(stroke
				(width 0.3048)
				(type default)
			)
			(fill no)
			(layer "F.SilkS")
		)
		(fp_poly
			(pts
				(xy -1.4986 10.1473) (xy -1.4986 6.4008) (xy -3.3528 6.4008) (xy -3.3528 -0.3937) (xy 3.3528 -0.3937)
				(xy 3.3528 6.4008) (xy 1.4986 6.4008) (xy 1.4986 10.1473)
			)
			(stroke
				(width 0)
				(type default)
			)
			(fill no)
			(layer "F.CrtYd")
		)
		(fp_poly
			(pts
				(xy -2.0066 10.668) (xy 2.0066 10.668) (xy 2.0066 6.9088) (xy 3.8608 6.9088) (xy 3.8608 2.2098)
				(xy 3.3528 2.2098) (xy 3.3528 6.4008) (xy 1.4986 6.4008) (xy 1.4986 10.1473) (xy -1.4986 10.1473)
				(xy -1.4986 6.4008) (xy -3.3528 6.4008) (xy -3.3528 -0.3937) (xy 3.3528 -0.3937) (xy 3.3528 2.1971)
				(xy 3.8608 2.1971) (xy 3.8608 -1.143) (xy -3.8608 -1.143) (xy -3.8608 6.9088) (xy -2.0066 6.9088)
			)
			(stroke
				(width 0)
				(type default)
			)
			(fill no)
			(layer "F.CrtYd")
		)
		(fp_poly
			(pts
				(xy -2.0066 10.668) (xy -2.0066 6.9088) (xy -3.8608 6.9088) (xy -3.8608 -1.143) (xy 3.8608 -1.143)
				(xy 3.8608 6.9088) (xy 2.0066 6.9088) (xy 2.0066 10.668)
			)
			(stroke
				(width 0)
				(type default)
			)
			(fill no)
			(layer "F.Fab")
		)
		(pad "1" thru_hole circle
			(at 2.54 0 270)
			(size 1.27 1.27)
			(drill 0.889)
			(layers "*.Cu" "*.Mask")
			(remove_unused_layers no)
			(net "LED_DR_LED3_BLUE")
			(clearance 0.1651)
			(thermal_gap 0.1651)
		)
		(pad "2" thru_hole circle
			(at 0 0 270)
			(size 1.27 1.27)
			(drill 0.889)
			(layers "*.Cu" "*.Mask")
			(remove_unused_layers no)
			(net "LED_DR_LED3_K")
			(clearance 0.1651)
			(thermal_gap 0.1651)
		)
		(pad "3" thru_hole circle
			(at -2.54 0 270)
			(size 1.27 1.27)
			(drill 0.889)
			(layers "*.Cu" "*.Mask")
			(remove_unused_layers no)
			(net "LED_DR_LED3")
			(clearance 0.1651)
			(thermal_gap 0.1651)
		)
	)
	(footprint ""
		(layer "F.Cu")
		(at 17.6276 -290.703 -90)
		(property "Reference" "C43"
			(at 0 0 270)
			(layer "F.SilkS")
			(hide yes)
			(effects
				(font
					(size 1.27 1.27)
				)
			)
		)
		(property "Value" "SCD1U16V2KX-3GP"
			(at 1.1811 -2.7051 270)
			(unlocked yes)
			(layer "F.Fab")
			(hide yes)
			(effects
				(font
					(size 1.016 1.016)
					(thickness 0.1524)
				)
			)
		)
		(property "Device Type" "C402H22"
			(at 1.1811 -4.2291 270)
			(unlocked yes)
			(layer "F.Fab")
			(hide yes)
			(effects
				(font
					(size 1.016 1.016)
					(thickness 0.1524)
				)
			)
		)
		(duplicate_pad_numbers_are_jumpers no)
		(fp_rect
			(start -0.4318 0.9525)
			(end 0.4318 -0.9525)
			(stroke
				(width 0)
				(type default)
			)
			(fill no)
			(layer "F.CrtYd")
		)
		(fp_rect
			(start -0.4318 0.9525)
			(end 0.4318 -0.9525)
			(stroke
				(width 0)
				(type default)
			)
			(fill no)
			(layer "F.Fab")
		)
		(pad "1" smd custom
			(at 0 -0.4445 270)
			(size 0.1524 0.1524)
			(layers "F.Cu" "F.Mask" "F.Paste")
			(net "FAN_TACH3")
			(options
				(clearance outline)
				(anchor circle)
			)
			(primitives
				(gr_poly
					(pts
						(arc
							(start 0.3048 -0.2032)
							(mid 0.275042 -0.275042)
							(end 0.2032 -0.3048)
						)
						(arc
							(start -0.2032 -0.3048)
							(mid -0.275042 -0.275042)
							(end -0.3048 -0.2032)
						)
						(arc
							(start -0.3048 0.2032)
							(mid -0.275042 0.275042)
							(end -0.2032 0.3048)
						)
						(arc
							(start 0.2032 0.3048)
							(mid 0.275042 0.275042)
							(end 0.3048 0.2032)
						)
					)
					(width 0)
					(fill yes)
				)
			)
		)
		(pad "2" smd custom
			(at 0 0.4445 270)
			(size 0.1524 0.1524)
			(layers "F.Cu" "F.Mask" "F.Paste")
			(net "GND")
			(options
				(clearance outline)
				(anchor circle)
			)
			(primitives
				(gr_poly
					(pts
						(arc
							(start 0.3048 -0.2032)
							(mid 0.275042 -0.275042)
							(end 0.2032 -0.3048)
						)
						(arc
							(start -0.2032 -0.3048)
							(mid -0.275042 -0.275042)
							(end -0.3048 -0.2032)
						)
						(arc
							(start -0.3048 0.2032)
							(mid -0.275042 0.275042)
							(end -0.2032 0.3048)
						)
						(arc
							(start 0.2032 0.3048)
							(mid 0.275042 0.275042)
							(end 0.3048 0.2032)
						)
					)
					(width 0)
					(fill yes)
				)
			)
		)
	)
	(footprint ""
		(layer "F.Cu")
		(at 38.989 -144.3482 180)
		(property "Reference" "PR113"
			(at 0 0 180)
			(layer "F.SilkS")
			(hide yes)
			(effects
				(font
					(size 1.27 1.27)
				)
			)
		)
		(property "Value" "6K81R2F-1-GP"
			(at 0.064008 -3.993896 180)
			(unlocked yes)
			(layer "F.Fab")
			(hide yes)
			(effects
				(font
					(size 1.016 1.016)
					(thickness 0.1524)
				)
			)
		)
		(property "Device Type" "R402H16"
			(at 0.064008 -5.517896 180)
			(unlocked yes)
			(layer "F.Fab")
			(hide yes)
			(effects
				(font
					(size 1.016 1.016)
					(thickness 0.1524)
				)
			)
		)
		(duplicate_pad_numbers_are_jumpers no)
		(fp_line
			(start 0.508 -0.9398)
			(end -0.508 -0.9398)
			(stroke
				(width 0.1524)
				(type default)
			)
			(layer "F.SilkS")
		)
		(fp_line
			(start -0.508 -0.9398)
			(end -0.508 0.9398)
			(stroke
				(width 0.1524)
				(type default)
			)
			(layer "F.SilkS")
		)
		(fp_rect
			(start -0.508 0.9398)
			(end 0.508 -0.9398)
			(stroke
				(width 0)
				(type default)
			)
			(fill no)
			(layer "F.CrtYd")
		)
		(fp_rect
			(start -0.508 0.9398)
			(end 0.508 -0.9398)
			(stroke
				(width 0)
				(type default)
			)
			(fill no)
			(layer "F.Fab")
		)
		(pad "1" smd custom
			(at 0 -0.4445 180)
			(size 0.1397 0.1397)
			(layers "F.Cu" "F.Mask" "F.Paste")
			(net "P12VL_2490_EN_2")
			(options
				(clearance outline)
				(anchor circle)
			)
			(primitives
				(gr_poly
					(pts
						(arc
							(start -0.1778 -0.2794)
							(mid -0.249642 -0.249642)
							(end -0.2794 -0.1778)
						)
						(arc
							(start -0.2794 0.1778)
							(mid -0.249642 0.249642)
							(end -0.1778 0.2794)
						)
						(arc
							(start 0.1778 0.2794)
							(mid 0.249642 0.249642)
							(end 0.2794 0.1778)
						)
						(arc
							(start 0.2794 -0.1778)
							(mid 0.249642 -0.249642)
							(end 0.1778 -0.2794)
						)
					)
					(width 0)
					(fill yes)
				)
			)
		)
		(pad "2" smd custom
			(at 0 0.4445 180)
			(size 0.1397 0.1397)
			(layers "F.Cu" "F.Mask" "F.Paste")
			(net "GND")
			(options
				(clearance outline)
				(anchor circle)
			)
			(primitives
				(gr_poly
					(pts
						(arc
							(start -0.1778 -0.2794)
							(mid -0.249642 -0.249642)
							(end -0.2794 -0.1778)
						)
						(arc
							(start -0.2794 0.1778)
							(mid -0.249642 0.249642)
							(end -0.1778 0.2794)
						)
						(arc
							(start 0.1778 0.2794)
							(mid 0.249642 0.249642)
							(end 0.2794 0.1778)
						)
						(arc
							(start 0.2794 -0.1778)
							(mid 0.249642 -0.249642)
							(end 0.1778 -0.2794)
						)
					)
					(width 0)
					(fill yes)
				)
			)
		)
	)
	(footprint ""
		(layer "F.Cu")
		(at 37.846 -240.665 180)
		(property "Reference" "R157"
			(at 0 0 180)
			(layer "F.SilkS")
			(hide yes)
			(effects
				(font
					(size 1.27 1.27)
				)
			)
		)
		(property "Value" "330R2J-3-GP"
			(at 0.064008 -3.993896 180)
			(unlocked yes)
			(layer "F.Fab")
			(hide yes)
			(effects
				(font
					(size 1.016 1.016)
					(thickness 0.1524)
				)
			)
		)
		(property "Device Type" "R402H16"
			(at 0.064008 -5.517896 180)
			(unlocked yes)
			(layer "F.Fab")
			(hide yes)
			(effects
				(font
					(size 1.016 1.016)
					(thickness 0.1524)
				)
			)
		)
		(duplicate_pad_numbers_are_jumpers no)
		(fp_line
			(start 0.508 -0.9398)
			(end -0.508 -0.9398)
			(stroke
				(width 0.1524)
				(type default)
			)
			(layer "F.SilkS")
		)
		(fp_line
			(start -0.508 -0.9398)
			(end -0.508 0.9398)
			(stroke
				(width 0.1524)
				(type default)
			)
			(layer "F.SilkS")
		)
		(fp_rect
			(start -0.508 0.9398)
			(end 0.508 -0.9398)
			(stroke
				(width 0)
				(type default)
			)
			(fill no)
			(layer "F.CrtYd")
		)
		(fp_rect
			(start -0.508 0.9398)
			(end 0.508 -0.9398)
			(stroke
				(width 0)
				(type default)
			)
			(fill no)
			(layer "F.Fab")
		)
		(pad "1" smd custom
			(at 0 -0.4445 180)
			(size 0.1397 0.1397)
			(layers "F.Cu" "F.Mask" "F.Paste")
			(net "P3V3")
			(options
				(clearance outline)
				(anchor circle)
			)
			(primitives
				(gr_poly
					(pts
						(arc
							(start -0.1778 -0.2794)
							(mid -0.249642 -0.249642)
							(end -0.2794 -0.1778)
						)
						(arc
							(start -0.2794 0.1778)
							(mid -0.249642 0.249642)
							(end -0.1778 0.2794)
						)
						(arc
							(start 0.1778 0.2794)
							(mid 0.249642 0.249642)
							(end 0.2794 0.1778)
						)
						(arc
							(start 0.2794 -0.1778)
							(mid 0.249642 -0.249642)
							(end 0.1778 -0.2794)
						)
					)
					(width 0)
					(fill yes)
				)
			)
		)
		(pad "2" smd custom
			(at 0 0.4445 180)
			(size 0.1397 0.1397)
			(layers "F.Cu" "F.Mask" "F.Paste")
			(net "LED_DR_LED1")
			(options
				(clearance outline)
				(anchor circle)
			)
			(primitives
				(gr_poly
					(pts
						(arc
							(start -0.1778 -0.2794)
							(mid -0.249642 -0.249642)
							(end -0.2794 -0.1778)
						)
						(arc
							(start -0.2794 0.1778)
							(mid -0.249642 0.249642)
							(end -0.1778 0.2794)
						)
						(arc
							(start 0.1778 0.2794)
							(mid 0.249642 0.249642)
							(end 0.2794 0.1778)
						)
						(arc
							(start 0.2794 -0.1778)
							(mid 0.249642 -0.249642)
							(end 0.1778 -0.2794)
						)
					)
					(width 0)
					(fill yes)
				)
			)
		)
	)
	(footprint ""
		(layer "F.Cu")
		(at 9.9568 -87.757)
		(property "Reference" "R30"
			(at 0 0 0)
			(layer "F.SilkS")
			(hide yes)
			(effects
				(font
					(size 1.27 1.27)
				)
			)
		)
		(property "Value" "0R2J-2-GP"
			(at 0.064008 -3.993896 0)
			(unlocked yes)
			(layer "F.Fab")
			(hide yes)
			(effects
				(font
					(size 1.016 1.016)
					(thickness 0.1524)
				)
			)
		)
		(property "Device Type" "R402H16"
			(at 0.064008 -5.517896 0)
			(unlocked yes)
			(layer "F.Fab")
			(hide yes)
			(effects
				(font
					(size 1.016 1.016)
					(thickness 0.1524)
				)
			)
		)
		(duplicate_pad_numbers_are_jumpers no)
		(fp_line
			(start -0.508 -0.9398)
			(end -0.508 0.9398)
			(stroke
				(width 0.1524)
				(type default)
			)
			(layer "F.SilkS")
		)
		(fp_line
			(start 0.508 -0.9398)
			(end -0.508 -0.9398)
			(stroke
				(width 0.1524)
				(type default)
			)
			(layer "F.SilkS")
		)
		(fp_rect
			(start -0.508 0.9398)
			(end 0.508 -0.9398)
			(stroke
				(width 0)
				(type default)
			)
			(fill no)
			(layer "F.CrtYd")
		)
		(fp_rect
			(start -0.508 0.9398)
			(end 0.508 -0.9398)
			(stroke
				(width 0)
				(type default)
			)
			(fill no)
			(layer "F.Fab")
		)
		(pad "1" smd custom
			(at 0 -0.4445)
			(size 0.1397 0.1397)
			(layers "F.Cu" "F.Mask" "F.Paste")
			(net "LED_DR_LED4_K")
			(options
				(clearance outline)
				(anchor circle)
			)
			(primitives
				(gr_poly
					(pts
						(arc
							(start -0.1778 -0.2794)
							(mid -0.249642 -0.249642)
							(end -0.2794 -0.1778)
						)
						(arc
							(start -0.2794 0.1778)
							(mid -0.249642 0.249642)
							(end -0.1778 0.2794)
						)
						(arc
							(start 0.1778 0.2794)
							(mid 0.249642 0.249642)
							(end 0.2794 0.1778)
						)
						(arc
							(start 0.2794 -0.1778)
							(mid 0.249642 -0.249642)
							(end 0.1778 -0.2794)
						)
					)
					(width 0)
					(fill yes)
				)
			)
		)
		(pad "2" smd custom
			(at 0 0.4445)
			(size 0.1397 0.1397)
			(layers "F.Cu" "F.Mask" "F.Paste")
			(net "GND")
			(options
				(clearance outline)
				(anchor circle)
			)
			(primitives
				(gr_poly
					(pts
						(arc
							(start -0.1778 -0.2794)
							(mid -0.249642 -0.249642)
							(end -0.2794 -0.1778)
						)
						(arc
							(start -0.2794 0.1778)
							(mid -0.249642 0.249642)
							(end -0.1778 0.2794)
						)
						(arc
							(start 0.1778 0.2794)
							(mid 0.249642 0.249642)
							(end 0.2794 0.1778)
						)
						(arc
							(start 0.2794 -0.1778)
							(mid 0.249642 -0.249642)
							(end 0.1778 -0.2794)
						)
					)
					(width 0)
					(fill yes)
				)
			)
		)
	)
	(footprint ""
		(layer "F.Cu")
		(at 31.3182 -253.8984 180)
		(property "Reference" "R47"
			(at 0 0 180)
			(layer "F.SilkS")
			(hide yes)
			(effects
				(font
					(size 1.27 1.27)
				)
			)
		)
		(property "Value" "0R2J-2-GP"
			(at 0.064008 -3.993896 180)
			(unlocked yes)
			(layer "F.Fab")
			(hide yes)
			(effects
				(font
					(size 1.016 1.016)
					(thickness 0.1524)
				)
			)
		)
		(property "Device Type" "R402H16"
			(at 0.064008 -5.517896 180)
			(unlocked yes)
			(layer "F.Fab")
			(hide yes)
			(effects
				(font
					(size 1.016 1.016)
					(thickness 0.1524)
				)
			)
		)
		(duplicate_pad_numbers_are_jumpers no)
		(fp_line
			(start 0.508 -0.9398)
			(end -0.508 -0.9398)
			(stroke
				(width 0.1524)
				(type default)
			)
			(layer "F.SilkS")
		)
		(fp_line
			(start -0.508 -0.9398)
			(end -0.508 0.9398)
			(stroke
				(width 0.1524)
				(type default)
			)
			(layer "F.SilkS")
		)
		(fp_rect
			(start -0.508 0.9398)
			(end 0.508 -0.9398)
			(stroke
				(width 0)
				(type default)
			)
			(fill no)
			(layer "F.CrtYd")
		)
		(fp_rect
			(start -0.508 0.9398)
			(end 0.508 -0.9398)
			(stroke
				(width 0)
				(type default)
			)
			(fill no)
			(layer "F.Fab")
		)
		(pad "1" smd custom
			(at 0 -0.4445 180)
			(size 0.1397 0.1397)
			(layers "F.Cu" "F.Mask" "F.Paste")
			(net "I2C_C_SDA_EEPROM")
			(options
				(clearance outline)
				(anchor circle)
			)
			(primitives
				(gr_poly
					(pts
						(arc
							(start -0.1778 -0.2794)
							(mid -0.249642 -0.249642)
							(end -0.2794 -0.1778)
						)
						(arc
							(start -0.2794 0.1778)
							(mid -0.249642 0.249642)
							(end -0.1778 0.2794)
						)
						(arc
							(start 0.1778 0.2794)
							(mid 0.249642 0.249642)
							(end 0.2794 0.1778)
						)
						(arc
							(start 0.2794 -0.1778)
							(mid 0.249642 -0.249642)
							(end 0.1778 -0.2794)
						)
					)
					(width 0)
					(fill yes)
				)
			)
		)
		(pad "2" smd custom
			(at 0 0.4445 180)
			(size 0.1397 0.1397)
			(layers "F.Cu" "F.Mask" "F.Paste")
			(net "I2C_C_SDA")
			(options
				(clearance outline)
				(anchor circle)
			)
			(primitives
				(gr_poly
					(pts
						(arc
							(start -0.1778 -0.2794)
							(mid -0.249642 -0.249642)
							(end -0.2794 -0.1778)
						)
						(arc
							(start -0.2794 0.1778)
							(mid -0.249642 0.249642)
							(end -0.1778 0.2794)
						)
						(arc
							(start 0.1778 0.2794)
							(mid 0.249642 0.249642)
							(end 0.2794 0.1778)
						)
						(arc
							(start 0.2794 -0.1778)
							(mid 0.249642 -0.249642)
							(end 0.1778 -0.2794)
						)
					)
					(width 0)
					(fill yes)
				)
			)
		)
	)
	(footprint ""
		(layer "F.Cu")
		(at 39.064184 -359.41 90)
		(property "Reference" "PR58"
			(at 0 0 90)
			(layer "F.SilkS")
			(hide yes)
			(effects
				(font
					(size 1.27 1.27)
				)
			)
		)
		(property "Value" "10KR2F-2-GP"
			(at 0.064008 -3.993896 90)
			(unlocked yes)
			(layer "F.Fab")
			(hide yes)
			(effects
				(font
					(size 1.016 1.016)
					(thickness 0.1524)
				)
			)
		)
		(property "Device Type" "R402H16"
			(at 0.064008 -5.517896 90)
			(unlocked yes)
			(layer "F.Fab")
			(hide yes)
			(effects
				(font
					(size 1.016 1.016)
					(thickness 0.1524)
				)
			)
		)
		(duplicate_pad_numbers_are_jumpers no)
		(fp_line
			(start 0.508 -0.9398)
			(end -0.508 -0.9398)
			(stroke
				(width 0.1524)
				(type default)
			)
			(layer "F.SilkS")
		)
		(fp_line
			(start -0.508 -0.9398)
			(end -0.508 0.9398)
			(stroke
				(width 0.1524)
				(type default)
			)
			(layer "F.SilkS")
		)
		(fp_rect
			(start -0.508 0.9398)
			(end 0.508 -0.9398)
			(stroke
				(width 0)
				(type default)
			)
			(fill no)
			(layer "F.CrtYd")
		)
		(fp_rect
			(start -0.508 0.9398)
			(end 0.508 -0.9398)
			(stroke
				(width 0)
				(type default)
			)
			(fill no)
			(layer "F.Fab")
		)
		(pad "1" smd custom
			(at 0 -0.4445 90)
			(size 0.1397 0.1397)
			(layers "F.Cu" "F.Mask" "F.Paste")
			(net "P12V_AUX")
			(options
				(clearance outline)
				(anchor circle)
			)
			(primitives
				(gr_poly
					(pts
						(arc
							(start -0.1778 -0.2794)
							(mid -0.249642 -0.249642)
							(end -0.2794 -0.1778)
						)
						(arc
							(start -0.2794 0.1778)
							(mid -0.249642 0.249642)
							(end -0.1778 0.2794)
						)
						(arc
							(start 0.1778 0.2794)
							(mid 0.249642 0.249642)
							(end 0.2794 0.1778)
						)
						(arc
							(start 0.2794 -0.1778)
							(mid 0.249642 -0.249642)
							(end 0.1778 -0.2794)
						)
					)
					(width 0)
					(fill yes)
				)
			)
		)
		(pad "2" smd custom
			(at 0 0.4445 90)
			(size 0.1397 0.1397)
			(layers "F.Cu" "F.Mask" "F.Paste")
			(net "OTP_RETRY_C")
			(options
				(clearance outline)
				(anchor circle)
			)
			(primitives
				(gr_poly
					(pts
						(arc
							(start -0.1778 -0.2794)
							(mid -0.249642 -0.249642)
							(end -0.2794 -0.1778)
						)
						(arc
							(start -0.2794 0.1778)
							(mid -0.249642 0.249642)
							(end -0.1778 0.2794)
						)
						(arc
							(start 0.1778 0.2794)
							(mid 0.249642 0.249642)
							(end 0.2794 0.1778)
						)
						(arc
							(start 0.2794 -0.1778)
							(mid 0.249642 -0.249642)
							(end 0.1778 -0.2794)
						)
					)
					(width 0)
					(fill yes)
				)
			)
		)
	)
	(footprint ""
		(layer "F.Cu")
		(at 37.465 -366.014 180)
		(property "Reference" "PQ4"
			(at 0 0 180)
			(layer "F.SilkS")
			(hide yes)
			(effects
				(font
					(size 1.27 1.27)
				)
			)
		)
		(property "Value" "MMBT3906-3-GP"
			(at 0.10287 -10.29843 180)
			(unlocked yes)
			(layer "F.Fab")
			(hide yes)
			(effects
				(font
					(size 1.016 1.016)
					(thickness 0.1524)
				)
			)
		)
		(property "Device Type" "SOT23CBE2D4H44"
			(at 0.10287 -12.20343 180)
			(unlocked yes)
			(layer "F.Fab")
			(hide yes)
			(effects
				(font
					(size 1.016 1.016)
					(thickness 0.1524)
				)
			)
		)
		(duplicate_pad_numbers_are_jumpers no)
		(fp_line
			(start 1.651 1.778)
			(end 1.651 -1.778)
			(stroke
				(width 0.1524)
				(type default)
			)
			(layer "F.SilkS")
		)
		(fp_line
			(start 1.651 -1.778)
			(end -1.651 -1.778)
			(stroke
				(width 0.1524)
				(type default)
			)
			(layer "F.SilkS")
		)
		(fp_line
			(start -1.651 1.778)
			(end 1.651 1.778)
			(stroke
				(width 0.1524)
				(type default)
			)
			(layer "F.SilkS")
		)
		(fp_line
			(start -1.651 -1.778)
			(end -1.651 1.778)
			(stroke
				(width 0.1524)
				(type default)
			)
			(layer "F.SilkS")
		)
		(fp_poly
			(pts
				(xy -1.778 1.8796) (xy -1.778 -1.8796) (xy 1.778 -1.8796) (xy 1.778 1.8796)
			)
			(stroke
				(width 0)
				(type default)
			)
			(fill no)
			(layer "F.CrtYd")
		)
		(fp_poly
			(pts
				(xy -1.778 1.8796) (xy -1.778 -1.8796) (xy 1.778 -1.8796) (xy 1.778 1.8796)
			)
			(stroke
				(width 0)
				(type default)
			)
			(fill no)
			(layer "F.Fab")
		)
		(pad "B" smd custom
			(at -0.98425 0.9525 180)
			(size 0.1905 0.1905)
			(layers "F.Cu" "F.Mask" "F.Paste")
			(net "ADM1276_LATCH_B")
			(options
				(clearance outline)
				(anchor circle)
			)
			(primitives
				(gr_poly
					(pts
						(arc
							(start -0.1778 0.5715)
							(mid -0.321484 0.511984)
							(end -0.381 0.3683)
						)
						(arc
							(start -0.381 -0.3683)
							(mid -0.321484 -0.511984)
							(end -0.1778 -0.5715)
						)
						(arc
							(start 0.1778 -0.5715)
							(mid 0.321484 -0.511984)
							(end 0.381 -0.3683)
						)
						(arc
							(start 0.381 0.3683)
							(mid 0.321484 0.511984)
							(end 0.1778 0.5715)
						)
					)
					(width 0)
					(fill yes)
				)
			)
		)
		(pad "C" smd custom
			(at 0 -0.9525 180)
			(size 0.1905 0.1905)
			(layers "F.Cu" "F.Mask" "F.Paste")
			(net "TEMP_ALM#_REVERSE_R")
			(options
				(clearance outline)
				(anchor circle)
			)
			(primitives
				(gr_poly
					(pts
						(arc
							(start -0.1778 0.5715)
							(mid -0.321484 0.511984)
							(end -0.381 0.3683)
						)
						(arc
							(start -0.381 -0.3683)
							(mid -0.321484 -0.511984)
							(end -0.1778 -0.5715)
						)
						(arc
							(start 0.1778 -0.5715)
							(mid 0.321484 -0.511984)
							(end 0.381 -0.3683)
						)
						(arc
							(start 0.381 0.3683)
							(mid 0.321484 0.511984)
							(end 0.1778 0.5715)
						)
					)
					(width 0)
					(fill yes)
				)
			)
		)
		(pad "E" smd custom
			(at 0.98425 0.9525 180)
			(size 0.1905 0.1905)
			(layers "F.Cu" "F.Mask" "F.Paste")
			(net "ADM1276_EN_NET")
			(options
				(clearance outline)
				(anchor circle)
			)
			(primitives
				(gr_poly
					(pts
						(arc
							(start -0.1778 0.5715)
							(mid -0.321484 0.511984)
							(end -0.381 0.3683)
						)
						(arc
							(start -0.381 -0.3683)
							(mid -0.321484 -0.511984)
							(end -0.1778 -0.5715)
						)
						(arc
							(start 0.1778 -0.5715)
							(mid 0.321484 -0.511984)
							(end 0.381 -0.3683)
						)
						(arc
							(start 0.381 0.3683)
							(mid 0.321484 0.511984)
							(end 0.1778 0.5715)
						)
					)
					(width 0)
					(fill yes)
				)
			)
		)
	)
	(footprint ""
		(layer "F.Cu")
		(at 45.466 -179.451)
		(property "Reference" "TP21"
			(at 0 0 0)
			(layer "F.SilkS")
			(hide yes)
			(effects
				(font
					(size 1.27 1.27)
				)
			)
		)
		(property "Value" "TPAD32-GP"
			(at 0 -3.166364 0)
			(unlocked yes)
			(layer "F.Fab")
			(hide yes)
			(effects
				(font
					(size 1.016 1.016)
					(thickness 0.1524)
				)
			)
		)
		(property "Device Type" "TPAD32"
			(at 0 -4.690618 0)
			(unlocked yes)
			(layer "F.Fab")
			(hide yes)
			(effects
				(font
					(size 1.016 1.016)
					(thickness 0.1524)
				)
			)
		)
		(duplicate_pad_numbers_are_jumpers no)
		(fp_poly
			(pts
				(arc
					(start 0.7112 0)
					(mid -0.7112 0)
					(end 0.7112 0)
				)
			)
			(stroke
				(width 0)
				(type default)
			)
			(fill no)
			(layer "F.CrtYd")
		)
		(fp_poly
			(pts
				(arc
					(start 0.7112 0)
					(mid -0.7112 0)
					(end 0.7112 0)
				)
			)
			(stroke
				(width 0)
				(type default)
			)
			(fill no)
			(layer "F.Fab")
		)
		(pad "1" smd circle
			(at 0 0)
			(size 0.8128 0.8128)
			(layers "F.Cu" "F.Mask" "F.Paste")
			(net "D_LATCH_Q#")
		)
	)
	(footprint ""
		(layer "F.Cu")
		(at 28.067 -238.252 180)
		(property "Reference" "R39"
			(at 0 0 180)
			(layer "F.SilkS")
			(hide yes)
			(effects
				(font
					(size 1.27 1.27)
				)
			)
		)
		(property "Value" "4K7R2J-2-GP"
			(at 0.064008 -3.993896 180)
			(unlocked yes)
			(layer "F.Fab")
			(hide yes)
			(effects
				(font
					(size 1.016 1.016)
					(thickness 0.1524)
				)
			)
		)
		(property "Device Type" "R402H16"
			(at 0.064008 -5.517896 180)
			(unlocked yes)
			(layer "F.Fab")
			(hide yes)
			(effects
				(font
					(size 1.016 1.016)
					(thickness 0.1524)
				)
			)
		)
		(duplicate_pad_numbers_are_jumpers no)
		(fp_line
			(start 0.508 -0.9398)
			(end -0.508 -0.9398)
			(stroke
				(width 0.1524)
				(type default)
			)
			(layer "F.SilkS")
		)
		(fp_line
			(start -0.508 -0.9398)
			(end -0.508 0.9398)
			(stroke
				(width 0.1524)
				(type default)
			)
			(layer "F.SilkS")
		)
		(fp_rect
			(start -0.508 0.9398)
			(end 0.508 -0.9398)
			(stroke
				(width 0)
				(type default)
			)
			(fill no)
			(layer "F.CrtYd")
		)
		(fp_rect
			(start -0.508 0.9398)
			(end 0.508 -0.9398)
			(stroke
				(width 0)
				(type default)
			)
			(fill no)
			(layer "F.Fab")
		)
		(pad "1" smd custom
			(at 0 -0.4445 180)
			(size 0.1397 0.1397)
			(layers "F.Cu" "F.Mask" "F.Paste")
			(net "P3V3")
			(options
				(clearance outline)
				(anchor circle)
			)
			(primitives
				(gr_poly
					(pts
						(arc
							(start -0.1778 -0.2794)
							(mid -0.249642 -0.249642)
							(end -0.2794 -0.1778)
						)
						(arc
							(start -0.2794 0.1778)
							(mid -0.249642 0.249642)
							(end -0.1778 0.2794)
						)
						(arc
							(start 0.1778 0.2794)
							(mid 0.249642 0.249642)
							(end 0.2794 0.1778)
						)
						(arc
							(start 0.2794 -0.1778)
							(mid 0.249642 -0.249642)
							(end 0.1778 -0.2794)
						)
					)
					(width 0)
					(fill yes)
				)
			)
		)
		(pad "2" smd custom
			(at 0 0.4445 180)
			(size 0.1397 0.1397)
			(layers "F.Cu" "F.Mask" "F.Paste")
			(net "FCB_EEPROM_A0")
			(options
				(clearance outline)
				(anchor circle)
			)
			(primitives
				(gr_poly
					(pts
						(arc
							(start -0.1778 -0.2794)
							(mid -0.249642 -0.249642)
							(end -0.2794 -0.1778)
						)
						(arc
							(start -0.2794 0.1778)
							(mid -0.249642 0.249642)
							(end -0.1778 0.2794)
						)
						(arc
							(start 0.1778 0.2794)
							(mid 0.249642 0.249642)
							(end 0.2794 0.1778)
						)
						(arc
							(start 0.2794 -0.1778)
							(mid 0.249642 -0.249642)
							(end 0.1778 -0.2794)
						)
					)
					(width 0)
					(fill yes)
				)
			)
		)
	)
	(footprint ""
		(layer "F.Cu")
		(at 15.3924 -49.0982 180)
		(property "Reference" "R184"
			(at 0 0 180)
			(layer "F.SilkS")
			(hide yes)
			(effects
				(font
					(size 1.27 1.27)
				)
			)
		)
		(property "Value" "0R2J-2-GP"
			(at 0.064008 -3.993896 180)
			(unlocked yes)
			(layer "F.Fab")
			(hide yes)
			(effects
				(font
					(size 1.016 1.016)
					(thickness 0.1524)
				)
			)
		)
		(property "Device Type" "R402H16"
			(at 0.064008 -5.517896 180)
			(unlocked yes)
			(layer "F.Fab")
			(hide yes)
			(effects
				(font
					(size 1.016 1.016)
					(thickness 0.1524)
				)
			)
		)
		(duplicate_pad_numbers_are_jumpers no)
		(fp_line
			(start 0.508 -0.9398)
			(end -0.508 -0.9398)
			(stroke
				(width 0.1524)
				(type default)
			)
			(layer "F.SilkS")
		)
		(fp_line
			(start -0.508 -0.9398)
			(end -0.508 0.9398)
			(stroke
				(width 0.1524)
				(type default)
			)
			(layer "F.SilkS")
		)
		(fp_rect
			(start -0.508 0.9398)
			(end 0.508 -0.9398)
			(stroke
				(width 0)
				(type default)
			)
			(fill no)
			(layer "F.CrtYd")
		)
		(fp_rect
			(start -0.508 0.9398)
			(end 0.508 -0.9398)
			(stroke
				(width 0)
				(type default)
			)
			(fill no)
			(layer "F.Fab")
		)
		(pad "1" smd custom
			(at 0 -0.4445 180)
			(size 0.1397 0.1397)
			(layers "F.Cu" "F.Mask" "F.Paste")
			(net "SD_LATCH_RELEASE_L")
			(options
				(clearance outline)
				(anchor circle)
			)
			(primitives
				(gr_poly
					(pts
						(arc
							(start -0.1778 -0.2794)
							(mid -0.249642 -0.249642)
							(end -0.2794 -0.1778)
						)
						(arc
							(start -0.2794 0.1778)
							(mid -0.249642 0.249642)
							(end -0.1778 0.2794)
						)
						(arc
							(start 0.1778 0.2794)
							(mid 0.249642 0.249642)
							(end 0.2794 0.1778)
						)
						(arc
							(start 0.2794 -0.1778)
							(mid 0.249642 -0.249642)
							(end 0.1778 -0.2794)
						)
					)
					(width 0)
					(fill yes)
				)
			)
		)
		(pad "2" smd custom
			(at 0 0.4445 180)
			(size 0.1397 0.1397)
			(layers "F.Cu" "F.Mask" "F.Paste")
			(net "TEMP_ALM#_REVERSE_R")
			(options
				(clearance outline)
				(anchor circle)
			)
			(primitives
				(gr_poly
					(pts
						(arc
							(start -0.1778 -0.2794)
							(mid -0.249642 -0.249642)
							(end -0.2794 -0.1778)
						)
						(arc
							(start -0.2794 0.1778)
							(mid -0.249642 0.249642)
							(end -0.1778 0.2794)
						)
						(arc
							(start 0.1778 0.2794)
							(mid 0.249642 0.249642)
							(end 0.2794 0.1778)
						)
						(arc
							(start 0.2794 -0.1778)
							(mid 0.249642 -0.249642)
							(end 0.1778 -0.2794)
						)
					)
					(width 0)
					(fill yes)
				)
			)
		)
	)
	(footprint ""
		(layer "F.Cu")
		(at 8.733028 -67.111118 -90)
		(property "Reference" "R111"
			(at 0 0 270)
			(layer "F.SilkS")
			(hide yes)
			(effects
				(font
					(size 1.27 1.27)
				)
			)
		)
		(property "Value" "2KR2F-3-GP"
			(at 0.064008 -3.993896 270)
			(unlocked yes)
			(layer "F.Fab")
			(hide yes)
			(effects
				(font
					(size 1.016 1.016)
					(thickness 0.1524)
				)
			)
		)
		(property "Device Type" "R402H16"
			(at 0.064008 -5.517896 270)
			(unlocked yes)
			(layer "F.Fab")
			(hide yes)
			(effects
				(font
					(size 1.016 1.016)
					(thickness 0.1524)
				)
			)
		)
		(duplicate_pad_numbers_are_jumpers no)
		(fp_line
			(start -0.508 -0.9398)
			(end -0.508 0.9398)
			(stroke
				(width 0.1524)
				(type default)
			)
			(layer "F.SilkS")
		)
		(fp_line
			(start 0.508 -0.9398)
			(end -0.508 -0.9398)
			(stroke
				(width 0.1524)
				(type default)
			)
			(layer "F.SilkS")
		)
		(fp_rect
			(start -0.508 0.9398)
			(end 0.508 -0.9398)
			(stroke
				(width 0)
				(type default)
			)
			(fill no)
			(layer "F.CrtYd")
		)
		(fp_rect
			(start -0.508 0.9398)
			(end 0.508 -0.9398)
			(stroke
				(width 0)
				(type default)
			)
			(fill no)
			(layer "F.Fab")
		)
		(pad "1" smd custom
			(at 0 -0.4445 270)
			(size 0.1397 0.1397)
			(layers "F.Cu" "F.Mask" "F.Paste")
			(net "LED_DR_LED5")
			(options
				(clearance outline)
				(anchor circle)
			)
			(primitives
				(gr_poly
					(pts
						(arc
							(start -0.1778 -0.2794)
							(mid -0.249642 -0.249642)
							(end -0.2794 -0.1778)
						)
						(arc
							(start -0.2794 0.1778)
							(mid -0.249642 0.249642)
							(end -0.1778 0.2794)
						)
						(arc
							(start 0.1778 0.2794)
							(mid 0.249642 0.249642)
							(end 0.2794 0.1778)
						)
						(arc
							(start 0.2794 -0.1778)
							(mid 0.249642 -0.249642)
							(end 0.1778 -0.2794)
						)
					)
					(width 0)
					(fill yes)
				)
			)
		)
		(pad "2" smd custom
			(at 0 0.4445 270)
			(size 0.1397 0.1397)
			(layers "F.Cu" "F.Mask" "F.Paste")
			(net "LED_DR_LED5_B")
			(options
				(clearance outline)
				(anchor circle)
			)
			(primitives
				(gr_poly
					(pts
						(arc
							(start -0.1778 -0.2794)
							(mid -0.249642 -0.249642)
							(end -0.2794 -0.1778)
						)
						(arc
							(start -0.2794 0.1778)
							(mid -0.249642 0.249642)
							(end -0.1778 0.2794)
						)
						(arc
							(start 0.1778 0.2794)
							(mid 0.249642 0.249642)
							(end 0.2794 0.1778)
						)
						(arc
							(start 0.2794 -0.1778)
							(mid 0.249642 -0.249642)
							(end 0.1778 -0.2794)
						)
					)
					(width 0)
					(fill yes)
				)
			)
		)
	)
	(footprint ""
		(layer "F.Cu")
		(at 20.701 -185.5216)
		(property "Reference" "R85"
			(at 0 0 0)
			(layer "F.SilkS")
			(hide yes)
			(effects
				(font
					(size 1.27 1.27)
				)
			)
		)
		(property "Value" "27KR3F-GP"
			(at -0.0254 -2.5146 0)
			(unlocked yes)
			(layer "F.Fab")
			(hide yes)
			(effects
				(font
					(size 1.016 1.016)
					(thickness 0.1524)
				)
			)
		)
		(property "Device Type" "R603H22"
			(at -0.0254 -4.0386 0)
			(unlocked yes)
			(layer "F.Fab")
			(hide yes)
			(effects
				(font
					(size 1.016 1.016)
					(thickness 0.1524)
				)
			)
		)
		(duplicate_pad_numbers_are_jumpers no)
		(fp_line
			(start -0.4826 0)
			(end -0.2032 0)
			(stroke
				(width 0.2032)
				(type default)
			)
			(layer "F.SilkS")
		)
		(fp_line
			(start 0.2032 0)
			(end 0.4826 0)
			(stroke
				(width 0.2032)
				(type default)
			)
			(layer "F.SilkS")
		)
		(fp_rect
			(start -0.5842 1.3335)
			(end 0.5842 -1.3335)
			(stroke
				(width 0)
				(type default)
			)
			(fill no)
			(layer "F.CrtYd")
		)
		(fp_rect
			(start -0.5842 1.3335)
			(end 0.5842 -1.3335)
			(stroke
				(width 0)
				(type default)
			)
			(fill no)
			(layer "F.Fab")
		)
		(pad "1" smd custom
			(at 0 -0.762)
			(size 0.2159 0.2159)
			(layers "F.Cu" "F.Mask" "F.Paste")
			(net "FAN_TACH8")
			(options
				(clearance outline)
				(anchor circle)
			)
			(primitives
				(gr_poly
					(pts
						(arc
							(start -0.3302 -0.4318)
							(mid -0.402042 -0.402042)
							(end -0.4318 -0.3302)
						)
						(arc
							(start -0.4318 0.3302)
							(mid -0.402042 0.402042)
							(end -0.3302 0.4318)
						)
						(arc
							(start 0.3302 0.4318)
							(mid 0.402042 0.402042)
							(end 0.4318 0.3302)
						)
						(arc
							(start 0.4318 -0.3302)
							(mid 0.402042 -0.402042)
							(end 0.3302 -0.4318)
						)
					)
					(width 0)
					(fill yes)
				)
			)
		)
		(pad "2" smd custom
			(at 0 0.762)
			(size 0.2159 0.2159)
			(layers "F.Cu" "F.Mask" "F.Paste")
			(net "FANIN_8")
			(options
				(clearance outline)
				(anchor circle)
			)
			(primitives
				(gr_poly
					(pts
						(arc
							(start -0.3302 -0.4318)
							(mid -0.402042 -0.402042)
							(end -0.4318 -0.3302)
						)
						(arc
							(start -0.4318 0.3302)
							(mid -0.402042 0.402042)
							(end -0.3302 0.4318)
						)
						(arc
							(start 0.3302 0.4318)
							(mid 0.402042 0.402042)
							(end 0.4318 0.3302)
						)
						(arc
							(start 0.4318 -0.3302)
							(mid 0.402042 -0.402042)
							(end 0.3302 -0.4318)
						)
					)
					(width 0)
					(fill yes)
				)
			)
		)
	)
	(footprint ""
		(layer "F.Cu")
		(at 4.499864 -340.000082)
		(property "Reference" "H4"
			(at 0 0 0)
			(layer "F.SilkS")
			(hide yes)
			(effects
				(font
					(size 1.27 1.27)
				)
			)
		)
		(property "Value" "HOLE315R138"
			(at 0 -7.0612 0)
			(unlocked yes)
			(layer "F.Fab")
			(hide yes)
			(effects
				(font
					(size 1.016 1.016)
					(thickness 0.1524)
				)
			)
		)
		(property "Device Type" "HOLE315R138"
			(at 0 -8.5852 0)
			(unlocked yes)
			(layer "F.Fab")
			(hide yes)
			(effects
				(font
					(size 1.016 1.016)
					(thickness 0.1524)
				)
			)
		)
		(duplicate_pad_numbers_are_jumpers no)
		(fp_poly
			(pts
				(xy 0 4.3053) (xy -0.13462 4.30276) (xy -0.27051 4.29641) (xy -0.40513 4.28625) (xy -0.53975 4.27101)
				(xy -0.6731 4.25196) (xy -0.80645 4.2291) (xy -0.9398 4.20116) (xy -1.07061 4.17068) (xy -1.20142 4.13385)
				(xy -1.33096 4.09448) (xy -1.45796 4.0513) (xy -1.58496 4.00304) (xy -1.70942 3.95097) (xy -1.83261 3.89509)
				(xy -1.95453 3.83667) (xy -2.07391 3.77317) (xy -2.19202 3.70586) (xy -2.30632 3.63474) (xy -2.41935 3.56108)
				(xy -2.53111 3.48361) (xy -2.63906 3.40233) (xy -2.74447 3.31724) (xy -2.84734 3.22961) (xy -2.94767 3.13817)
				(xy -3.04419 3.04419) (xy -3.13817 2.94767) (xy -3.22961 2.84734) (xy -3.31724 2.74447) (xy -3.40233 2.63906)
				(xy -3.48361 2.53111) (xy -3.56108 2.41935) (xy -3.63474 2.30632) (xy -3.70586 2.19202) (xy -3.77317 2.07391)
				(xy -3.83667 1.95453) (xy -3.89509 1.83261) (xy -3.95097 1.70942) (xy -4.00304 1.58496) (xy -4.0513 1.45796)
				(xy -4.09448 1.33096) (xy -4.13385 1.20142) (xy -4.17068 1.07061) (xy -4.20116 0.9398) (xy -4.2291 0.80645)
				(xy -4.25196 0.6731) (xy -4.27101 0.53975) (xy -4.28625 0.40513) (xy -4.29641 0.27051) (xy -4.30276 0.13462)
				(xy -4.3053 0) (xy -4.30276 -0.13462) (xy -4.29641 -0.27051) (xy -4.28625 -0.40513) (xy -4.27101 -0.53975)
				(xy -4.25196 -0.6731) (xy -4.2291 -0.80645) (xy -4.20116 -0.9398) (xy -4.17068 -1.07061) (xy -4.13385 -1.20142)
				(xy -4.09448 -1.33096) (xy -4.0513 -1.45796) (xy -4.00304 -1.58496) (xy -3.95097 -1.70942) (xy -3.89509 -1.83261)
				(xy -3.83667 -1.95453) (xy -3.77317 -2.07391) (xy -3.70586 -2.19202) (xy -3.63474 -2.30632) (xy -3.56108 -2.41935)
				(xy -3.48361 -2.53111) (xy -3.40233 -2.63906) (xy -3.31724 -2.74447) (xy -3.22961 -2.84734) (xy -3.13817 -2.94767)
				(xy -3.04419 -3.04419) (xy -2.94767 -3.13817) (xy -2.84734 -3.22961) (xy -2.74447 -3.31724) (xy -2.63906 -3.40233)
				(xy -2.53111 -3.48361) (xy -2.41935 -3.56108) (xy -2.30632 -3.63474) (xy -2.19202 -3.70586) (xy -2.07391 -3.77317)
				(xy -1.95453 -3.83667) (xy -1.83261 -3.89509) (xy -1.70942 -3.95097) (xy -1.58496 -4.00304) (xy -1.45796 -4.0513)
				(xy -1.33096 -4.09448) (xy -1.20142 -4.13385) (xy -1.07061 -4.17068) (xy -0.9398 -4.20116) (xy -0.80645 -4.2291)
				(xy -0.6731 -4.25196) (xy -0.53975 -4.27101) (xy -0.40513 -4.28625) (xy -0.27051 -4.29641) (xy -0.13462 -4.30276)
				(xy 0 -4.3053) (xy 0.13462 -4.30276) (xy 0.27051 -4.29641) (xy 0.40513 -4.28625) (xy 0.53975 -4.27101)
				(xy 0.6731 -4.25196) (xy 0.80645 -4.2291) (xy 0.9398 -4.20116) (xy 1.07061 -4.17068) (xy 1.20142 -4.13385)
				(xy 1.33096 -4.09448) (xy 1.45796 -4.0513) (xy 1.58496 -4.00304) (xy 1.70942 -3.95097) (xy 1.83261 -3.89509)
				(xy 1.95453 -3.83667) (xy 2.07391 -3.77317) (xy 2.19202 -3.70586) (xy 2.30632 -3.63474) (xy 2.41935 -3.56108)
				(xy 2.53111 -3.48361) (xy 2.63906 -3.40233) (xy 2.74447 -3.31724) (xy 2.84734 -3.22961) (xy 2.94767 -3.13817)
				(xy 3.04419 -3.04419) (xy 3.13817 -2.94767) (xy 3.22961 -2.84734) (xy 3.31724 -2.74447) (xy 3.40233 -2.63906)
				(xy 3.48361 -2.53111) (xy 3.56108 -2.41935) (xy 3.63474 -2.30632) (xy 3.70586 -2.19202) (xy 3.77317 -2.07391)
				(xy 3.83667 -1.95453) (xy 3.89509 -1.83261) (xy 3.95097 -1.70942) (xy 4.00304 -1.58496) (xy 4.0513 -1.45796)
				(xy 4.09448 -1.33096) (xy 4.13385 -1.20142) (xy 4.17068 -1.07061) (xy 4.20116 -0.9398) (xy 4.2291 -0.80645)
				(xy 4.25196 -0.6731) (xy 4.27101 -0.53975) (xy 4.28625 -0.40513) (xy 4.29641 -0.27051) (xy 4.30276 -0.13462)
				(xy 4.3053 0) (xy 4.30276 0.13462) (xy 4.29641 0.27051) (xy 4.28625 0.40513) (xy 4.27101 0.53975)
				(xy 4.25196 0.6731) (xy 4.2291 0.80645) (xy 4.20116 0.9398) (xy 4.17068 1.07061) (xy 4.13385 1.20142)
				(xy 4.09448 1.33096) (xy 4.0513 1.45796) (xy 4.00304 1.58496) (xy 3.95097 1.70942) (xy 3.89509 1.83261)
				(xy 3.83667 1.95453) (xy 3.77317 2.07391) (xy 3.70586 2.19202) (xy 3.63474 2.30632) (xy 3.56108 2.41935)
				(xy 3.48361 2.53111) (xy 3.40233 2.63906) (xy 3.31724 2.74447) (xy 3.22961 2.84734) (xy 3.13817 2.94767)
				(xy 3.04419 3.04419) (xy 2.94767 3.13817) (xy 2.84734 3.22961) (xy 2.74447 3.31724) (xy 2.63906 3.40233)
				(xy 2.53111 3.48361) (xy 2.41935 3.56108) (xy 2.30632 3.63474) (xy 2.19202 3.70586) (xy 2.07391 3.77317)
				(xy 1.95453 3.83667) (xy 1.83261 3.89509) (xy 1.70942 3.95097) (xy 1.58496 4.00304) (xy 1.45796 4.0513)
				(xy 1.33096 4.09448) (xy 1.20142 4.13385) (xy 1.07061 4.17068) (xy 0.9398 4.20116) (xy 0.80645 4.2291)
				(xy 0.6731 4.25196) (xy 0.53975 4.27101) (xy 0.40513 4.28625) (xy 0.27051 4.29641) (xy 0.13462 4.30276)
			)
			(stroke
				(width 0)
				(type default)
			)
			(fill no)
			(layer "F.CrtYd")
		)
		(fp_poly
			(pts
				(xy 0 4.3053) (xy -0.13462 4.30276) (xy -0.27051 4.29641) (xy -0.40513 4.28625) (xy -0.53975 4.27101)
				(xy -0.6731 4.25196) (xy -0.80645 4.2291) (xy -0.9398 4.20116) (xy -1.07061 4.17068) (xy -1.20142 4.13385)
				(xy -1.33096 4.09448) (xy -1.45796 4.0513) (xy -1.58496 4.00304) (xy -1.70942 3.95097) (xy -1.83261 3.89509)
				(xy -1.95453 3.83667) (xy -2.07391 3.77317) (xy -2.19202 3.70586) (xy -2.30632 3.63474) (xy -2.41935 3.56108)
				(xy -2.53111 3.48361) (xy -2.63906 3.40233) (xy -2.74447 3.31724) (xy -2.84734 3.22961) (xy -2.94767 3.13817)
				(xy -3.04419 3.04419) (xy -3.13817 2.94767) (xy -3.22961 2.84734) (xy -3.31724 2.74447) (xy -3.40233 2.63906)
				(xy -3.48361 2.53111) (xy -3.56108 2.41935) (xy -3.63474 2.30632) (xy -3.70586 2.19202) (xy -3.77317 2.07391)
				(xy -3.83667 1.95453) (xy -3.89509 1.83261) (xy -3.95097 1.70942) (xy -4.00304 1.58496) (xy -4.0513 1.45796)
				(xy -4.09448 1.33096) (xy -4.13385 1.20142) (xy -4.17068 1.07061) (xy -4.20116 0.9398) (xy -4.2291 0.80645)
				(xy -4.25196 0.6731) (xy -4.27101 0.53975) (xy -4.28625 0.40513) (xy -4.29641 0.27051) (xy -4.30276 0.13462)
				(xy -4.3053 0) (xy -4.30276 -0.13462) (xy -4.29641 -0.27051) (xy -4.28625 -0.40513) (xy -4.27101 -0.53975)
				(xy -4.25196 -0.6731) (xy -4.2291 -0.80645) (xy -4.20116 -0.9398) (xy -4.17068 -1.07061) (xy -4.13385 -1.20142)
				(xy -4.09448 -1.33096) (xy -4.0513 -1.45796) (xy -4.00304 -1.58496) (xy -3.95097 -1.70942) (xy -3.89509 -1.83261)
				(xy -3.83667 -1.95453) (xy -3.77317 -2.07391) (xy -3.70586 -2.19202) (xy -3.63474 -2.30632) (xy -3.56108 -2.41935)
				(xy -3.48361 -2.53111) (xy -3.40233 -2.63906) (xy -3.31724 -2.74447) (xy -3.22961 -2.84734) (xy -3.13817 -2.94767)
				(xy -3.04419 -3.04419) (xy -2.94767 -3.13817) (xy -2.84734 -3.22961) (xy -2.74447 -3.31724) (xy -2.63906 -3.40233)
				(xy -2.53111 -3.48361) (xy -2.41935 -3.56108) (xy -2.30632 -3.63474) (xy -2.19202 -3.70586) (xy -2.07391 -3.77317)
				(xy -1.95453 -3.83667) (xy -1.83261 -3.89509) (xy -1.70942 -3.95097) (xy -1.58496 -4.00304) (xy -1.45796 -4.0513)
				(xy -1.33096 -4.09448) (xy -1.20142 -4.13385) (xy -1.07061 -4.17068) (xy -0.9398 -4.20116) (xy -0.80645 -4.2291)
				(xy -0.6731 -4.25196) (xy -0.53975 -4.27101) (xy -0.40513 -4.28625) (xy -0.27051 -4.29641) (xy -0.13462 -4.30276)
				(xy 0 -4.3053) (xy 0.13462 -4.30276) (xy 0.27051 -4.29641) (xy 0.40513 -4.28625) (xy 0.53975 -4.27101)
				(xy 0.6731 -4.25196) (xy 0.80645 -4.2291) (xy 0.9398 -4.20116) (xy 1.07061 -4.17068) (xy 1.20142 -4.13385)
				(xy 1.33096 -4.09448) (xy 1.45796 -4.0513) (xy 1.58496 -4.00304) (xy 1.70942 -3.95097) (xy 1.83261 -3.89509)
				(xy 1.95453 -3.83667) (xy 2.07391 -3.77317) (xy 2.19202 -3.70586) (xy 2.30632 -3.63474) (xy 2.41935 -3.56108)
				(xy 2.53111 -3.48361) (xy 2.63906 -3.40233) (xy 2.74447 -3.31724) (xy 2.84734 -3.22961) (xy 2.94767 -3.13817)
				(xy 3.04419 -3.04419) (xy 3.13817 -2.94767) (xy 3.22961 -2.84734) (xy 3.31724 -2.74447) (xy 3.40233 -2.63906)
				(xy 3.48361 -2.53111) (xy 3.56108 -2.41935) (xy 3.63474 -2.30632) (xy 3.70586 -2.19202) (xy 3.77317 -2.07391)
				(xy 3.83667 -1.95453) (xy 3.89509 -1.83261) (xy 3.95097 -1.70942) (xy 4.00304 -1.58496) (xy 4.0513 -1.45796)
				(xy 4.09448 -1.33096) (xy 4.13385 -1.20142) (xy 4.17068 -1.07061) (xy 4.20116 -0.9398) (xy 4.2291 -0.80645)
				(xy 4.25196 -0.6731) (xy 4.27101 -0.53975) (xy 4.28625 -0.40513) (xy 4.29641 -0.27051) (xy 4.30276 -0.13462)
				(xy 4.3053 0) (xy 4.30276 0.13462) (xy 4.29641 0.27051) (xy 4.28625 0.40513) (xy 4.27101 0.53975)
				(xy 4.25196 0.6731) (xy 4.2291 0.80645) (xy 4.20116 0.9398) (xy 4.17068 1.07061) (xy 4.13385 1.20142)
				(xy 4.09448 1.33096) (xy 4.0513 1.45796) (xy 4.00304 1.58496) (xy 3.95097 1.70942) (xy 3.89509 1.83261)
				(xy 3.83667 1.95453) (xy 3.77317 2.07391) (xy 3.70586 2.19202) (xy 3.63474 2.30632) (xy 3.56108 2.41935)
				(xy 3.48361 2.53111) (xy 3.40233 2.63906) (xy 3.31724 2.74447) (xy 3.22961 2.84734) (xy 3.13817 2.94767)
				(xy 3.04419 3.04419) (xy 2.94767 3.13817) (xy 2.84734 3.22961) (xy 2.74447 3.31724) (xy 2.63906 3.40233)
				(xy 2.53111 3.48361) (xy 2.41935 3.56108) (xy 2.30632 3.63474) (xy 2.19202 3.70586) (xy 2.07391 3.77317)
				(xy 1.95453 3.83667) (xy 1.83261 3.89509) (xy 1.70942 3.95097) (xy 1.58496 4.00304) (xy 1.45796 4.0513)
				(xy 1.33096 4.09448) (xy 1.20142 4.13385) (xy 1.07061 4.17068) (xy 0.9398 4.20116) (xy 0.80645 4.2291)
				(xy 0.6731 4.25196) (xy 0.53975 4.27101) (xy 0.40513 4.28625) (xy 0.27051 4.29641) (xy 0.13462 4.30276)
			)
			(stroke
				(width 0)
				(type default)
			)
			(fill no)
			(layer "F.Fab")
		)
		(pad "1" thru_hole circle
			(at 0 0)
			(size 8.001 8.001)
			(drill 3.5052)
			(layers "*.Cu" "*.Mask")
			(remove_unused_layers no)
			(net "GND")
			(clearance -1.7399)
			(thermal_gap 0.3048)
			(padstack
				(mode front_inner_back)
				(layer "Inner"
					(shape circle)
					(size 3.9116 3.9116)
					(clearance 0.3048)
				)
				(layer "B.Cu"
					(shape circle)
					(size 8.001 8.001)
					(clearance -1.7399)
				)
			)
		)
	)
	(footprint ""
		(layer "F.Cu")
		(at 4.040124 -17.29994 -90)
		(property "Reference" "CN6"
			(at 0 0 270)
			(layer "F.SilkS")
			(hide yes)
			(effects
				(font
					(size 1.27 1.27)
				)
			)
		)
		(property "Value" "JWT-CON5-42-GP"
			(at -7.8105 2.9591 270)
			(unlocked yes)
			(layer "F.Fab")
			(hide yes)
			(effects
				(font
					(size 1.016 1.016)
					(thickness 0.1524)
				)
			)
		)
		(property "Device Type" "A2541WR0-1TX5PA-6T-0E"
			(at -7.8105 1.4351 270)
			(unlocked yes)
			(layer "F.Fab")
			(hide yes)
			(effects
				(font
					(size 1.016 1.016)
					(thickness 0.1524)
				)
			)
		)
		(duplicate_pad_numbers_are_jumpers no)
		(fp_line
			(start -6.604 10.287)
			(end 6.604 10.287)
			(stroke
				(width 0.1524)
				(type default)
			)
			(layer "F.SilkS")
		)
		(fp_line
			(start 6.604 10.287)
			(end 6.604 -0.9652)
			(stroke
				(width 0.1524)
				(type default)
			)
			(layer "F.SilkS")
		)
		(fp_line
			(start -6.604 -0.9652)
			(end -6.604 10.287)
			(stroke
				(width 0.1524)
				(type default)
			)
			(layer "F.SilkS")
		)
		(fp_line
			(start 6.604 -0.9652)
			(end -6.604 -0.9652)
			(stroke
				(width 0.1524)
				(type default)
			)
			(layer "F.SilkS")
		)
		(fp_line
			(start -6.731 -1.0922)
			(end -6.731 0.1778)
			(stroke
				(width 0.4064)
				(type default)
			)
			(layer "F.SilkS")
		)
		(fp_line
			(start -5.461 -1.0922)
			(end -6.731 -1.0922)
			(stroke
				(width 0.4064)
				(type default)
			)
			(layer "F.SilkS")
		)
		(fp_circle
			(center -5.08 0)
			(end -5.08 -1.0668)
			(stroke
				(width 0.3048)
				(type default)
			)
			(fill no)
			(layer "F.SilkS")
		)
		(fp_circle
			(center -2.54 0)
			(end -2.54 -1.0668)
			(stroke
				(width 0.3048)
				(type default)
			)
			(fill no)
			(layer "F.SilkS")
		)
		(fp_circle
			(center 0 0)
			(end 0 -1.0668)
			(stroke
				(width 0.3048)
				(type default)
			)
			(fill no)
			(layer "F.SilkS")
		)
		(fp_circle
			(center 2.54 0)
			(end 2.54 -1.0668)
			(stroke
				(width 0.3048)
				(type default)
			)
			(fill no)
			(layer "F.SilkS")
		)
		(fp_circle
			(center 5.08 0)
			(end 5.08 -1.0668)
			(stroke
				(width 0.3048)
				(type default)
			)
			(fill no)
			(layer "F.SilkS")
		)
		(fp_rect
			(start -6.35 10.033)
			(end 6.35 -0.3302)
			(stroke
				(width 0)
				(type default)
			)
			(fill no)
			(layer "F.CrtYd")
		)
		(fp_poly
			(pts
				(xy -6.35 -0.3302) (xy 6.858 -0.3302) (xy 6.858 -1.2192) (xy -6.858 -1.2192) (xy -6.858 10.541)
				(xy 6.858 10.541) (xy 6.858 -0.3175) (xy 6.35 -0.3175) (xy 6.35 10.033) (xy -6.35 10.033)
			)
			(stroke
				(width 0)
				(type default)
			)
			(fill no)
			(layer "F.CrtYd")
		)
		(fp_rect
			(start -6.858 10.541)
			(end 6.858 -1.2192)
			(stroke
				(width 0)
				(type default)
			)
			(fill no)
			(layer "F.Fab")
		)
		(pad "1" thru_hole circle
			(at -5.08 0 270)
			(size 1.4224 1.4224)
			(drill 1.016)
			(layers "*.Cu" "*.Mask")
			(remove_unused_layers no)
			(net "GND")
			(clearance 0.1524)
			(thermal_gap 0.1524)
		)
		(pad "2" thru_hole circle
			(at -2.54 0 270)
			(size 1.4224 1.4224)
			(drill 1.016)
			(layers "*.Cu" "*.Mask")
			(remove_unused_layers no)
			(net "P12V_FAN6")
			(clearance 0.1524)
			(thermal_gap 0.1524)
		)
		(pad "3" thru_hole circle
			(at 0 0 270)
			(size 1.4224 1.4224)
			(drill 1.016)
			(layers "*.Cu" "*.Mask")
			(remove_unused_layers no)
			(net "FAN_TACH12")
			(clearance 0.1524)
			(thermal_gap 0.1524)
		)
		(pad "4" thru_hole circle
			(at 2.54 0 270)
			(size 1.4224 1.4224)
			(drill 1.016)
			(layers "*.Cu" "*.Mask")
			(remove_unused_layers no)
			(net "PWM_OUT_FAN6_NET")
			(clearance 0.1524)
			(thermal_gap 0.1524)
		)
		(pad "5" thru_hole circle
			(at 5.08 0 270)
			(size 1.4224 1.4224)
			(drill 1.016)
			(layers "*.Cu" "*.Mask")
			(remove_unused_layers no)
			(net "FAN_TACH11")
			(clearance 0.1524)
			(thermal_gap 0.1524)
		)
	)
	(footprint ""
		(layer "F.Cu")
		(at 20.585938 -15.595092 -90)
		(property "Reference" "R73"
			(at 0 0 270)
			(layer "F.SilkS")
			(hide yes)
			(effects
				(font
					(size 1.27 1.27)
				)
			)
		)
		(property "Value" "27KR3F-GP"
			(at -0.0254 -2.5146 270)
			(unlocked yes)
			(layer "F.Fab")
			(hide yes)
			(effects
				(font
					(size 1.016 1.016)
					(thickness 0.1524)
				)
			)
		)
		(property "Device Type" "R603H22"
			(at -0.0254 -4.0386 270)
			(unlocked yes)
			(layer "F.Fab")
			(hide yes)
			(effects
				(font
					(size 1.016 1.016)
					(thickness 0.1524)
				)
			)
		)
		(duplicate_pad_numbers_are_jumpers no)
		(fp_line
			(start -0.4826 0)
			(end -0.2032 0)
			(stroke
				(width 0.2032)
				(type default)
			)
			(layer "F.SilkS")
		)
		(fp_line
			(start 0.2032 0)
			(end 0.4826 0)
			(stroke
				(width 0.2032)
				(type default)
			)
			(layer "F.SilkS")
		)
		(fp_rect
			(start -0.5842 1.3335)
			(end 0.5842 -1.3335)
			(stroke
				(width 0)
				(type default)
			)
			(fill no)
			(layer "F.CrtYd")
		)
		(fp_rect
			(start -0.5842 1.3335)
			(end 0.5842 -1.3335)
			(stroke
				(width 0)
				(type default)
			)
			(fill no)
			(layer "F.Fab")
		)
		(pad "1" smd custom
			(at 0 -0.762 270)
			(size 0.2159 0.2159)
			(layers "F.Cu" "F.Mask" "F.Paste")
			(net "FANIN_11")
			(options
				(clearance outline)
				(anchor circle)
			)
			(primitives
				(gr_poly
					(pts
						(arc
							(start -0.3302 -0.4318)
							(mid -0.402042 -0.402042)
							(end -0.4318 -0.3302)
						)
						(arc
							(start -0.4318 0.3302)
							(mid -0.402042 0.402042)
							(end -0.3302 0.4318)
						)
						(arc
							(start 0.3302 0.4318)
							(mid 0.402042 0.402042)
							(end 0.4318 0.3302)
						)
						(arc
							(start 0.4318 -0.3302)
							(mid 0.402042 -0.402042)
							(end 0.3302 -0.4318)
						)
					)
					(width 0)
					(fill yes)
				)
			)
		)
		(pad "2" smd custom
			(at 0 0.762 270)
			(size 0.2159 0.2159)
			(layers "F.Cu" "F.Mask" "F.Paste")
			(net "FAN_TACH11")
			(options
				(clearance outline)
				(anchor circle)
			)
			(primitives
				(gr_poly
					(pts
						(arc
							(start -0.3302 -0.4318)
							(mid -0.402042 -0.402042)
							(end -0.4318 -0.3302)
						)
						(arc
							(start -0.4318 0.3302)
							(mid -0.402042 0.402042)
							(end -0.3302 0.4318)
						)
						(arc
							(start 0.3302 0.4318)
							(mid 0.402042 0.402042)
							(end 0.4318 0.3302)
						)
						(arc
							(start 0.4318 -0.3302)
							(mid 0.402042 -0.402042)
							(end 0.3302 -0.4318)
						)
					)
					(width 0)
					(fill yes)
				)
			)
		)
	)
	(footprint ""
		(layer "F.Cu")
		(at 33.2232 -248.5644)
		(property "Reference" "C20"
			(at 0 0 0)
			(layer "F.SilkS")
			(hide yes)
			(effects
				(font
					(size 1.27 1.27)
				)
			)
		)
		(property "Value" "SCD1U50V3KX-GP"
			(at 0 -2.8194 0)
			(unlocked yes)
			(layer "F.Fab")
			(hide yes)
			(effects
				(font
					(size 1.016 1.016)
					(thickness 0.1524)
				)
			)
		)
		(property "Device Type" "C603H36"
			(at 0 -4.3434 0)
			(unlocked yes)
			(layer "F.Fab")
			(hide yes)
			(effects
				(font
					(size 1.016 1.016)
					(thickness 0.1524)
				)
			)
		)
		(duplicate_pad_numbers_are_jumpers no)
		(fp_line
			(start 0.508 0)
			(end -0.508 0)
			(stroke
				(width 0.2032)
				(type default)
			)
			(layer "F.SilkS")
		)
		(fp_rect
			(start -0.5842 1.3335)
			(end 0.5842 -1.3335)
			(stroke
				(width 0)
				(type default)
			)
			(fill no)
			(layer "F.CrtYd")
		)
		(fp_rect
			(start -0.5842 1.3335)
			(end 0.5842 -1.3335)
			(stroke
				(width 0)
				(type default)
			)
			(fill no)
			(layer "F.Fab")
		)
		(pad "1" smd custom
			(at 0 -0.762)
			(size 0.2159 0.2159)
			(layers "F.Cu" "F.Mask" "F.Paste")
			(net "P3V3")
			(options
				(clearance outline)
				(anchor circle)
			)
			(primitives
				(gr_poly
					(pts
						(arc
							(start -0.3302 -0.4318)
							(mid -0.402042 -0.402042)
							(end -0.4318 -0.3302)
						)
						(arc
							(start -0.4318 0.3302)
							(mid -0.402042 0.402042)
							(end -0.3302 0.4318)
						)
						(arc
							(start 0.3302 0.4318)
							(mid 0.402042 0.402042)
							(end 0.4318 0.3302)
						)
						(arc
							(start 0.4318 -0.3302)
							(mid 0.402042 -0.402042)
							(end 0.3302 -0.4318)
						)
					)
					(width 0)
					(fill yes)
				)
			)
		)
		(pad "2" smd custom
			(at 0 0.762)
			(size 0.2159 0.2159)
			(layers "F.Cu" "F.Mask" "F.Paste")
			(net "GND")
			(options
				(clearance outline)
				(anchor circle)
			)
			(primitives
				(gr_poly
					(pts
						(arc
							(start -0.3302 -0.4318)
							(mid -0.402042 -0.402042)
							(end -0.4318 -0.3302)
						)
						(arc
							(start -0.4318 0.3302)
							(mid -0.402042 0.402042)
							(end -0.3302 0.4318)
						)
						(arc
							(start 0.3302 0.4318)
							(mid 0.402042 0.402042)
							(end 0.4318 0.3302)
						)
						(arc
							(start 0.4318 -0.3302)
							(mid 0.402042 -0.402042)
							(end 0.3302 -0.4318)
						)
					)
					(width 0)
					(fill yes)
				)
			)
		)
	)
	(footprint ""
		(layer "F.Cu")
		(at 31.122366 -242.327176)
		(property "Reference" "R44"
			(at 0 0 0)
			(layer "F.SilkS")
			(hide yes)
			(effects
				(font
					(size 1.27 1.27)
				)
			)
		)
		(property "Value" "4K7R2J-2-GP"
			(at 0.064008 -3.993896 0)
			(unlocked yes)
			(layer "F.Fab")
			(hide yes)
			(effects
				(font
					(size 1.016 1.016)
					(thickness 0.1524)
				)
			)
		)
		(property "Device Type" "R402H16"
			(at 0.064008 -5.517896 0)
			(unlocked yes)
			(layer "F.Fab")
			(hide yes)
			(effects
				(font
					(size 1.016 1.016)
					(thickness 0.1524)
				)
			)
		)
		(duplicate_pad_numbers_are_jumpers no)
		(fp_line
			(start -0.508 -0.9398)
			(end -0.508 0.9398)
			(stroke
				(width 0.1524)
				(type default)
			)
			(layer "F.SilkS")
		)
		(fp_line
			(start 0.508 -0.9398)
			(end -0.508 -0.9398)
			(stroke
				(width 0.1524)
				(type default)
			)
			(layer "F.SilkS")
		)
		(fp_rect
			(start -0.508 0.9398)
			(end 0.508 -0.9398)
			(stroke
				(width 0)
				(type default)
			)
			(fill no)
			(layer "F.CrtYd")
		)
		(fp_rect
			(start -0.508 0.9398)
			(end 0.508 -0.9398)
			(stroke
				(width 0)
				(type default)
			)
			(fill no)
			(layer "F.Fab")
		)
		(pad "1" smd custom
			(at 0 -0.4445)
			(size 0.1397 0.1397)
			(layers "F.Cu" "F.Mask" "F.Paste")
			(net "FCB_EEPROM_A2")
			(options
				(clearance outline)
				(anchor circle)
			)
			(primitives
				(gr_poly
					(pts
						(arc
							(start -0.1778 -0.2794)
							(mid -0.249642 -0.249642)
							(end -0.2794 -0.1778)
						)
						(arc
							(start -0.2794 0.1778)
							(mid -0.249642 0.249642)
							(end -0.1778 0.2794)
						)
						(arc
							(start 0.1778 0.2794)
							(mid 0.249642 0.249642)
							(end 0.2794 0.1778)
						)
						(arc
							(start 0.2794 -0.1778)
							(mid 0.249642 -0.249642)
							(end 0.1778 -0.2794)
						)
					)
					(width 0)
					(fill yes)
				)
			)
		)
		(pad "2" smd custom
			(at 0 0.4445)
			(size 0.1397 0.1397)
			(layers "F.Cu" "F.Mask" "F.Paste")
			(net "GND")
			(options
				(clearance outline)
				(anchor circle)
			)
			(primitives
				(gr_poly
					(pts
						(arc
							(start -0.1778 -0.2794)
							(mid -0.249642 -0.249642)
							(end -0.2794 -0.1778)
						)
						(arc
							(start -0.2794 0.1778)
							(mid -0.249642 0.249642)
							(end -0.1778 0.2794)
						)
						(arc
							(start 0.1778 0.2794)
							(mid 0.249642 0.249642)
							(end 0.2794 0.1778)
						)
						(arc
							(start 0.2794 -0.1778)
							(mid 0.249642 -0.249642)
							(end 0.1778 -0.2794)
						)
					)
					(width 0)
					(fill yes)
				)
			)
		)
	)
	(footprint ""
		(layer "F.Cu")
		(at 12.6746 -225.8822 180)
		(property "Reference" "R124"
			(at 0 0 180)
			(layer "F.SilkS")
			(hide yes)
			(effects
				(font
					(size 1.27 1.27)
				)
			)
		)
		(property "Value" "1K8R6J-GP"
			(at -0.0508 -4.8514 180)
			(unlocked yes)
			(layer "F.Fab")
			(hide yes)
			(effects
				(font
					(size 1.016 1.016)
					(thickness 0.1524)
				)
			)
		)
		(property "Device Type" "R1206H28"
			(at 0 -6.3754 180)
			(unlocked yes)
			(layer "F.Fab")
			(hide yes)
			(effects
				(font
					(size 1.016 1.016)
					(thickness 0.1524)
				)
			)
		)
		(duplicate_pad_numbers_are_jumpers no)
		(fp_line
			(start 1.016 2.2352)
			(end -1.016 2.2352)
			(stroke
				(width 0.1524)
				(type default)
			)
			(layer "F.SilkS")
		)
		(fp_line
			(start 1.016 -2.2352)
			(end 1.016 2.2352)
			(stroke
				(width 0.1524)
				(type default)
			)
			(layer "F.SilkS")
		)
		(fp_line
			(start -1.016 2.2352)
			(end -1.016 -2.2352)
			(stroke
				(width 0.1524)
				(type default)
			)
			(layer "F.SilkS")
		)
		(fp_line
			(start -1.016 -2.2352)
			(end 1.016 -2.2352)
			(stroke
				(width 0.1524)
				(type default)
			)
			(layer "F.SilkS")
		)
		(fp_rect
			(start -1.0922 2.3114)
			(end 1.0922 -2.3114)
			(stroke
				(width 0)
				(type default)
			)
			(fill no)
			(layer "F.CrtYd")
		)
		(fp_poly
			(pts
				(xy -1.0922 -2.3114) (xy 1.0922 -2.3114) (xy 1.0922 2.3114) (xy -1.0922 2.3114)
			)
			(stroke
				(width 0)
				(type default)
			)
			(fill no)
			(layer "F.Fab")
		)
		(pad "1" smd rect
			(at 0 -1.397 180)
			(size 1.651 1.27)
			(layers "F.Cu" "F.Mask" "F.Paste")
			(net "P12V")
		)
		(pad "2" smd rect
			(at 0 1.397 180)
			(size 1.651 1.27)
			(layers "F.Cu" "F.Mask" "F.Paste")
			(net "LED_DR_LED3_BLUE")
		)
	)
	(footprint ""
		(layer "F.Cu")
		(at 7.141972 -277.643082 90)
		(property "Reference" "Q6"
			(at 0 0 90)
			(layer "F.SilkS")
			(hide yes)
			(effects
				(font
					(size 1.27 1.27)
				)
			)
		)
		(property "Value" "PMBS3904-1-GP"
			(at 0 -9.0932 90)
			(unlocked yes)
			(layer "F.Fab")
			(hide yes)
			(effects
				(font
					(size 1.016 1.016)
					(thickness 0.1524)
				)
			)
		)
		(property "Device Type" "SOT-23-10H44"
			(at 0 -10.6172 90)
			(unlocked yes)
			(layer "F.Fab")
			(hide yes)
			(effects
				(font
					(size 1.016 1.016)
					(thickness 0.1524)
				)
			)
		)
		(duplicate_pad_numbers_are_jumpers no)
		(fp_line
			(start 1.651 -1.778)
			(end -1.651 -1.778)
			(stroke
				(width 0.1524)
				(type default)
			)
			(layer "F.SilkS")
		)
		(fp_line
			(start -1.651 -1.778)
			(end -1.651 1.778)
			(stroke
				(width 0.1524)
				(type default)
			)
			(layer "F.SilkS")
		)
		(fp_line
			(start 1.651 1.778)
			(end 1.651 -1.778)
			(stroke
				(width 0.1524)
				(type default)
			)
			(layer "F.SilkS")
		)
		(fp_line
			(start -1.651 1.778)
			(end 1.651 1.778)
			(stroke
				(width 0.1524)
				(type default)
			)
			(layer "F.SilkS")
		)
		(fp_line
			(start -0.9906 1.86309)
			(end -0.701294 2.15265)
			(stroke
				(width 0.0127)
				(type default)
			)
			(layer "F.SilkS")
		)
		(fp_line
			(start -0.994156 1.8669)
			(end -0.987044 1.8669)
			(stroke
				(width 0.0127)
				(type default)
			)
			(layer "F.SilkS")
		)
		(fp_line
			(start -1.003808 1.876552)
			(end -0.977646 1.876552)
			(stroke
				(width 0.0127)
				(type default)
			)
			(layer "F.SilkS")
		)
		(fp_line
			(start -0.635 1.8796)
			(end -1.7526 1.8796)
			(stroke
				(width 0.3302)
				(type default)
			)
			(layer "F.SilkS")
		)
		(fp_line
			(start -1.7526 1.8796)
			(end -1.7526 0.9906)
			(stroke
				(width 0.3302)
				(type default)
			)
			(layer "F.SilkS")
		)
		(fp_line
			(start -1.013206 1.88595)
			(end -0.967994 1.88595)
			(stroke
				(width 0.0127)
				(type default)
			)
			(layer "F.SilkS")
		)
		(fp_line
			(start -1.022858 1.895602)
			(end -0.958596 1.895602)
			(stroke
				(width 0.0127)
				(type default)
			)
			(layer "F.SilkS")
		)
		(fp_line
			(start -1.032256 1.905)
			(end -0.948944 1.905)
			(stroke
				(width 0.0127)
				(type default)
			)
			(layer "F.SilkS")
		)
		(fp_line
			(start -1.041908 1.914652)
			(end -0.939546 1.914652)
			(stroke
				(width 0.0127)
				(type default)
			)
			(layer "F.SilkS")
		)
		(fp_line
			(start -1.051306 1.92405)
			(end -0.929894 1.92405)
			(stroke
				(width 0.0127)
				(type default)
			)
			(layer "F.SilkS")
		)
		(fp_line
			(start -1.060958 1.933702)
			(end -0.920496 1.933702)
			(stroke
				(width 0.0127)
				(type default)
			)
			(layer "F.SilkS")
		)
		(fp_line
			(start -1.070356 1.9431)
			(end -0.910844 1.9431)
			(stroke
				(width 0.0127)
				(type default)
			)
			(layer "F.SilkS")
		)
		(fp_line
			(start -1.080008 1.952752)
			(end -0.901446 1.952752)
			(stroke
				(width 0.0127)
				(type default)
			)
			(layer "F.SilkS")
		)
		(fp_line
			(start -1.089406 1.96215)
			(end -0.891794 1.96215)
			(stroke
				(width 0.0127)
				(type default)
			)
			(layer "F.SilkS")
		)
		(fp_line
			(start -1.099058 1.971802)
			(end -0.882396 1.971802)
			(stroke
				(width 0.0127)
				(type default)
			)
			(layer "F.SilkS")
		)
		(fp_line
			(start -1.108456 1.9812)
			(end -0.872744 1.9812)
			(stroke
				(width 0.0127)
				(type default)
			)
			(layer "F.SilkS")
		)
		(fp_line
			(start -1.118108 1.990852)
			(end -0.863346 1.990852)
			(stroke
				(width 0.0127)
				(type default)
			)
			(layer "F.SilkS")
		)
		(fp_line
			(start -1.127506 2.00025)
			(end -0.853694 2.00025)
			(stroke
				(width 0.0127)
				(type default)
			)
			(layer "F.SilkS")
		)
		(fp_line
			(start -1.137158 2.009902)
			(end -0.844296 2.009902)
			(stroke
				(width 0.0127)
				(type default)
			)
			(layer "F.SilkS")
		)
		(fp_line
			(start -1.146556 2.0193)
			(end -0.834644 2.0193)
			(stroke
				(width 0.0127)
				(type default)
			)
			(layer "F.SilkS")
		)
		(fp_line
			(start -1.156208 2.028952)
			(end -0.825246 2.028952)
			(stroke
				(width 0.0127)
				(type default)
			)
			(layer "F.SilkS")
		)
		(fp_line
			(start -1.165606 2.03835)
			(end -0.815594 2.03835)
			(stroke
				(width 0.0127)
				(type default)
			)
			(layer "F.SilkS")
		)
		(fp_line
			(start -1.175258 2.048002)
			(end -0.806196 2.048002)
			(stroke
				(width 0.0127)
				(type default)
			)
			(layer "F.SilkS")
		)
		(fp_line
			(start -1.184656 2.0574)
			(end -0.796544 2.0574)
			(stroke
				(width 0.0127)
				(type default)
			)
			(layer "F.SilkS")
		)
		(fp_line
			(start -1.194308 2.067052)
			(end -0.787146 2.067052)
			(stroke
				(width 0.0127)
				(type default)
			)
			(layer "F.SilkS")
		)
		(fp_line
			(start -1.203706 2.07645)
			(end -0.777494 2.07645)
			(stroke
				(width 0.0127)
				(type default)
			)
			(layer "F.SilkS")
		)
		(fp_line
			(start -1.213358 2.086102)
			(end -0.768096 2.086102)
			(stroke
				(width 0.0127)
				(type default)
			)
			(layer "F.SilkS")
		)
		(fp_line
			(start -1.222756 2.0955)
			(end -0.758444 2.0955)
			(stroke
				(width 0.0127)
				(type default)
			)
			(layer "F.SilkS")
		)
		(fp_line
			(start -1.232408 2.105152)
			(end -0.749046 2.105152)
			(stroke
				(width 0.0127)
				(type default)
			)
			(layer "F.SilkS")
		)
		(fp_line
			(start -1.241806 2.11455)
			(end -0.739394 2.11455)
			(stroke
				(width 0.0127)
				(type default)
			)
			(layer "F.SilkS")
		)
		(fp_line
			(start -1.251458 2.124202)
			(end -0.729996 2.124202)
			(stroke
				(width 0.0127)
				(type default)
			)
			(layer "F.SilkS")
		)
		(fp_line
			(start -1.260856 2.1336)
			(end -0.720344 2.1336)
			(stroke
				(width 0.0127)
				(type default)
			)
			(layer "F.SilkS")
		)
		(fp_line
			(start -0.719074 2.145538)
			(end -1.265936 2.14122)
			(stroke
				(width 0.0127)
				(type default)
			)
			(layer "F.SilkS")
		)
		(fp_line
			(start -1.279398 2.152142)
			(end -0.9906 1.86309)
			(stroke
				(width 0.0127)
				(type default)
			)
			(layer "F.SilkS")
		)
		(fp_line
			(start -0.71628 2.15265)
			(end -1.26492 2.15265)
			(stroke
				(width 0.0127)
				(type default)
			)
			(layer "F.SilkS")
		)
		(fp_line
			(start -1.279144 2.15265)
			(end -0.701294 2.15265)
			(stroke
				(width 0.0127)
				(type default)
			)
			(layer "F.SilkS")
		)
		(fp_poly
			(pts
				(xy -1.285748 2.159) (xy -1.285748 1.8796) (xy -1.778 1.8796) (xy -1.778 -1.8796) (xy 1.778 -1.8796)
				(xy 1.778 1.8796) (xy -0.694944 1.8796) (xy -0.694944 2.159)
			)
			(stroke
				(width 0)
				(type default)
			)
			(fill no)
			(layer "F.CrtYd")
		)
		(fp_poly
			(pts
				(xy -1.285748 2.159) (xy -1.285748 1.8796) (xy -1.778 1.8796) (xy -1.778 -1.8796) (xy 1.778 -1.8796)
				(xy 1.778 1.8796) (xy -0.694944 1.8796) (xy -0.694944 2.159)
			)
			(stroke
				(width 0)
				(type default)
			)
			(fill no)
			(layer "F.Fab")
		)
		(pad "1" smd rect
			(at -0.98425 0.9525 90)
			(size 0.762 1.143)
			(layers "F.Cu" "F.Mask" "F.Paste")
			(net "LED_DR_LED2_B")
		)
		(pad "2" smd rect
			(at 0.98425 0.9525 90)
			(size 0.762 1.143)
			(layers "F.Cu" "F.Mask" "F.Paste")
			(net "GND")
		)
		(pad "3" smd rect
			(at 0 -0.9525 90)
			(size 0.762 1.143)
			(layers "F.Cu" "F.Mask" "F.Paste")
			(net "LED_DR_LED2_BLUE")
		)
	)
	(footprint ""
		(layer "F.Cu")
		(at 20.3454 -481.5586)
		(property "Reference" "R177"
			(at 0 0 0)
			(layer "F.SilkS")
			(hide yes)
			(effects
				(font
					(size 1.27 1.27)
				)
			)
		)
		(property "Value" "0R1206-PAD-1-GP"
			(at 0 -5.0292 0)
			(unlocked yes)
			(layer "F.Fab")
			(hide yes)
			(effects
				(font
					(size 1.016 1.016)
					(thickness 0.1524)
				)
			)
		)
		(property "Device Type" "0R1206-PAD-1"
			(at 0 -6.5532 0)
			(unlocked yes)
			(layer "F.Fab")
			(hide yes)
			(effects
				(font
					(size 1.016 1.016)
					(thickness 0.1524)
				)
			)
		)
		(duplicate_pad_numbers_are_jumpers no)
		(fp_line
			(start -1.016 -2.2352)
			(end -1.016 2.2352)
			(stroke
				(width 0.1524)
				(type default)
			)
			(layer "F.SilkS")
		)
		(fp_line
			(start -1.016 2.2352)
			(end 1.016 2.2352)
			(stroke
				(width 0.1524)
				(type default)
			)
			(layer "F.SilkS")
		)
		(fp_line
			(start 1.016 -2.2352)
			(end -1.016 -2.2352)
			(stroke
				(width 0.1524)
				(type default)
			)
			(layer "F.SilkS")
		)
		(fp_line
			(start 1.016 2.2352)
			(end 1.016 -2.2352)
			(stroke
				(width 0.1524)
				(type default)
			)
			(layer "F.SilkS")
		)
		(fp_rect
			(start -1.0922 2.3114)
			(end 1.0922 -2.3114)
			(stroke
				(width 0)
				(type default)
			)
			(fill no)
			(layer "F.CrtYd")
		)
		(fp_poly
			(pts
				(xy -1.0922 -2.3114) (xy 1.0922 -2.3114) (xy 1.0922 2.3114) (xy -1.0922 2.3114)
			)
			(stroke
				(width 0)
				(type default)
			)
			(fill no)
			(layer "F.Fab")
		)
		(pad "1" smd rect
			(at 0 -1.397)
			(size 1.651 2.0574)
			(drill
				(offset 0 0.3937)
			)
			(layers "F.Cu" "F.Mask" "F.Paste")
			(net "P12V_FAN1")
		)
		(pad "2" smd rect
			(at 0 1.397)
			(size 1.651 2.0574)
			(drill
				(offset 0 -0.3937)
			)
			(layers "F.Cu" "F.Mask" "F.Paste")
			(net "P12V")
		)
	)
	(footprint ""
		(layer "F.Cu")
		(at 17.831308 -287.451038)
		(property "Reference" "D9"
			(at 0 0 0)
			(layer "F.SilkS")
			(hide yes)
			(effects
				(font
					(size 1.27 1.27)
				)
			)
		)
		(property "Value" "BAS16H-GP"
			(at 0 -5.5372 0)
			(unlocked yes)
			(layer "F.Fab")
			(hide yes)
			(effects
				(font
					(size 1.016 1.016)
					(thickness 0.1524)
				)
			)
		)
		(property "Device Type" "SOD123AKH48"
			(at 0 -7.0612 0)
			(unlocked yes)
			(layer "F.Fab")
			(hide yes)
			(effects
				(font
					(size 1.016 1.016)
					(thickness 0.1524)
				)
			)
		)
		(duplicate_pad_numbers_are_jumpers no)
		(fp_line
			(start -1.016 -2.667)
			(end -1.016 2.667)
			(stroke
				(width 0.1524)
				(type default)
			)
			(layer "F.SilkS")
		)
		(fp_line
			(start -1.016 2.667)
			(end 1.016 2.667)
			(stroke
				(width 0.1524)
				(type default)
			)
			(layer "F.SilkS")
		)
		(fp_line
			(start 0.889 2.921)
			(end -0.889 2.921)
			(stroke
				(width 0.508)
				(type default)
			)
			(layer "F.SilkS")
		)
		(fp_line
			(start 1.016 -2.667)
			(end -1.016 -2.667)
			(stroke
				(width 0.1524)
				(type default)
			)
			(layer "F.SilkS")
		)
		(fp_line
			(start 1.016 2.667)
			(end 1.016 -2.667)
			(stroke
				(width 0.1524)
				(type default)
			)
			(layer "F.SilkS")
		)
		(fp_rect
			(start -1.143 3.175)
			(end 1.143 -2.794)
			(stroke
				(width 0)
				(type default)
			)
			(fill no)
			(layer "F.CrtYd")
		)
		(fp_poly
			(pts
				(xy -1.143 -2.794) (xy 1.143 -2.794) (xy 1.143 3.175) (xy -1.143 3.175)
			)
			(stroke
				(width 0)
				(type default)
			)
			(fill no)
			(layer "F.Fab")
		)
		(pad "A" smd rect
			(at 0 -1.6891)
			(size 0.889 1.397)
			(layers "F.Cu" "F.Mask" "F.Paste")
			(net "FAN_TACH3")
		)
		(pad "K" smd rect
			(at 0 1.6891)
			(size 0.889 1.397)
			(layers "F.Cu" "F.Mask" "F.Paste")
			(net "P12V")
		)
	)
	(footprint ""
		(layer "F.Cu")
		(at 40.259 -178.054 180)
		(property "Reference" "R260"
			(at 0 0 180)
			(layer "F.SilkS")
			(hide yes)
			(effects
				(font
					(size 1.27 1.27)
				)
			)
		)
		(property "Value" "47KR2J-2-GP"
			(at 0.064008 -3.993896 180)
			(unlocked yes)
			(layer "F.Fab")
			(hide yes)
			(effects
				(font
					(size 1.016 1.016)
					(thickness 0.1524)
				)
			)
		)
		(property "Device Type" "R402H16"
			(at 0.064008 -5.517896 180)
			(unlocked yes)
			(layer "F.Fab")
			(hide yes)
			(effects
				(font
					(size 1.016 1.016)
					(thickness 0.1524)
				)
			)
		)
		(duplicate_pad_numbers_are_jumpers no)
		(fp_line
			(start 0.508 -0.9398)
			(end -0.508 -0.9398)
			(stroke
				(width 0.1524)
				(type default)
			)
			(layer "F.SilkS")
		)
		(fp_line
			(start -0.508 -0.9398)
			(end -0.508 0.9398)
			(stroke
				(width 0.1524)
				(type default)
			)
			(layer "F.SilkS")
		)
		(fp_rect
			(start -0.508 0.9398)
			(end 0.508 -0.9398)
			(stroke
				(width 0)
				(type default)
			)
			(fill no)
			(layer "F.CrtYd")
		)
		(fp_rect
			(start -0.508 0.9398)
			(end 0.508 -0.9398)
			(stroke
				(width 0)
				(type default)
			)
			(fill no)
			(layer "F.Fab")
		)
		(pad "1" smd custom
			(at 0 -0.4445 180)
			(size 0.1397 0.1397)
			(layers "F.Cu" "F.Mask" "F.Paste")
			(net "P3V3_AUX")
			(options
				(clearance outline)
				(anchor circle)
			)
			(primitives
				(gr_poly
					(pts
						(arc
							(start -0.1778 -0.2794)
							(mid -0.249642 -0.249642)
							(end -0.2794 -0.1778)
						)
						(arc
							(start -0.2794 0.1778)
							(mid -0.249642 0.249642)
							(end -0.1778 0.2794)
						)
						(arc
							(start 0.1778 0.2794)
							(mid 0.249642 0.249642)
							(end 0.2794 0.1778)
						)
						(arc
							(start 0.2794 -0.1778)
							(mid 0.249642 -0.249642)
							(end 0.1778 -0.2794)
						)
					)
					(width 0)
					(fill yes)
				)
			)
		)
		(pad "2" smd custom
			(at 0 0.4445 180)
			(size 0.1397 0.1397)
			(layers "F.Cu" "F.Mask" "F.Paste")
			(net "D_LATCH_PRE#")
			(options
				(clearance outline)
				(anchor circle)
			)
			(primitives
				(gr_poly
					(pts
						(arc
							(start -0.1778 -0.2794)
							(mid -0.249642 -0.249642)
							(end -0.2794 -0.1778)
						)
						(arc
							(start -0.2794 0.1778)
							(mid -0.249642 0.249642)
							(end -0.1778 0.2794)
						)
						(arc
							(start 0.1778 0.2794)
							(mid 0.249642 0.249642)
							(end 0.2794 0.1778)
						)
						(arc
							(start 0.2794 -0.1778)
							(mid 0.249642 -0.249642)
							(end 0.1778 -0.2794)
						)
					)
					(width 0)
					(fill yes)
				)
			)
		)
	)
	(footprint ""
		(layer "F.Cu")
		(at 17.271492 -13.919962 180)
		(property "Reference" "R69"
			(at 0 0 180)
			(layer "F.SilkS")
			(hide yes)
			(effects
				(font
					(size 1.27 1.27)
				)
			)
		)
		(property "Value" "4K7R2F-GP"
			(at 0.064008 -3.993896 180)
			(unlocked yes)
			(layer "F.Fab")
			(hide yes)
			(effects
				(font
					(size 1.016 1.016)
					(thickness 0.1524)
				)
			)
		)
		(property "Device Type" "R402H16"
			(at 0.064008 -5.517896 180)
			(unlocked yes)
			(layer "F.Fab")
			(hide yes)
			(effects
				(font
					(size 1.016 1.016)
					(thickness 0.1524)
				)
			)
		)
		(duplicate_pad_numbers_are_jumpers no)
		(fp_line
			(start 0.508 -0.9398)
			(end -0.508 -0.9398)
			(stroke
				(width 0.1524)
				(type default)
			)
			(layer "F.SilkS")
		)
		(fp_line
			(start -0.508 -0.9398)
			(end -0.508 0.9398)
			(stroke
				(width 0.1524)
				(type default)
			)
			(layer "F.SilkS")
		)
		(fp_rect
			(start -0.508 0.9398)
			(end 0.508 -0.9398)
			(stroke
				(width 0)
				(type default)
			)
			(fill no)
			(layer "F.CrtYd")
		)
		(fp_rect
			(start -0.508 0.9398)
			(end 0.508 -0.9398)
			(stroke
				(width 0)
				(type default)
			)
			(fill no)
			(layer "F.Fab")
		)
		(pad "1" smd custom
			(at 0 -0.4445 180)
			(size 0.1397 0.1397)
			(layers "F.Cu" "F.Mask" "F.Paste")
			(net "P12V")
			(options
				(clearance outline)
				(anchor circle)
			)
			(primitives
				(gr_poly
					(pts
						(arc
							(start -0.1778 -0.2794)
							(mid -0.249642 -0.249642)
							(end -0.2794 -0.1778)
						)
						(arc
							(start -0.2794 0.1778)
							(mid -0.249642 0.249642)
							(end -0.1778 0.2794)
						)
						(arc
							(start 0.1778 0.2794)
							(mid 0.249642 0.249642)
							(end 0.2794 0.1778)
						)
						(arc
							(start 0.2794 -0.1778)
							(mid 0.249642 -0.249642)
							(end 0.1778 -0.2794)
						)
					)
					(width 0)
					(fill yes)
				)
			)
		)
		(pad "2" smd custom
			(at 0 0.4445 180)
			(size 0.1397 0.1397)
			(layers "F.Cu" "F.Mask" "F.Paste")
			(net "FAN_TACH11")
			(options
				(clearance outline)
				(anchor circle)
			)
			(primitives
				(gr_poly
					(pts
						(arc
							(start -0.1778 -0.2794)
							(mid -0.249642 -0.249642)
							(end -0.2794 -0.1778)
						)
						(arc
							(start -0.2794 0.1778)
							(mid -0.249642 0.249642)
							(end -0.1778 0.2794)
						)
						(arc
							(start 0.1778 0.2794)
							(mid 0.249642 0.249642)
							(end 0.2794 0.1778)
						)
						(arc
							(start 0.2794 -0.1778)
							(mid 0.249642 -0.249642)
							(end 0.1778 -0.2794)
						)
					)
					(width 0)
					(fill yes)
				)
			)
		)
	)
	(footprint ""
		(layer "F.Cu")
		(at 33.91789 -167.723566 180)
		(property "Reference" "R11"
			(at 0 0 180)
			(layer "F.SilkS")
			(hide yes)
			(effects
				(font
					(size 1.27 1.27)
				)
			)
		)
		(property "Value" "100KR2J-1-GP"
			(at 0.064008 -3.993896 180)
			(unlocked yes)
			(layer "F.Fab")
			(hide yes)
			(effects
				(font
					(size 1.016 1.016)
					(thickness 0.1524)
				)
			)
		)
		(property "Device Type" "R402H16"
			(at 0.064008 -5.517896 180)
			(unlocked yes)
			(layer "F.Fab")
			(hide yes)
			(effects
				(font
					(size 1.016 1.016)
					(thickness 0.1524)
				)
			)
		)
		(duplicate_pad_numbers_are_jumpers no)
		(fp_line
			(start 0.508 -0.9398)
			(end -0.508 -0.9398)
			(stroke
				(width 0.1524)
				(type default)
			)
			(layer "F.SilkS")
		)
		(fp_line
			(start -0.508 -0.9398)
			(end -0.508 0.9398)
			(stroke
				(width 0.1524)
				(type default)
			)
			(layer "F.SilkS")
		)
		(fp_rect
			(start -0.508 0.9398)
			(end 0.508 -0.9398)
			(stroke
				(width 0)
				(type default)
			)
			(fill no)
			(layer "F.CrtYd")
		)
		(fp_rect
			(start -0.508 0.9398)
			(end 0.508 -0.9398)
			(stroke
				(width 0)
				(type default)
			)
			(fill no)
			(layer "F.Fab")
		)
		(pad "1" smd custom
			(at 0 -0.4445 180)
			(size 0.1397 0.1397)
			(layers "F.Cu" "F.Mask" "F.Paste")
			(net "NCT7904_ADR")
			(options
				(clearance outline)
				(anchor circle)
			)
			(primitives
				(gr_poly
					(pts
						(arc
							(start -0.1778 -0.2794)
							(mid -0.249642 -0.249642)
							(end -0.2794 -0.1778)
						)
						(arc
							(start -0.2794 0.1778)
							(mid -0.249642 0.249642)
							(end -0.1778 0.2794)
						)
						(arc
							(start 0.1778 0.2794)
							(mid 0.249642 0.249642)
							(end 0.2794 0.1778)
						)
						(arc
							(start 0.2794 -0.1778)
							(mid 0.249642 -0.249642)
							(end 0.1778 -0.2794)
						)
					)
					(width 0)
					(fill yes)
				)
			)
		)
		(pad "2" smd custom
			(at 0 0.4445 180)
			(size 0.1397 0.1397)
			(layers "F.Cu" "F.Mask" "F.Paste")
			(net "GND")
			(options
				(clearance outline)
				(anchor circle)
			)
			(primitives
				(gr_poly
					(pts
						(arc
							(start -0.1778 -0.2794)
							(mid -0.249642 -0.249642)
							(end -0.2794 -0.1778)
						)
						(arc
							(start -0.2794 0.1778)
							(mid -0.249642 0.249642)
							(end -0.1778 0.2794)
						)
						(arc
							(start 0.1778 0.2794)
							(mid 0.249642 0.249642)
							(end 0.2794 0.1778)
						)
						(arc
							(start 0.2794 -0.1778)
							(mid 0.249642 -0.249642)
							(end 0.1778 -0.2794)
						)
					)
					(width 0)
					(fill yes)
				)
			)
		)
	)
	(footprint ""
		(layer "F.Cu")
		(at 26.035 -17.399 90)
		(property "Reference" "D1"
			(at 0 0 90)
			(layer "F.SilkS")
			(hide yes)
			(effects
				(font
					(size 1.27 1.27)
				)
			)
		)
		(property "Value" "BAS16H-GP"
			(at 0 -5.5372 90)
			(unlocked yes)
			(layer "F.Fab")
			(hide yes)
			(effects
				(font
					(size 1.016 1.016)
					(thickness 0.1524)
				)
			)
		)
		(property "Device Type" "SOD123AKH48"
			(at 0 -7.0612 90)
			(unlocked yes)
			(layer "F.Fab")
			(hide yes)
			(effects
				(font
					(size 1.016 1.016)
					(thickness 0.1524)
				)
			)
		)
		(duplicate_pad_numbers_are_jumpers no)
		(fp_line
			(start 1.016 -2.667)
			(end -1.016 -2.667)
			(stroke
				(width 0.1524)
				(type default)
			)
			(layer "F.SilkS")
		)
		(fp_line
			(start -1.016 -2.667)
			(end -1.016 2.667)
			(stroke
				(width 0.1524)
				(type default)
			)
			(layer "F.SilkS")
		)
		(fp_line
			(start 1.016 2.667)
			(end 1.016 -2.667)
			(stroke
				(width 0.1524)
				(type default)
			)
			(layer "F.SilkS")
		)
		(fp_line
			(start -1.016 2.667)
			(end 1.016 2.667)
			(stroke
				(width 0.1524)
				(type default)
			)
			(layer "F.SilkS")
		)
		(fp_line
			(start 0.889 2.921)
			(end -0.889 2.921)
			(stroke
				(width 0.508)
				(type default)
			)
			(layer "F.SilkS")
		)
		(fp_rect
			(start -1.143 3.175)
			(end 1.143 -2.794)
			(stroke
				(width 0)
				(type default)
			)
			(fill no)
			(layer "F.CrtYd")
		)
		(fp_poly
			(pts
				(xy -1.143 -2.794) (xy 1.143 -2.794) (xy 1.143 3.175) (xy -1.143 3.175)
			)
			(stroke
				(width 0)
				(type default)
			)
			(fill no)
			(layer "F.Fab")
		)
		(pad "A" smd rect
			(at 0 -1.6891 90)
			(size 0.889 1.397)
			(layers "F.Cu" "F.Mask" "F.Paste")
			(net "FAN_TACH12")
		)
		(pad "K" smd rect
			(at 0 1.6891 90)
			(size 0.889 1.397)
			(layers "F.Cu" "F.Mask" "F.Paste")
			(net "P12V")
		)
	)
	(footprint ""
		(layer "F.Cu")
		(at 13.6652 -256.8702)
		(property "Reference" "C38"
			(at 0 0 0)
			(layer "F.SilkS")
			(hide yes)
			(effects
				(font
					(size 1.27 1.27)
				)
			)
		)
		(property "Value" "SCD1U16V2KX-3GP"
			(at 1.1811 -2.7051 0)
			(unlocked yes)
			(layer "F.Fab")
			(hide yes)
			(effects
				(font
					(size 1.016 1.016)
					(thickness 0.1524)
				)
			)
		)
		(property "Device Type" "C402H22"
			(at 1.1811 -4.2291 0)
			(unlocked yes)
			(layer "F.Fab")
			(hide yes)
			(effects
				(font
					(size 1.016 1.016)
					(thickness 0.1524)
				)
			)
		)
		(duplicate_pad_numbers_are_jumpers no)
		(fp_rect
			(start -0.4318 0.9525)
			(end 0.4318 -0.9525)
			(stroke
				(width 0)
				(type default)
			)
			(fill no)
			(layer "F.CrtYd")
		)
		(fp_rect
			(start -0.4318 0.9525)
			(end 0.4318 -0.9525)
			(stroke
				(width 0)
				(type default)
			)
			(fill no)
			(layer "F.Fab")
		)
		(pad "1" smd custom
			(at 0 -0.4445)
			(size 0.1524 0.1524)
			(layers "F.Cu" "F.Mask" "F.Paste")
			(net "FAN_TACH5")
			(options
				(clearance outline)
				(anchor circle)
			)
			(primitives
				(gr_poly
					(pts
						(arc
							(start 0.3048 -0.2032)
							(mid 0.275042 -0.275042)
							(end 0.2032 -0.3048)
						)
						(arc
							(start -0.2032 -0.3048)
							(mid -0.275042 -0.275042)
							(end -0.3048 -0.2032)
						)
						(arc
							(start -0.3048 0.2032)
							(mid -0.275042 0.275042)
							(end -0.2032 0.3048)
						)
						(arc
							(start 0.2032 0.3048)
							(mid 0.275042 0.275042)
							(end 0.3048 0.2032)
						)
					)
					(width 0)
					(fill yes)
				)
			)
		)
		(pad "2" smd custom
			(at 0 0.4445)
			(size 0.1524 0.1524)
			(layers "F.Cu" "F.Mask" "F.Paste")
			(net "GND")
			(options
				(clearance outline)
				(anchor circle)
			)
			(primitives
				(gr_poly
					(pts
						(arc
							(start 0.3048 -0.2032)
							(mid 0.275042 -0.275042)
							(end 0.2032 -0.3048)
						)
						(arc
							(start -0.2032 -0.3048)
							(mid -0.275042 -0.275042)
							(end -0.3048 -0.2032)
						)
						(arc
							(start -0.3048 0.2032)
							(mid -0.275042 0.275042)
							(end -0.2032 0.3048)
						)
						(arc
							(start 0.2032 0.3048)
							(mid 0.275042 0.275042)
							(end 0.3048 0.2032)
						)
					)
					(width 0)
					(fill yes)
				)
			)
		)
	)
	(footprint ""
		(layer "F.Cu")
		(at 14.8844 -43.5102 -90)
		(property "Reference" "R118"
			(at 0 0 270)
			(layer "F.SilkS")
			(hide yes)
			(effects
				(font
					(size 1.27 1.27)
				)
			)
		)
		(property "Value" "470R2F-GP"
			(at 0.064008 -3.993896 270)
			(unlocked yes)
			(layer "F.Fab")
			(hide yes)
			(effects
				(font
					(size 1.016 1.016)
					(thickness 0.1524)
				)
			)
		)
		(property "Device Type" "R402H16"
			(at 0.064008 -5.517896 270)
			(unlocked yes)
			(layer "F.Fab")
			(hide yes)
			(effects
				(font
					(size 1.016 1.016)
					(thickness 0.1524)
				)
			)
		)
		(duplicate_pad_numbers_are_jumpers no)
		(fp_line
			(start -0.508 -0.9398)
			(end -0.508 0.9398)
			(stroke
				(width 0.1524)
				(type default)
			)
			(layer "F.SilkS")
		)
		(fp_line
			(start 0.508 -0.9398)
			(end -0.508 -0.9398)
			(stroke
				(width 0.1524)
				(type default)
			)
			(layer "F.SilkS")
		)
		(fp_rect
			(start -0.508 0.9398)
			(end 0.508 -0.9398)
			(stroke
				(width 0)
				(type default)
			)
			(fill no)
			(layer "F.CrtYd")
		)
		(fp_rect
			(start -0.508 0.9398)
			(end 0.508 -0.9398)
			(stroke
				(width 0)
				(type default)
			)
			(fill no)
			(layer "F.Fab")
		)
		(pad "1" smd custom
			(at 0 -0.4445 270)
			(size 0.1397 0.1397)
			(layers "F.Cu" "F.Mask" "F.Paste")
			(net "SEB_PEER_2A_HB")
			(options
				(clearance outline)
				(anchor circle)
			)
			(primitives
				(gr_poly
					(pts
						(arc
							(start -0.1778 -0.2794)
							(mid -0.249642 -0.249642)
							(end -0.2794 -0.1778)
						)
						(arc
							(start -0.2794 0.1778)
							(mid -0.249642 0.249642)
							(end -0.1778 0.2794)
						)
						(arc
							(start 0.1778 0.2794)
							(mid 0.249642 0.249642)
							(end 0.2794 0.1778)
						)
						(arc
							(start 0.2794 -0.1778)
							(mid 0.249642 -0.249642)
							(end 0.1778 -0.2794)
						)
					)
					(width 0)
					(fill yes)
				)
			)
		)
		(pad "2" smd custom
			(at 0 0.4445 270)
			(size 0.1397 0.1397)
			(layers "F.Cu" "F.Mask" "F.Paste")
			(net "GND")
			(options
				(clearance outline)
				(anchor circle)
			)
			(primitives
				(gr_poly
					(pts
						(arc
							(start -0.1778 -0.2794)
							(mid -0.249642 -0.249642)
							(end -0.2794 -0.1778)
						)
						(arc
							(start -0.2794 0.1778)
							(mid -0.249642 0.249642)
							(end -0.1778 0.2794)
						)
						(arc
							(start 0.1778 0.2794)
							(mid 0.249642 0.249642)
							(end 0.2794 0.1778)
						)
						(arc
							(start 0.2794 -0.1778)
							(mid 0.249642 -0.249642)
							(end 0.1778 -0.2794)
						)
					)
					(width 0)
					(fill yes)
				)
			)
		)
	)
	(footprint ""
		(layer "F.Cu")
		(at 9.3218 -454.2028 -90)
		(property "Reference" "R96"
			(at 0 0 270)
			(layer "F.SilkS")
			(hide yes)
			(effects
				(font
					(size 1.27 1.27)
				)
			)
		)
		(property "Value" "4K7R2F-GP"
			(at 0.064008 -3.993896 270)
			(unlocked yes)
			(layer "F.Fab")
			(hide yes)
			(effects
				(font
					(size 1.016 1.016)
					(thickness 0.1524)
				)
			)
		)
		(property "Device Type" "R402H16"
			(at 0.064008 -5.517896 270)
			(unlocked yes)
			(layer "F.Fab")
			(hide yes)
			(effects
				(font
					(size 1.016 1.016)
					(thickness 0.1524)
				)
			)
		)
		(duplicate_pad_numbers_are_jumpers no)
		(fp_line
			(start -0.508 -0.9398)
			(end -0.508 0.9398)
			(stroke
				(width 0.1524)
				(type default)
			)
			(layer "F.SilkS")
		)
		(fp_line
			(start 0.508 -0.9398)
			(end -0.508 -0.9398)
			(stroke
				(width 0.1524)
				(type default)
			)
			(layer "F.SilkS")
		)
		(fp_rect
			(start -0.508 0.9398)
			(end 0.508 -0.9398)
			(stroke
				(width 0)
				(type default)
			)
			(fill no)
			(layer "F.CrtYd")
		)
		(fp_rect
			(start -0.508 0.9398)
			(end 0.508 -0.9398)
			(stroke
				(width 0)
				(type default)
			)
			(fill no)
			(layer "F.Fab")
		)
		(pad "1" smd custom
			(at 0 -0.4445 270)
			(size 0.1397 0.1397)
			(layers "F.Cu" "F.Mask" "F.Paste")
			(net "P12V")
			(options
				(clearance outline)
				(anchor circle)
			)
			(primitives
				(gr_poly
					(pts
						(arc
							(start -0.1778 -0.2794)
							(mid -0.249642 -0.249642)
							(end -0.2794 -0.1778)
						)
						(arc
							(start -0.2794 0.1778)
							(mid -0.249642 0.249642)
							(end -0.1778 0.2794)
						)
						(arc
							(start 0.1778 0.2794)
							(mid 0.249642 0.249642)
							(end 0.2794 0.1778)
						)
						(arc
							(start 0.2794 -0.1778)
							(mid 0.249642 -0.249642)
							(end 0.1778 -0.2794)
						)
					)
					(width 0)
					(fill yes)
				)
			)
		)
		(pad "2" smd custom
			(at 0 0.4445 270)
			(size 0.1397 0.1397)
			(layers "F.Cu" "F.Mask" "F.Paste")
			(net "PWM_OUT_FAN1_NET")
			(options
				(clearance outline)
				(anchor circle)
			)
			(primitives
				(gr_poly
					(pts
						(arc
							(start -0.1778 -0.2794)
							(mid -0.249642 -0.249642)
							(end -0.2794 -0.1778)
						)
						(arc
							(start -0.2794 0.1778)
							(mid -0.249642 0.249642)
							(end -0.1778 0.2794)
						)
						(arc
							(start 0.1778 0.2794)
							(mid 0.249642 0.249642)
							(end 0.2794 0.1778)
						)
						(arc
							(start 0.2794 -0.1778)
							(mid 0.249642 -0.249642)
							(end 0.1778 -0.2794)
						)
					)
					(width 0)
					(fill yes)
				)
			)
		)
	)
	(footprint ""
		(layer "F.Cu")
		(at 22.225 -222.416116 180)
		(property "Reference" "C16"
			(at 0 0 180)
			(layer "F.SilkS")
			(hide yes)
			(effects
				(font
					(size 1.27 1.27)
				)
			)
		)
		(property "Value" "SCD1U50V3KX-GP"
			(at 0 -2.8194 180)
			(unlocked yes)
			(layer "F.Fab")
			(hide yes)
			(effects
				(font
					(size 1.016 1.016)
					(thickness 0.1524)
				)
			)
		)
		(property "Device Type" "C603H36"
			(at 0 -4.3434 180)
			(unlocked yes)
			(layer "F.Fab")
			(hide yes)
			(effects
				(font
					(size 1.016 1.016)
					(thickness 0.1524)
				)
			)
		)
		(duplicate_pad_numbers_are_jumpers no)
		(fp_line
			(start 0.508 0)
			(end -0.508 0)
			(stroke
				(width 0.2032)
				(type default)
			)
			(layer "F.SilkS")
		)
		(fp_rect
			(start -0.5842 1.3335)
			(end 0.5842 -1.3335)
			(stroke
				(width 0)
				(type default)
			)
			(fill no)
			(layer "F.CrtYd")
		)
		(fp_rect
			(start -0.5842 1.3335)
			(end 0.5842 -1.3335)
			(stroke
				(width 0)
				(type default)
			)
			(fill no)
			(layer "F.Fab")
		)
		(pad "1" smd custom
			(at 0 -0.762 180)
			(size 0.2159 0.2159)
			(layers "F.Cu" "F.Mask" "F.Paste")
			(net "P3V3")
			(options
				(clearance outline)
				(anchor circle)
			)
			(primitives
				(gr_poly
					(pts
						(arc
							(start -0.3302 -0.4318)
							(mid -0.402042 -0.402042)
							(end -0.4318 -0.3302)
						)
						(arc
							(start -0.4318 0.3302)
							(mid -0.402042 0.402042)
							(end -0.3302 0.4318)
						)
						(arc
							(start 0.3302 0.4318)
							(mid 0.402042 0.402042)
							(end 0.4318 0.3302)
						)
						(arc
							(start 0.4318 -0.3302)
							(mid 0.402042 -0.402042)
							(end 0.3302 -0.4318)
						)
					)
					(width 0)
					(fill yes)
				)
			)
		)
		(pad "2" smd custom
			(at 0 0.762 180)
			(size 0.2159 0.2159)
			(layers "F.Cu" "F.Mask" "F.Paste")
			(net "GND")
			(options
				(clearance outline)
				(anchor circle)
			)
			(primitives
				(gr_poly
					(pts
						(arc
							(start -0.3302 -0.4318)
							(mid -0.402042 -0.402042)
							(end -0.4318 -0.3302)
						)
						(arc
							(start -0.4318 0.3302)
							(mid -0.402042 0.402042)
							(end -0.3302 0.4318)
						)
						(arc
							(start 0.3302 0.4318)
							(mid 0.402042 0.402042)
							(end 0.4318 0.3302)
						)
						(arc
							(start 0.4318 -0.3302)
							(mid 0.402042 -0.402042)
							(end 0.3302 -0.4318)
						)
					)
					(width 0)
					(fill yes)
				)
			)
		)
	)
	(footprint ""
		(layer "F.Cu")
		(at 18.8214 -259.3086 -90)
		(property "Reference" "R78"
			(at 0 0 270)
			(layer "F.SilkS")
			(hide yes)
			(effects
				(font
					(size 1.27 1.27)
				)
			)
		)
		(property "Value" "4K7R2F-GP"
			(at 0.064008 -3.993896 270)
			(unlocked yes)
			(layer "F.Fab")
			(hide yes)
			(effects
				(font
					(size 1.016 1.016)
					(thickness 0.1524)
				)
			)
		)
		(property "Device Type" "R402H16"
			(at 0.064008 -5.517896 270)
			(unlocked yes)
			(layer "F.Fab")
			(hide yes)
			(effects
				(font
					(size 1.016 1.016)
					(thickness 0.1524)
				)
			)
		)
		(duplicate_pad_numbers_are_jumpers no)
		(fp_line
			(start -0.508 -0.9398)
			(end -0.508 0.9398)
			(stroke
				(width 0.1524)
				(type default)
			)
			(layer "F.SilkS")
		)
		(fp_line
			(start 0.508 -0.9398)
			(end -0.508 -0.9398)
			(stroke
				(width 0.1524)
				(type default)
			)
			(layer "F.SilkS")
		)
		(fp_rect
			(start -0.508 0.9398)
			(end 0.508 -0.9398)
			(stroke
				(width 0)
				(type default)
			)
			(fill no)
			(layer "F.CrtYd")
		)
		(fp_rect
			(start -0.508 0.9398)
			(end 0.508 -0.9398)
			(stroke
				(width 0)
				(type default)
			)
			(fill no)
			(layer "F.Fab")
		)
		(pad "1" smd custom
			(at 0 -0.4445 270)
			(size 0.1397 0.1397)
			(layers "F.Cu" "F.Mask" "F.Paste")
			(net "P12V")
			(options
				(clearance outline)
				(anchor circle)
			)
			(primitives
				(gr_poly
					(pts
						(arc
							(start -0.1778 -0.2794)
							(mid -0.249642 -0.249642)
							(end -0.2794 -0.1778)
						)
						(arc
							(start -0.2794 0.1778)
							(mid -0.249642 0.249642)
							(end -0.1778 0.2794)
						)
						(arc
							(start 0.1778 0.2794)
							(mid 0.249642 0.249642)
							(end 0.2794 0.1778)
						)
						(arc
							(start 0.2794 -0.1778)
							(mid 0.249642 -0.249642)
							(end 0.1778 -0.2794)
						)
					)
					(width 0)
					(fill yes)
				)
			)
		)
		(pad "2" smd custom
			(at 0 0.4445 270)
			(size 0.1397 0.1397)
			(layers "F.Cu" "F.Mask" "F.Paste")
			(net "PWM_OUT_FAN3_NET")
			(options
				(clearance outline)
				(anchor circle)
			)
			(primitives
				(gr_poly
					(pts
						(arc
							(start -0.1778 -0.2794)
							(mid -0.249642 -0.249642)
							(end -0.2794 -0.1778)
						)
						(arc
							(start -0.2794 0.1778)
							(mid -0.249642 0.249642)
							(end -0.1778 0.2794)
						)
						(arc
							(start 0.1778 0.2794)
							(mid 0.249642 0.249642)
							(end 0.2794 0.1778)
						)
						(arc
							(start 0.2794 -0.1778)
							(mid 0.249642 -0.249642)
							(end 0.1778 -0.2794)
						)
					)
					(width 0)
					(fill yes)
				)
			)
		)
	)
	(footprint ""
		(layer "F.Cu")
		(at 34.29 -254.381 180)
		(property "Reference" "R106"
			(at 0 0 180)
			(layer "F.SilkS")
			(hide yes)
			(effects
				(font
					(size 1.27 1.27)
				)
			)
		)
		(property "Value" "0R2J-2-GP"
			(at 0.064008 -3.993896 180)
			(unlocked yes)
			(layer "F.Fab")
			(hide yes)
			(effects
				(font
					(size 1.016 1.016)
					(thickness 0.1524)
				)
			)
		)
		(property "Device Type" "R402H16"
			(at 0.064008 -5.517896 180)
			(unlocked yes)
			(layer "F.Fab")
			(hide yes)
			(effects
				(font
					(size 1.016 1.016)
					(thickness 0.1524)
				)
			)
		)
		(duplicate_pad_numbers_are_jumpers no)
		(fp_line
			(start 0.508 -0.9398)
			(end -0.508 -0.9398)
			(stroke
				(width 0.1524)
				(type default)
			)
			(layer "F.SilkS")
		)
		(fp_line
			(start -0.508 -0.9398)
			(end -0.508 0.9398)
			(stroke
				(width 0.1524)
				(type default)
			)
			(layer "F.SilkS")
		)
		(fp_rect
			(start -0.508 0.9398)
			(end 0.508 -0.9398)
			(stroke
				(width 0)
				(type default)
			)
			(fill no)
			(layer "F.CrtYd")
		)
		(fp_rect
			(start -0.508 0.9398)
			(end 0.508 -0.9398)
			(stroke
				(width 0)
				(type default)
			)
			(fill no)
			(layer "F.Fab")
		)
		(pad "1" smd custom
			(at 0 -0.4445 180)
			(size 0.1397 0.1397)
			(layers "F.Cu" "F.Mask" "F.Paste")
			(net "I2C_C_SDA_LEDDRV")
			(options
				(clearance outline)
				(anchor circle)
			)
			(primitives
				(gr_poly
					(pts
						(arc
							(start -0.1778 -0.2794)
							(mid -0.249642 -0.249642)
							(end -0.2794 -0.1778)
						)
						(arc
							(start -0.2794 0.1778)
							(mid -0.249642 0.249642)
							(end -0.1778 0.2794)
						)
						(arc
							(start 0.1778 0.2794)
							(mid 0.249642 0.249642)
							(end 0.2794 0.1778)
						)
						(arc
							(start 0.2794 -0.1778)
							(mid 0.249642 -0.249642)
							(end 0.1778 -0.2794)
						)
					)
					(width 0)
					(fill yes)
				)
			)
		)
		(pad "2" smd custom
			(at 0 0.4445 180)
			(size 0.1397 0.1397)
			(layers "F.Cu" "F.Mask" "F.Paste")
			(net "I2C_C_SDA")
			(options
				(clearance outline)
				(anchor circle)
			)
			(primitives
				(gr_poly
					(pts
						(arc
							(start -0.1778 -0.2794)
							(mid -0.249642 -0.249642)
							(end -0.2794 -0.1778)
						)
						(arc
							(start -0.2794 0.1778)
							(mid -0.249642 0.249642)
							(end -0.1778 0.2794)
						)
						(arc
							(start 0.1778 0.2794)
							(mid 0.249642 0.249642)
							(end 0.2794 0.1778)
						)
						(arc
							(start 0.2794 -0.1778)
							(mid 0.249642 -0.249642)
							(end 0.1778 -0.2794)
						)
					)
					(width 0)
					(fill yes)
				)
			)
		)
	)
	(footprint ""
		(layer "F.Cu")
		(at 39.878 -240.665 180)
		(property "Reference" "R155"
			(at 0 0 180)
			(layer "F.SilkS")
			(hide yes)
			(effects
				(font
					(size 1.27 1.27)
				)
			)
		)
		(property "Value" "330R2J-3-GP"
			(at 0.064008 -3.993896 180)
			(unlocked yes)
			(layer "F.Fab")
			(hide yes)
			(effects
				(font
					(size 1.016 1.016)
					(thickness 0.1524)
				)
			)
		)
		(property "Device Type" "R402H16"
			(at 0.064008 -5.517896 180)
			(unlocked yes)
			(layer "F.Fab")
			(hide yes)
			(effects
				(font
					(size 1.016 1.016)
					(thickness 0.1524)
				)
			)
		)
		(duplicate_pad_numbers_are_jumpers no)
		(fp_line
			(start 0.508 -0.9398)
			(end -0.508 -0.9398)
			(stroke
				(width 0.1524)
				(type default)
			)
			(layer "F.SilkS")
		)
		(fp_line
			(start -0.508 -0.9398)
			(end -0.508 0.9398)
			(stroke
				(width 0.1524)
				(type default)
			)
			(layer "F.SilkS")
		)
		(fp_rect
			(start -0.508 0.9398)
			(end 0.508 -0.9398)
			(stroke
				(width 0)
				(type default)
			)
			(fill no)
			(layer "F.CrtYd")
		)
		(fp_rect
			(start -0.508 0.9398)
			(end 0.508 -0.9398)
			(stroke
				(width 0)
				(type default)
			)
			(fill no)
			(layer "F.Fab")
		)
		(pad "1" smd custom
			(at 0 -0.4445 180)
			(size 0.1397 0.1397)
			(layers "F.Cu" "F.Mask" "F.Paste")
			(net "P3V3")
			(options
				(clearance outline)
				(anchor circle)
			)
			(primitives
				(gr_poly
					(pts
						(arc
							(start -0.1778 -0.2794)
							(mid -0.249642 -0.249642)
							(end -0.2794 -0.1778)
						)
						(arc
							(start -0.2794 0.1778)
							(mid -0.249642 0.249642)
							(end -0.1778 0.2794)
						)
						(arc
							(start 0.1778 0.2794)
							(mid 0.249642 0.249642)
							(end 0.2794 0.1778)
						)
						(arc
							(start 0.2794 -0.1778)
							(mid 0.249642 -0.249642)
							(end 0.1778 -0.2794)
						)
					)
					(width 0)
					(fill yes)
				)
			)
		)
		(pad "2" smd custom
			(at 0 0.4445 180)
			(size 0.1397 0.1397)
			(layers "F.Cu" "F.Mask" "F.Paste")
			(net "LED_DR_LED3")
			(options
				(clearance outline)
				(anchor circle)
			)
			(primitives
				(gr_poly
					(pts
						(arc
							(start -0.1778 -0.2794)
							(mid -0.249642 -0.249642)
							(end -0.2794 -0.1778)
						)
						(arc
							(start -0.2794 0.1778)
							(mid -0.249642 0.249642)
							(end -0.1778 0.2794)
						)
						(arc
							(start 0.1778 0.2794)
							(mid 0.249642 0.249642)
							(end 0.2794 0.1778)
						)
						(arc
							(start 0.2794 -0.1778)
							(mid 0.249642 -0.249642)
							(end 0.1778 -0.2794)
						)
					)
					(width 0)
					(fill yes)
				)
			)
		)
	)
	(footprint ""
		(layer "F.Cu")
		(at 35.8394 -357.097584 180)
		(property "Reference" "D19"
			(at 0 0 180)
			(layer "F.SilkS")
			(hide yes)
			(effects
				(font
					(size 1.27 1.27)
				)
			)
		)
		(property "Value" "CH751H-40PT-1GP"
			(at -0.1016 -4.4958 180)
			(unlocked yes)
			(layer "F.Fab")
			(hide yes)
			(effects
				(font
					(size 1.016 1.016)
					(thickness 0.1524)
				)
			)
		)
		(property "Device Type" "SOD80CAKH36"
			(at -0.1016 -6.0198 180)
			(unlocked yes)
			(layer "F.Fab")
			(hide yes)
			(effects
				(font
					(size 1.016 1.016)
					(thickness 0.1524)
				)
			)
		)
		(duplicate_pad_numbers_are_jumpers no)
		(fp_line
			(start 0.8128 1.8796)
			(end 0.8128 -1.8796)
			(stroke
				(width 0.1524)
				(type default)
			)
			(layer "F.SilkS")
		)
		(fp_line
			(start 0.8128 -1.8796)
			(end -0.8128 -1.8796)
			(stroke
				(width 0.1524)
				(type default)
			)
			(layer "F.SilkS")
		)
		(fp_line
			(start -0.6858 2.0066)
			(end 0.6858 2.0066)
			(stroke
				(width 0.4064)
				(type default)
			)
			(layer "F.SilkS")
		)
		(fp_line
			(start -0.8128 1.8796)
			(end 0.8128 1.8796)
			(stroke
				(width 0.1524)
				(type default)
			)
			(layer "F.SilkS")
		)
		(fp_line
			(start -0.8128 -1.8796)
			(end -0.8128 1.8796)
			(stroke
				(width 0.1524)
				(type default)
			)
			(layer "F.SilkS")
		)
		(fp_rect
			(start -0.889 2.2098)
			(end 0.889 -1.9558)
			(stroke
				(width 0)
				(type default)
			)
			(fill no)
			(layer "F.CrtYd")
		)
		(fp_rect
			(start -0.889 2.2098)
			(end 0.889 -1.9558)
			(stroke
				(width 0)
				(type default)
			)
			(fill no)
			(layer "F.Fab")
		)
		(pad "A" smd rect
			(at 0 -1.0668 180)
			(size 0.762 1.1684)
			(layers "F.Cu" "F.Mask" "F.Paste")
			(net "OTP_RETRY_C")
		)
		(pad "K" smd rect
			(at 0 1.0668 180)
			(size 0.762 1.1684)
			(layers "F.Cu" "F.Mask" "F.Paste")
			(net "OTP_RETRY_DIODE")
		)
	)
	(footprint ""
		(layer "F.Cu")
		(at 31.012638 -289.229292 -90)
		(property "Reference" "F5"
			(at 0 0 270)
			(layer "F.SilkS")
			(hide yes)
			(effects
				(font
					(size 1.27 1.27)
				)
			)
		)
		(property "Value" "FUSE-3A15V-GP"
			(at 0.2286 -10.5918 270)
			(unlocked yes)
			(layer "F.Fab")
			(hide yes)
			(effects
				(font
					(size 1.016 1.016)
					(thickness 0.1524)
				)
			)
		)
		(property "Device Type" "FUSE-7452-UH50"
			(at 0.2286 -12.4968 270)
			(unlocked yes)
			(layer "F.Fab")
			(hide yes)
			(effects
				(font
					(size 1.016 1.016)
					(thickness 0.1524)
				)
			)
		)
		(duplicate_pad_numbers_are_jumpers no)
		(fp_line
			(start -4.9276 2.921)
			(end -4.9276 -2.921)
			(stroke
				(width 0.1524)
				(type default)
			)
			(layer "F.SilkS")
		)
		(fp_line
			(start 4.9276 2.921)
			(end -4.9276 2.921)
			(stroke
				(width 0.1524)
				(type default)
			)
			(layer "F.SilkS")
		)
		(fp_line
			(start -4.9276 -2.921)
			(end 4.9276 -2.921)
			(stroke
				(width 0.1524)
				(type default)
			)
			(layer "F.SilkS")
		)
		(fp_line
			(start 4.9276 -2.921)
			(end 4.9276 2.921)
			(stroke
				(width 0.1524)
				(type default)
			)
			(layer "F.SilkS")
		)
		(fp_poly
			(pts
				(xy -5.08 3.0988) (xy 5.08 3.0988) (xy 5.08 -3.0988) (xy -5.08 -3.0988)
			)
			(stroke
				(width 0)
				(type default)
			)
			(fill no)
			(layer "F.CrtYd")
		)
		(fp_poly
			(pts
				(xy -5.08 -3.0988) (xy 5.08 -3.0988) (xy 5.08 3.0988) (xy -5.08 3.0988)
			)
			(stroke
				(width 0)
				(type default)
			)
			(fill no)
			(layer "F.Fab")
		)
		(pad "1" smd rect
			(at -3.4036 0 270)
			(size 2.2098 5.2832)
			(layers "F.Cu" "F.Mask" "F.Paste")
			(net "P12V_FAN2")
		)
		(pad "2" smd rect
			(at 3.4036 0 270)
			(size 2.2098 5.2832)
			(layers "F.Cu" "F.Mask" "F.Paste")
			(net "P12V")
		)
	)
	(footprint ""
		(layer "F.Cu")
		(at 19.558 -185.1914 180)
		(property "Reference" "R89"
			(at 0 0 180)
			(layer "F.SilkS")
			(hide yes)
			(effects
				(font
					(size 1.27 1.27)
				)
			)
		)
		(property "Value" "10KR2F-2-GP"
			(at 0.064008 -3.993896 180)
			(unlocked yes)
			(layer "F.Fab")
			(hide yes)
			(effects
				(font
					(size 1.016 1.016)
					(thickness 0.1524)
				)
			)
		)
		(property "Device Type" "R402H16"
			(at 0.064008 -5.517896 180)
			(unlocked yes)
			(layer "F.Fab")
			(hide yes)
			(effects
				(font
					(size 1.016 1.016)
					(thickness 0.1524)
				)
			)
		)
		(duplicate_pad_numbers_are_jumpers no)
		(fp_line
			(start 0.508 -0.9398)
			(end -0.508 -0.9398)
			(stroke
				(width 0.1524)
				(type default)
			)
			(layer "F.SilkS")
		)
		(fp_line
			(start -0.508 -0.9398)
			(end -0.508 0.9398)
			(stroke
				(width 0.1524)
				(type default)
			)
			(layer "F.SilkS")
		)
		(fp_rect
			(start -0.508 0.9398)
			(end 0.508 -0.9398)
			(stroke
				(width 0)
				(type default)
			)
			(fill no)
			(layer "F.CrtYd")
		)
		(fp_rect
			(start -0.508 0.9398)
			(end 0.508 -0.9398)
			(stroke
				(width 0)
				(type default)
			)
			(fill no)
			(layer "F.Fab")
		)
		(pad "1" smd custom
			(at 0 -0.4445 180)
			(size 0.1397 0.1397)
			(layers "F.Cu" "F.Mask" "F.Paste")
			(net "FANIN_8")
			(options
				(clearance outline)
				(anchor circle)
			)
			(primitives
				(gr_poly
					(pts
						(arc
							(start -0.1778 -0.2794)
							(mid -0.249642 -0.249642)
							(end -0.2794 -0.1778)
						)
						(arc
							(start -0.2794 0.1778)
							(mid -0.249642 0.249642)
							(end -0.1778 0.2794)
						)
						(arc
							(start 0.1778 0.2794)
							(mid 0.249642 0.249642)
							(end 0.2794 0.1778)
						)
						(arc
							(start 0.2794 -0.1778)
							(mid 0.249642 -0.249642)
							(end 0.1778 -0.2794)
						)
					)
					(width 0)
					(fill yes)
				)
			)
		)
		(pad "2" smd custom
			(at 0 0.4445 180)
			(size 0.1397 0.1397)
			(layers "F.Cu" "F.Mask" "F.Paste")
			(net "GND")
			(options
				(clearance outline)
				(anchor circle)
			)
			(primitives
				(gr_poly
					(pts
						(arc
							(start -0.1778 -0.2794)
							(mid -0.249642 -0.249642)
							(end -0.2794 -0.1778)
						)
						(arc
							(start -0.2794 0.1778)
							(mid -0.249642 0.249642)
							(end -0.1778 0.2794)
						)
						(arc
							(start 0.1778 0.2794)
							(mid 0.249642 0.249642)
							(end 0.2794 0.1778)
						)
						(arc
							(start 0.2794 -0.1778)
							(mid 0.249642 -0.249642)
							(end 0.1778 -0.2794)
						)
					)
					(width 0)
					(fill yes)
				)
			)
		)
	)
	(footprint ""
		(layer "F.Cu")
		(at 8.3566 -422.275)
		(property "Reference" "R119"
			(at 0 0 0)
			(layer "F.SilkS")
			(hide yes)
			(effects
				(font
					(size 1.27 1.27)
				)
			)
		)
		(property "Value" "2KR2F-3-GP"
			(at 0.064008 -3.993896 0)
			(unlocked yes)
			(layer "F.Fab")
			(hide yes)
			(effects
				(font
					(size 1.016 1.016)
					(thickness 0.1524)
				)
			)
		)
		(property "Device Type" "R402H16"
			(at 0.064008 -5.517896 0)
			(unlocked yes)
			(layer "F.Fab")
			(hide yes)
			(effects
				(font
					(size 1.016 1.016)
					(thickness 0.1524)
				)
			)
		)
		(duplicate_pad_numbers_are_jumpers no)
		(fp_line
			(start -0.508 -0.9398)
			(end -0.508 0.9398)
			(stroke
				(width 0.1524)
				(type default)
			)
			(layer "F.SilkS")
		)
		(fp_line
			(start 0.508 -0.9398)
			(end -0.508 -0.9398)
			(stroke
				(width 0.1524)
				(type default)
			)
			(layer "F.SilkS")
		)
		(fp_rect
			(start -0.508 0.9398)
			(end 0.508 -0.9398)
			(stroke
				(width 0)
				(type default)
			)
			(fill no)
			(layer "F.CrtYd")
		)
		(fp_rect
			(start -0.508 0.9398)
			(end 0.508 -0.9398)
			(stroke
				(width 0)
				(type default)
			)
			(fill no)
			(layer "F.Fab")
		)
		(pad "1" smd custom
			(at 0 -0.4445)
			(size 0.1397 0.1397)
			(layers "F.Cu" "F.Mask" "F.Paste")
			(net "LED_DR_LED1")
			(options
				(clearance outline)
				(anchor circle)
			)
			(primitives
				(gr_poly
					(pts
						(arc
							(start -0.1778 -0.2794)
							(mid -0.249642 -0.249642)
							(end -0.2794 -0.1778)
						)
						(arc
							(start -0.2794 0.1778)
							(mid -0.249642 0.249642)
							(end -0.1778 0.2794)
						)
						(arc
							(start 0.1778 0.2794)
							(mid 0.249642 0.249642)
							(end 0.2794 0.1778)
						)
						(arc
							(start 0.2794 -0.1778)
							(mid 0.249642 -0.249642)
							(end 0.1778 -0.2794)
						)
					)
					(width 0)
					(fill yes)
				)
			)
		)
		(pad "2" smd custom
			(at 0 0.4445)
			(size 0.1397 0.1397)
			(layers "F.Cu" "F.Mask" "F.Paste")
			(net "LED_DR_LED1_B")
			(options
				(clearance outline)
				(anchor circle)
			)
			(primitives
				(gr_poly
					(pts
						(arc
							(start -0.1778 -0.2794)
							(mid -0.249642 -0.249642)
							(end -0.2794 -0.1778)
						)
						(arc
							(start -0.2794 0.1778)
							(mid -0.249642 0.249642)
							(end -0.1778 0.2794)
						)
						(arc
							(start 0.1778 0.2794)
							(mid 0.249642 0.249642)
							(end 0.2794 0.1778)
						)
						(arc
							(start 0.2794 -0.1778)
							(mid 0.249642 -0.249642)
							(end 0.1778 -0.2794)
						)
					)
					(width 0)
					(fill yes)
				)
			)
		)
	)
	(footprint ""
		(layer "F.Cu")
		(at 20.7518 -173.2788 -90)
		(property "Reference" "R183"
			(at 0 0 270)
			(layer "F.SilkS")
			(hide yes)
			(effects
				(font
					(size 1.27 1.27)
				)
			)
		)
		(property "Value" "0R2J-2-GP"
			(at 0.064008 -3.993896 270)
			(unlocked yes)
			(layer "F.Fab")
			(hide yes)
			(effects
				(font
					(size 1.016 1.016)
					(thickness 0.1524)
				)
			)
		)
		(property "Device Type" "R402H16"
			(at 0.064008 -5.517896 270)
			(unlocked yes)
			(layer "F.Fab")
			(hide yes)
			(effects
				(font
					(size 1.016 1.016)
					(thickness 0.1524)
				)
			)
		)
		(duplicate_pad_numbers_are_jumpers no)
		(fp_line
			(start -0.508 -0.9398)
			(end -0.508 0.9398)
			(stroke
				(width 0.1524)
				(type default)
			)
			(layer "F.SilkS")
		)
		(fp_line
			(start 0.508 -0.9398)
			(end -0.508 -0.9398)
			(stroke
				(width 0.1524)
				(type default)
			)
			(layer "F.SilkS")
		)
		(fp_rect
			(start -0.508 0.9398)
			(end 0.508 -0.9398)
			(stroke
				(width 0)
				(type default)
			)
			(fill no)
			(layer "F.CrtYd")
		)
		(fp_rect
			(start -0.508 0.9398)
			(end 0.508 -0.9398)
			(stroke
				(width 0)
				(type default)
			)
			(fill no)
			(layer "F.Fab")
		)
		(pad "1" smd custom
			(at 0 -0.4445 270)
			(size 0.1397 0.1397)
			(layers "F.Cu" "F.Mask" "F.Paste")
			(net "THERMHOT#")
			(options
				(clearance outline)
				(anchor circle)
			)
			(primitives
				(gr_poly
					(pts
						(arc
							(start -0.1778 -0.2794)
							(mid -0.249642 -0.249642)
							(end -0.2794 -0.1778)
						)
						(arc
							(start -0.2794 0.1778)
							(mid -0.249642 0.249642)
							(end -0.1778 0.2794)
						)
						(arc
							(start 0.1778 0.2794)
							(mid 0.249642 0.249642)
							(end 0.2794 0.1778)
						)
						(arc
							(start 0.2794 -0.1778)
							(mid 0.249642 -0.249642)
							(end 0.1778 -0.2794)
						)
					)
					(width 0)
					(fill yes)
				)
			)
		)
		(pad "2" smd custom
			(at 0 0.4445 270)
			(size 0.1397 0.1397)
			(layers "F.Cu" "F.Mask" "F.Paste")
			(net "THERMHOT#_R")
			(options
				(clearance outline)
				(anchor circle)
			)
			(primitives
				(gr_poly
					(pts
						(arc
							(start -0.1778 -0.2794)
							(mid -0.249642 -0.249642)
							(end -0.2794 -0.1778)
						)
						(arc
							(start -0.2794 0.1778)
							(mid -0.249642 0.249642)
							(end -0.1778 0.2794)
						)
						(arc
							(start 0.1778 0.2794)
							(mid 0.249642 0.249642)
							(end 0.2794 0.1778)
						)
						(arc
							(start 0.2794 -0.1778)
							(mid 0.249642 -0.249642)
							(end 0.1778 -0.2794)
						)
					)
					(width 0)
					(fill yes)
				)
			)
		)
	)
	(footprint ""
		(layer "F.Cu")
		(at 29.852366 -242.327176)
		(property "Reference" "R43"
			(at 0 0 0)
			(layer "F.SilkS")
			(hide yes)
			(effects
				(font
					(size 1.27 1.27)
				)
			)
		)
		(property "Value" "4K7R2J-2-GP"
			(at 0.064008 -3.993896 0)
			(unlocked yes)
			(layer "F.Fab")
			(hide yes)
			(effects
				(font
					(size 1.016 1.016)
					(thickness 0.1524)
				)
			)
		)
		(property "Device Type" "R402H16"
			(at 0.064008 -5.517896 0)
			(unlocked yes)
			(layer "F.Fab")
			(hide yes)
			(effects
				(font
					(size 1.016 1.016)
					(thickness 0.1524)
				)
			)
		)
		(duplicate_pad_numbers_are_jumpers no)
		(fp_line
			(start -0.508 -0.9398)
			(end -0.508 0.9398)
			(stroke
				(width 0.1524)
				(type default)
			)
			(layer "F.SilkS")
		)
		(fp_line
			(start 0.508 -0.9398)
			(end -0.508 -0.9398)
			(stroke
				(width 0.1524)
				(type default)
			)
			(layer "F.SilkS")
		)
		(fp_rect
			(start -0.508 0.9398)
			(end 0.508 -0.9398)
			(stroke
				(width 0)
				(type default)
			)
			(fill no)
			(layer "F.CrtYd")
		)
		(fp_rect
			(start -0.508 0.9398)
			(end 0.508 -0.9398)
			(stroke
				(width 0)
				(type default)
			)
			(fill no)
			(layer "F.Fab")
		)
		(pad "1" smd custom
			(at 0 -0.4445)
			(size 0.1397 0.1397)
			(layers "F.Cu" "F.Mask" "F.Paste")
			(net "FCB_EEPROM_A1")
			(options
				(clearance outline)
				(anchor circle)
			)
			(primitives
				(gr_poly
					(pts
						(arc
							(start -0.1778 -0.2794)
							(mid -0.249642 -0.249642)
							(end -0.2794 -0.1778)
						)
						(arc
							(start -0.2794 0.1778)
							(mid -0.249642 0.249642)
							(end -0.1778 0.2794)
						)
						(arc
							(start 0.1778 0.2794)
							(mid 0.249642 0.249642)
							(end 0.2794 0.1778)
						)
						(arc
							(start 0.2794 -0.1778)
							(mid 0.249642 -0.249642)
							(end 0.1778 -0.2794)
						)
					)
					(width 0)
					(fill yes)
				)
			)
		)
		(pad "2" smd custom
			(at 0 0.4445)
			(size 0.1397 0.1397)
			(layers "F.Cu" "F.Mask" "F.Paste")
			(net "GND")
			(options
				(clearance outline)
				(anchor circle)
			)
			(primitives
				(gr_poly
					(pts
						(arc
							(start -0.1778 -0.2794)
							(mid -0.249642 -0.249642)
							(end -0.2794 -0.1778)
						)
						(arc
							(start -0.2794 0.1778)
							(mid -0.249642 0.249642)
							(end -0.1778 0.2794)
						)
						(arc
							(start 0.1778 0.2794)
							(mid 0.249642 0.249642)
							(end 0.2794 0.1778)
						)
						(arc
							(start 0.2794 -0.1778)
							(mid 0.249642 -0.249642)
							(end 0.1778 -0.2794)
						)
					)
					(width 0)
					(fill yes)
				)
			)
		)
	)
	(footprint ""
		(layer "F.Cu")
		(at 37.973 -147.4216 180)
		(property "Reference" "PC94"
			(at 0 0 180)
			(layer "F.SilkS")
			(hide yes)
			(effects
				(font
					(size 1.27 1.27)
				)
			)
		)
		(property "Value" "SC220P50V2KX-3GP"
			(at 1.1811 -2.7051 180)
			(unlocked yes)
			(layer "F.Fab")
			(hide yes)
			(effects
				(font
					(size 1.016 1.016)
					(thickness 0.1524)
				)
			)
		)
		(property "Device Type" "C402H22"
			(at 1.1811 -4.2291 180)
			(unlocked yes)
			(layer "F.Fab")
			(hide yes)
			(effects
				(font
					(size 1.016 1.016)
					(thickness 0.1524)
				)
			)
		)
		(duplicate_pad_numbers_are_jumpers no)
		(fp_rect
			(start -0.4318 0.9525)
			(end 0.4318 -0.9525)
			(stroke
				(width 0)
				(type default)
			)
			(fill no)
			(layer "F.CrtYd")
		)
		(fp_rect
			(start -0.4318 0.9525)
			(end 0.4318 -0.9525)
			(stroke
				(width 0)
				(type default)
			)
			(fill no)
			(layer "F.Fab")
		)
		(pad "1" smd custom
			(at 0 -0.4445 180)
			(size 0.1524 0.1524)
			(layers "F.Cu" "F.Mask" "F.Paste")
			(net "P12VL_2490_VREF")
			(options
				(clearance outline)
				(anchor circle)
			)
			(primitives
				(gr_poly
					(pts
						(arc
							(start 0.3048 -0.2032)
							(mid 0.275042 -0.275042)
							(end 0.2032 -0.3048)
						)
						(arc
							(start -0.2032 -0.3048)
							(mid -0.275042 -0.275042)
							(end -0.3048 -0.2032)
						)
						(arc
							(start -0.3048 0.2032)
							(mid -0.275042 0.275042)
							(end -0.2032 0.3048)
						)
						(arc
							(start 0.2032 0.3048)
							(mid 0.275042 0.275042)
							(end 0.3048 0.2032)
						)
					)
					(width 0)
					(fill yes)
				)
			)
		)
		(pad "2" smd custom
			(at 0 0.4445 180)
			(size 0.1524 0.1524)
			(layers "F.Cu" "F.Mask" "F.Paste")
			(net "GND")
			(options
				(clearance outline)
				(anchor circle)
			)
			(primitives
				(gr_poly
					(pts
						(arc
							(start 0.3048 -0.2032)
							(mid 0.275042 -0.275042)
							(end 0.2032 -0.3048)
						)
						(arc
							(start -0.2032 -0.3048)
							(mid -0.275042 -0.275042)
							(end -0.3048 -0.2032)
						)
						(arc
							(start -0.3048 0.2032)
							(mid -0.275042 0.275042)
							(end -0.2032 0.3048)
						)
						(arc
							(start 0.2032 0.3048)
							(mid 0.275042 0.275042)
							(end 0.3048 0.2032)
						)
					)
					(width 0)
					(fill yes)
				)
			)
		)
	)
	(footprint ""
		(layer "F.Cu")
		(at 6.5786 -437.7436)
		(property "Reference" "R32"
			(at 0 0 0)
			(layer "F.SilkS")
			(hide yes)
			(effects
				(font
					(size 1.27 1.27)
				)
			)
		)
		(property "Value" "0R2J-2-GP"
			(at 0.064008 -3.993896 0)
			(unlocked yes)
			(layer "F.Fab")
			(hide yes)
			(effects
				(font
					(size 1.016 1.016)
					(thickness 0.1524)
				)
			)
		)
		(property "Device Type" "R402H16"
			(at 0.064008 -5.517896 0)
			(unlocked yes)
			(layer "F.Fab")
			(hide yes)
			(effects
				(font
					(size 1.016 1.016)
					(thickness 0.1524)
				)
			)
		)
		(duplicate_pad_numbers_are_jumpers no)
		(fp_line
			(start -0.508 -0.9398)
			(end -0.508 0.9398)
			(stroke
				(width 0.1524)
				(type default)
			)
			(layer "F.SilkS")
		)
		(fp_line
			(start 0.508 -0.9398)
			(end -0.508 -0.9398)
			(stroke
				(width 0.1524)
				(type default)
			)
			(layer "F.SilkS")
		)
		(fp_rect
			(start -0.508 0.9398)
			(end 0.508 -0.9398)
			(stroke
				(width 0)
				(type default)
			)
			(fill no)
			(layer "F.CrtYd")
		)
		(fp_rect
			(start -0.508 0.9398)
			(end 0.508 -0.9398)
			(stroke
				(width 0)
				(type default)
			)
			(fill no)
			(layer "F.Fab")
		)
		(pad "1" smd custom
			(at 0 -0.4445)
			(size 0.1397 0.1397)
			(layers "F.Cu" "F.Mask" "F.Paste")
			(net "LED_DR_LED0_K")
			(options
				(clearance outline)
				(anchor circle)
			)
			(primitives
				(gr_poly
					(pts
						(arc
							(start -0.1778 -0.2794)
							(mid -0.249642 -0.249642)
							(end -0.2794 -0.1778)
						)
						(arc
							(start -0.2794 0.1778)
							(mid -0.249642 0.249642)
							(end -0.1778 0.2794)
						)
						(arc
							(start 0.1778 0.2794)
							(mid 0.249642 0.249642)
							(end 0.2794 0.1778)
						)
						(arc
							(start 0.2794 -0.1778)
							(mid 0.249642 -0.249642)
							(end 0.1778 -0.2794)
						)
					)
					(width 0)
					(fill yes)
				)
			)
		)
		(pad "2" smd custom
			(at 0 0.4445)
			(size 0.1397 0.1397)
			(layers "F.Cu" "F.Mask" "F.Paste")
			(net "GND")
			(options
				(clearance outline)
				(anchor circle)
			)
			(primitives
				(gr_poly
					(pts
						(arc
							(start -0.1778 -0.2794)
							(mid -0.249642 -0.249642)
							(end -0.2794 -0.1778)
						)
						(arc
							(start -0.2794 0.1778)
							(mid -0.249642 0.249642)
							(end -0.1778 0.2794)
						)
						(arc
							(start 0.1778 0.2794)
							(mid 0.249642 0.249642)
							(end 0.2794 0.1778)
						)
						(arc
							(start 0.2794 -0.1778)
							(mid 0.249642 -0.249642)
							(end 0.1778 -0.2794)
						)
					)
					(width 0)
					(fill yes)
				)
			)
		)
	)
	(footprint ""
		(layer "F.Cu")
		(at 14.8844 -41.4782 90)
		(property "Reference" "R116"
			(at 0 0 90)
			(layer "F.SilkS")
			(hide yes)
			(effects
				(font
					(size 1.27 1.27)
				)
			)
		)
		(property "Value" "470R2F-GP"
			(at 0.064008 -3.993896 90)
			(unlocked yes)
			(layer "F.Fab")
			(hide yes)
			(effects
				(font
					(size 1.016 1.016)
					(thickness 0.1524)
				)
			)
		)
		(property "Device Type" "R402H16"
			(at 0.064008 -5.517896 90)
			(unlocked yes)
			(layer "F.Fab")
			(hide yes)
			(effects
				(font
					(size 1.016 1.016)
					(thickness 0.1524)
				)
			)
		)
		(duplicate_pad_numbers_are_jumpers no)
		(fp_line
			(start 0.508 -0.9398)
			(end -0.508 -0.9398)
			(stroke
				(width 0.1524)
				(type default)
			)
			(layer "F.SilkS")
		)
		(fp_line
			(start -0.508 -0.9398)
			(end -0.508 0.9398)
			(stroke
				(width 0.1524)
				(type default)
			)
			(layer "F.SilkS")
		)
		(fp_rect
			(start -0.508 0.9398)
			(end 0.508 -0.9398)
			(stroke
				(width 0)
				(type default)
			)
			(fill no)
			(layer "F.CrtYd")
		)
		(fp_rect
			(start -0.508 0.9398)
			(end 0.508 -0.9398)
			(stroke
				(width 0)
				(type default)
			)
			(fill no)
			(layer "F.Fab")
		)
		(pad "1" smd custom
			(at 0 -0.4445 90)
			(size 0.1397 0.1397)
			(layers "F.Cu" "F.Mask" "F.Paste")
			(net "SEB_PEER_1B_HB")
			(options
				(clearance outline)
				(anchor circle)
			)
			(primitives
				(gr_poly
					(pts
						(arc
							(start -0.1778 -0.2794)
							(mid -0.249642 -0.249642)
							(end -0.2794 -0.1778)
						)
						(arc
							(start -0.2794 0.1778)
							(mid -0.249642 0.249642)
							(end -0.1778 0.2794)
						)
						(arc
							(start 0.1778 0.2794)
							(mid 0.249642 0.249642)
							(end 0.2794 0.1778)
						)
						(arc
							(start 0.2794 -0.1778)
							(mid 0.249642 -0.249642)
							(end 0.1778 -0.2794)
						)
					)
					(width 0)
					(fill yes)
				)
			)
		)
		(pad "2" smd custom
			(at 0 0.4445 90)
			(size 0.1397 0.1397)
			(layers "F.Cu" "F.Mask" "F.Paste")
			(net "GND")
			(options
				(clearance outline)
				(anchor circle)
			)
			(primitives
				(gr_poly
					(pts
						(arc
							(start -0.1778 -0.2794)
							(mid -0.249642 -0.249642)
							(end -0.2794 -0.1778)
						)
						(arc
							(start -0.2794 0.1778)
							(mid -0.249642 0.249642)
							(end -0.1778 0.2794)
						)
						(arc
							(start 0.1778 0.2794)
							(mid 0.249642 0.249642)
							(end 0.2794 0.1778)
						)
						(arc
							(start 0.2794 -0.1778)
							(mid 0.249642 -0.249642)
							(end 0.1778 -0.2794)
						)
					)
					(width 0)
					(fill yes)
				)
			)
		)
	)
	(footprint ""
		(layer "F.Cu")
		(at 15.9258 -65.278)
		(property "Reference" "C57"
			(at 0 0 0)
			(layer "F.SilkS")
			(hide yes)
			(effects
				(font
					(size 1.27 1.27)
				)
			)
		)
		(property "Value" "SC220P50V3JN-GP"
			(at 0 -2.8194 0)
			(unlocked yes)
			(layer "F.Fab")
			(hide yes)
			(effects
				(font
					(size 1.016 1.016)
					(thickness 0.1524)
				)
			)
		)
		(property "Device Type" "C603H36"
			(at 0 -4.3434 0)
			(unlocked yes)
			(layer "F.Fab")
			(hide yes)
			(effects
				(font
					(size 1.016 1.016)
					(thickness 0.1524)
				)
			)
		)
		(duplicate_pad_numbers_are_jumpers no)
		(fp_line
			(start 0.508 0)
			(end -0.508 0)
			(stroke
				(width 0.2032)
				(type default)
			)
			(layer "F.SilkS")
		)
		(fp_rect
			(start -0.5842 1.3335)
			(end 0.5842 -1.3335)
			(stroke
				(width 0)
				(type default)
			)
			(fill no)
			(layer "F.CrtYd")
		)
		(fp_rect
			(start -0.5842 1.3335)
			(end 0.5842 -1.3335)
			(stroke
				(width 0)
				(type default)
			)
			(fill no)
			(layer "F.Fab")
		)
		(pad "1" smd custom
			(at 0 -0.762)
			(size 0.2159 0.2159)
			(layers "F.Cu" "F.Mask" "F.Paste")
			(net "I2C_C_SDA_CONN_R")
			(options
				(clearance outline)
				(anchor circle)
			)
			(primitives
				(gr_poly
					(pts
						(arc
							(start -0.3302 -0.4318)
							(mid -0.402042 -0.402042)
							(end -0.4318 -0.3302)
						)
						(arc
							(start -0.4318 0.3302)
							(mid -0.402042 0.402042)
							(end -0.3302 0.4318)
						)
						(arc
							(start 0.3302 0.4318)
							(mid 0.402042 0.402042)
							(end 0.4318 0.3302)
						)
						(arc
							(start 0.4318 -0.3302)
							(mid 0.402042 -0.402042)
							(end 0.3302 -0.4318)
						)
					)
					(width 0)
					(fill yes)
				)
			)
		)
		(pad "2" smd custom
			(at 0 0.762)
			(size 0.2159 0.2159)
			(layers "F.Cu" "F.Mask" "F.Paste")
			(net "GND")
			(options
				(clearance outline)
				(anchor circle)
			)
			(primitives
				(gr_poly
					(pts
						(arc
							(start -0.3302 -0.4318)
							(mid -0.402042 -0.402042)
							(end -0.4318 -0.3302)
						)
						(arc
							(start -0.4318 0.3302)
							(mid -0.402042 0.402042)
							(end -0.3302 0.4318)
						)
						(arc
							(start 0.3302 0.4318)
							(mid 0.402042 0.402042)
							(end 0.4318 0.3302)
						)
						(arc
							(start 0.4318 -0.3302)
							(mid 0.402042 -0.402042)
							(end 0.3302 -0.4318)
						)
					)
					(width 0)
					(fill yes)
				)
			)
		)
	)
	(footprint ""
		(layer "F.Cu")
		(at 22.479508 -286.917638)
		(property "Reference" "D10"
			(at 0 0 0)
			(layer "F.SilkS")
			(hide yes)
			(effects
				(font
					(size 1.27 1.27)
				)
			)
		)
		(property "Value" "BAS16H-GP"
			(at 0 -5.5372 0)
			(unlocked yes)
			(layer "F.Fab")
			(hide yes)
			(effects
				(font
					(size 1.016 1.016)
					(thickness 0.1524)
				)
			)
		)
		(property "Device Type" "SOD123AKH48"
			(at 0 -7.0612 0)
			(unlocked yes)
			(layer "F.Fab")
			(hide yes)
			(effects
				(font
					(size 1.016 1.016)
					(thickness 0.1524)
				)
			)
		)
		(duplicate_pad_numbers_are_jumpers no)
		(fp_line
			(start -1.016 -2.667)
			(end -1.016 2.667)
			(stroke
				(width 0.1524)
				(type default)
			)
			(layer "F.SilkS")
		)
		(fp_line
			(start -1.016 2.667)
			(end 1.016 2.667)
			(stroke
				(width 0.1524)
				(type default)
			)
			(layer "F.SilkS")
		)
		(fp_line
			(start 0.889 2.921)
			(end -0.889 2.921)
			(stroke
				(width 0.508)
				(type default)
			)
			(layer "F.SilkS")
		)
		(fp_line
			(start 1.016 -2.667)
			(end -1.016 -2.667)
			(stroke
				(width 0.1524)
				(type default)
			)
			(layer "F.SilkS")
		)
		(fp_line
			(start 1.016 2.667)
			(end 1.016 -2.667)
			(stroke
				(width 0.1524)
				(type default)
			)
			(layer "F.SilkS")
		)
		(fp_rect
			(start -1.143 3.175)
			(end 1.143 -2.794)
			(stroke
				(width 0)
				(type default)
			)
			(fill no)
			(layer "F.CrtYd")
		)
		(fp_poly
			(pts
				(xy -1.143 -2.794) (xy 1.143 -2.794) (xy 1.143 3.175) (xy -1.143 3.175)
			)
			(stroke
				(width 0)
				(type default)
			)
			(fill no)
			(layer "F.Fab")
		)
		(pad "A" smd rect
			(at 0 -1.6891)
			(size 0.889 1.397)
			(layers "F.Cu" "F.Mask" "F.Paste")
			(net "FAN_TACH4")
		)
		(pad "K" smd rect
			(at 0 1.6891)
			(size 0.889 1.397)
			(layers "F.Cu" "F.Mask" "F.Paste")
			(net "P12V")
		)
	)
	(footprint ""
		(layer "F.Cu")
		(at 17.9578 -150.114 -90)
		(property "Reference" "R72"
			(at 0 0 270)
			(layer "F.SilkS")
			(hide yes)
			(effects
				(font
					(size 1.27 1.27)
				)
			)
		)
		(property "Value" "27KR3F-GP"
			(at -0.0254 -2.5146 270)
			(unlocked yes)
			(layer "F.Fab")
			(hide yes)
			(effects
				(font
					(size 1.016 1.016)
					(thickness 0.1524)
				)
			)
		)
		(property "Device Type" "R603H22"
			(at -0.0254 -4.0386 270)
			(unlocked yes)
			(layer "F.Fab")
			(hide yes)
			(effects
				(font
					(size 1.016 1.016)
					(thickness 0.1524)
				)
			)
		)
		(duplicate_pad_numbers_are_jumpers no)
		(fp_line
			(start -0.4826 0)
			(end -0.2032 0)
			(stroke
				(width 0.2032)
				(type default)
			)
			(layer "F.SilkS")
		)
		(fp_line
			(start 0.2032 0)
			(end 0.4826 0)
			(stroke
				(width 0.2032)
				(type default)
			)
			(layer "F.SilkS")
		)
		(fp_rect
			(start -0.5842 1.3335)
			(end 0.5842 -1.3335)
			(stroke
				(width 0)
				(type default)
			)
			(fill no)
			(layer "F.CrtYd")
		)
		(fp_rect
			(start -0.5842 1.3335)
			(end 0.5842 -1.3335)
			(stroke
				(width 0)
				(type default)
			)
			(fill no)
			(layer "F.Fab")
		)
		(pad "1" smd custom
			(at 0 -0.762 270)
			(size 0.2159 0.2159)
			(layers "F.Cu" "F.Mask" "F.Paste")
			(net "FANIN_9")
			(options
				(clearance outline)
				(anchor circle)
			)
			(primitives
				(gr_poly
					(pts
						(arc
							(start -0.3302 -0.4318)
							(mid -0.402042 -0.402042)
							(end -0.4318 -0.3302)
						)
						(arc
							(start -0.4318 0.3302)
							(mid -0.402042 0.402042)
							(end -0.3302 0.4318)
						)
						(arc
							(start 0.3302 0.4318)
							(mid 0.402042 0.402042)
							(end 0.4318 0.3302)
						)
						(arc
							(start 0.4318 -0.3302)
							(mid 0.402042 -0.402042)
							(end 0.3302 -0.4318)
						)
					)
					(width 0)
					(fill yes)
				)
			)
		)
		(pad "2" smd custom
			(at 0 0.762 270)
			(size 0.2159 0.2159)
			(layers "F.Cu" "F.Mask" "F.Paste")
			(net "FAN_TACH9")
			(options
				(clearance outline)
				(anchor circle)
			)
			(primitives
				(gr_poly
					(pts
						(arc
							(start -0.3302 -0.4318)
							(mid -0.402042 -0.402042)
							(end -0.4318 -0.3302)
						)
						(arc
							(start -0.4318 0.3302)
							(mid -0.402042 0.402042)
							(end -0.3302 0.4318)
						)
						(arc
							(start 0.3302 0.4318)
							(mid 0.402042 0.402042)
							(end 0.4318 0.3302)
						)
						(arc
							(start 0.4318 -0.3302)
							(mid 0.402042 -0.402042)
							(end 0.3302 -0.4318)
						)
					)
					(width 0)
					(fill yes)
				)
			)
		)
	)
	(footprint ""
		(layer "F.Cu")
		(at 14.224 -157.353 180)
		(property "Reference" "R181"
			(at 0 0 180)
			(layer "F.SilkS")
			(hide yes)
			(effects
				(font
					(size 1.27 1.27)
				)
			)
		)
		(property "Value" "0R1206-PAD-1-GP"
			(at 0 -5.0292 180)
			(unlocked yes)
			(layer "F.Fab")
			(hide yes)
			(effects
				(font
					(size 1.016 1.016)
					(thickness 0.1524)
				)
			)
		)
		(property "Device Type" "0R1206-PAD-1"
			(at 0 -6.5532 180)
			(unlocked yes)
			(layer "F.Fab")
			(hide yes)
			(effects
				(font
					(size 1.016 1.016)
					(thickness 0.1524)
				)
			)
		)
		(duplicate_pad_numbers_are_jumpers no)
		(fp_line
			(start 1.016 2.2352)
			(end 1.016 -2.2352)
			(stroke
				(width 0.1524)
				(type default)
			)
			(layer "F.SilkS")
		)
		(fp_line
			(start 1.016 -2.2352)
			(end -1.016 -2.2352)
			(stroke
				(width 0.1524)
				(type default)
			)
			(layer "F.SilkS")
		)
		(fp_line
			(start -1.016 2.2352)
			(end 1.016 2.2352)
			(stroke
				(width 0.1524)
				(type default)
			)
			(layer "F.SilkS")
		)
		(fp_line
			(start -1.016 -2.2352)
			(end -1.016 2.2352)
			(stroke
				(width 0.1524)
				(type default)
			)
			(layer "F.SilkS")
		)
		(fp_rect
			(start -1.0922 2.3114)
			(end 1.0922 -2.3114)
			(stroke
				(width 0)
				(type default)
			)
			(fill no)
			(layer "F.CrtYd")
		)
		(fp_poly
			(pts
				(xy -1.0922 -2.3114) (xy 1.0922 -2.3114) (xy 1.0922 2.3114) (xy -1.0922 2.3114)
			)
			(stroke
				(width 0)
				(type default)
			)
			(fill no)
			(layer "F.Fab")
		)
		(pad "1" smd rect
			(at 0 -1.397 180)
			(size 1.651 2.0574)
			(drill
				(offset 0 0.3937)
			)
			(layers "F.Cu" "F.Mask" "F.Paste")
			(net "P12V_FAN5")
		)
		(pad "2" smd rect
			(at 0 1.397 180)
			(size 1.651 2.0574)
			(drill
				(offset 0 -0.3937)
			)
			(layers "F.Cu" "F.Mask" "F.Paste")
			(net "P12V")
		)
	)
	(footprint ""
		(layer "F.Cu")
		(at 15.494 -60.5282 180)
		(property "Reference" "R359"
			(at 0 0 180)
			(layer "F.SilkS")
			(hide yes)
			(effects
				(font
					(size 1.27 1.27)
				)
			)
		)
		(property "Value" "10KR2F-2-GP"
			(at 0.064008 -3.993896 180)
			(unlocked yes)
			(layer "F.Fab")
			(hide yes)
			(effects
				(font
					(size 1.016 1.016)
					(thickness 0.1524)
				)
			)
		)
		(property "Device Type" "R402H16"
			(at 0.064008 -5.517896 180)
			(unlocked yes)
			(layer "F.Fab")
			(hide yes)
			(effects
				(font
					(size 1.016 1.016)
					(thickness 0.1524)
				)
			)
		)
		(duplicate_pad_numbers_are_jumpers no)
		(fp_line
			(start 0.508 -0.9398)
			(end -0.508 -0.9398)
			(stroke
				(width 0.1524)
				(type default)
			)
			(layer "F.SilkS")
		)
		(fp_line
			(start -0.508 -0.9398)
			(end -0.508 0.9398)
			(stroke
				(width 0.1524)
				(type default)
			)
			(layer "F.SilkS")
		)
		(fp_rect
			(start -0.508 0.9398)
			(end 0.508 -0.9398)
			(stroke
				(width 0)
				(type default)
			)
			(fill no)
			(layer "F.CrtYd")
		)
		(fp_rect
			(start -0.508 0.9398)
			(end 0.508 -0.9398)
			(stroke
				(width 0)
				(type default)
			)
			(fill no)
			(layer "F.Fab")
		)
		(pad "1" smd custom
			(at 0 -0.4445 180)
			(size 0.1397 0.1397)
			(layers "F.Cu" "F.Mask" "F.Paste")
			(net "P3V3")
			(options
				(clearance outline)
				(anchor circle)
			)
			(primitives
				(gr_poly
					(pts
						(arc
							(start -0.1778 -0.2794)
							(mid -0.249642 -0.249642)
							(end -0.2794 -0.1778)
						)
						(arc
							(start -0.2794 0.1778)
							(mid -0.249642 0.249642)
							(end -0.1778 0.2794)
						)
						(arc
							(start 0.1778 0.2794)
							(mid 0.249642 0.249642)
							(end 0.2794 0.1778)
						)
						(arc
							(start 0.2794 -0.1778)
							(mid 0.249642 -0.249642)
							(end 0.1778 -0.2794)
						)
					)
					(width 0)
					(fill yes)
				)
			)
		)
		(pad "2" smd custom
			(at 0 0.4445 180)
			(size 0.1397 0.1397)
			(layers "F.Cu" "F.Mask" "F.Paste")
			(net "UPPER_TRAY_ID")
			(options
				(clearance outline)
				(anchor circle)
			)
			(primitives
				(gr_poly
					(pts
						(arc
							(start -0.1778 -0.2794)
							(mid -0.249642 -0.249642)
							(end -0.2794 -0.1778)
						)
						(arc
							(start -0.2794 0.1778)
							(mid -0.249642 0.249642)
							(end -0.1778 0.2794)
						)
						(arc
							(start 0.1778 0.2794)
							(mid 0.249642 0.249642)
							(end 0.2794 0.1778)
						)
						(arc
							(start 0.2794 -0.1778)
							(mid 0.249642 -0.249642)
							(end 0.1778 -0.2794)
						)
					)
					(width 0)
					(fill yes)
				)
			)
		)
	)
	(footprint ""
		(layer "F.Cu")
		(at 33.401 -240.3094 180)
		(property "Reference" "R54"
			(at 0 0 180)
			(layer "F.SilkS")
			(hide yes)
			(effects
				(font
					(size 1.27 1.27)
				)
			)
		)
		(property "Value" "4K7R2J-2-GP"
			(at 0.064008 -3.993896 180)
			(unlocked yes)
			(layer "F.Fab")
			(hide yes)
			(effects
				(font
					(size 1.016 1.016)
					(thickness 0.1524)
				)
			)
		)
		(property "Device Type" "R402H16"
			(at 0.064008 -5.517896 180)
			(unlocked yes)
			(layer "F.Fab")
			(hide yes)
			(effects
				(font
					(size 1.016 1.016)
					(thickness 0.1524)
				)
			)
		)
		(duplicate_pad_numbers_are_jumpers no)
		(fp_line
			(start 0.508 -0.9398)
			(end -0.508 -0.9398)
			(stroke
				(width 0.1524)
				(type default)
			)
			(layer "F.SilkS")
		)
		(fp_line
			(start -0.508 -0.9398)
			(end -0.508 0.9398)
			(stroke
				(width 0.1524)
				(type default)
			)
			(layer "F.SilkS")
		)
		(fp_rect
			(start -0.508 0.9398)
			(end 0.508 -0.9398)
			(stroke
				(width 0)
				(type default)
			)
			(fill no)
			(layer "F.CrtYd")
		)
		(fp_rect
			(start -0.508 0.9398)
			(end 0.508 -0.9398)
			(stroke
				(width 0)
				(type default)
			)
			(fill no)
			(layer "F.Fab")
		)
		(pad "1" smd custom
			(at 0 -0.4445 180)
			(size 0.1397 0.1397)
			(layers "F.Cu" "F.Mask" "F.Paste")
			(net "GND")
			(options
				(clearance outline)
				(anchor circle)
			)
			(primitives
				(gr_poly
					(pts
						(arc
							(start -0.1778 -0.2794)
							(mid -0.249642 -0.249642)
							(end -0.2794 -0.1778)
						)
						(arc
							(start -0.2794 0.1778)
							(mid -0.249642 0.249642)
							(end -0.1778 0.2794)
						)
						(arc
							(start 0.1778 0.2794)
							(mid 0.249642 0.249642)
							(end 0.2794 0.1778)
						)
						(arc
							(start 0.2794 -0.1778)
							(mid 0.249642 -0.249642)
							(end 0.1778 -0.2794)
						)
					)
					(width 0)
					(fill yes)
				)
			)
		)
		(pad "2" smd custom
			(at 0 0.4445 180)
			(size 0.1397 0.1397)
			(layers "F.Cu" "F.Mask" "F.Paste")
			(net "LED_DRV_A0")
			(options
				(clearance outline)
				(anchor circle)
			)
			(primitives
				(gr_poly
					(pts
						(arc
							(start -0.1778 -0.2794)
							(mid -0.249642 -0.249642)
							(end -0.2794 -0.1778)
						)
						(arc
							(start -0.2794 0.1778)
							(mid -0.249642 0.249642)
							(end -0.1778 0.2794)
						)
						(arc
							(start 0.1778 0.2794)
							(mid 0.249642 0.249642)
							(end 0.2794 0.1778)
						)
						(arc
							(start 0.2794 -0.1778)
							(mid 0.249642 -0.249642)
							(end 0.1778 -0.2794)
						)
					)
					(width 0)
					(fill yes)
				)
			)
		)
	)
	(footprint ""
		(layer "F.Cu")
		(at 28.2956 -141.8082 90)
		(property "Reference" "PC97"
			(at 0 0 90)
			(layer "F.SilkS")
			(hide yes)
			(effects
				(font
					(size 1.27 1.27)
				)
			)
		)
		(property "Value" "SC10U25V5KX-GP"
			(at -0.0762 -6.1214 90)
			(unlocked yes)
			(layer "F.Fab")
			(hide yes)
			(effects
				(font
					(size 1.016 1.016)
					(thickness 0.1524)
				)
			)
		)
		(property "Device Type" "C805H56"
			(at -0.0762 -8.1534 90)
			(unlocked yes)
			(layer "F.Fab")
			(hide yes)
			(effects
				(font
					(size 1.016 1.016)
					(thickness 0.1524)
				)
			)
		)
		(duplicate_pad_numbers_are_jumpers no)
		(fp_line
			(start 0.635 0)
			(end -0.635 0)
			(stroke
				(width 0.508)
				(type default)
			)
			(layer "F.SilkS")
		)
		(fp_rect
			(start -0.9652 1.778)
			(end 0.9652 -1.778)
			(stroke
				(width 0)
				(type default)
			)
			(fill no)
			(layer "F.CrtYd")
		)
		(fp_poly
			(pts
				(xy -0.9652 -1.778) (xy 0.9652 -1.778) (xy 0.9652 1.778) (xy -0.9652 1.778)
			)
			(stroke
				(width 0)
				(type default)
			)
			(fill no)
			(layer "F.Fab")
		)
		(pad "1" smd rect
			(at 0 -0.9652 90)
			(size 1.397 1.143)
			(layers "F.Cu" "F.Mask" "F.Paste")
			(net "P12VU_2490_EN_2")
		)
		(pad "2" smd rect
			(at 0 0.9652 90)
			(size 1.397 1.143)
			(layers "F.Cu" "F.Mask" "F.Paste")
			(net "GND")
		)
	)
	(footprint ""
		(layer "F.Cu")
		(at 11.0236 -227.1776 180)
		(property "Reference" "R33"
			(at 0 0 180)
			(layer "F.SilkS")
			(hide yes)
			(effects
				(font
					(size 1.27 1.27)
				)
			)
		)
		(property "Value" "33R2F-3-GP"
			(at 0.064008 -3.993896 180)
			(unlocked yes)
			(layer "F.Fab")
			(hide yes)
			(effects
				(font
					(size 1.016 1.016)
					(thickness 0.1524)
				)
			)
		)
		(property "Device Type" "R402H16"
			(at 0.064008 -5.517896 180)
			(unlocked yes)
			(layer "F.Fab")
			(hide yes)
			(effects
				(font
					(size 1.016 1.016)
					(thickness 0.1524)
				)
			)
		)
		(duplicate_pad_numbers_are_jumpers no)
		(fp_line
			(start 0.508 -0.9398)
			(end -0.508 -0.9398)
			(stroke
				(width 0.1524)
				(type default)
			)
			(layer "F.SilkS")
		)
		(fp_line
			(start -0.508 -0.9398)
			(end -0.508 0.9398)
			(stroke
				(width 0.1524)
				(type default)
			)
			(layer "F.SilkS")
		)
		(fp_rect
			(start -0.508 0.9398)
			(end 0.508 -0.9398)
			(stroke
				(width 0)
				(type default)
			)
			(fill no)
			(layer "F.CrtYd")
		)
		(fp_rect
			(start -0.508 0.9398)
			(end 0.508 -0.9398)
			(stroke
				(width 0)
				(type default)
			)
			(fill no)
			(layer "F.Fab")
		)
		(pad "1" smd custom
			(at 0 -0.4445 180)
			(size 0.1397 0.1397)
			(layers "F.Cu" "F.Mask" "F.Paste")
			(net "P3V3")
			(options
				(clearance outline)
				(anchor circle)
			)
			(primitives
				(gr_poly
					(pts
						(arc
							(start -0.1778 -0.2794)
							(mid -0.249642 -0.249642)
							(end -0.2794 -0.1778)
						)
						(arc
							(start -0.2794 0.1778)
							(mid -0.249642 0.249642)
							(end -0.1778 0.2794)
						)
						(arc
							(start 0.1778 0.2794)
							(mid 0.249642 0.249642)
							(end 0.2794 0.1778)
						)
						(arc
							(start 0.2794 -0.1778)
							(mid 0.249642 -0.249642)
							(end 0.1778 -0.2794)
						)
					)
					(width 0)
					(fill yes)
				)
			)
		)
		(pad "2" smd custom
			(at 0 0.4445 180)
			(size 0.1397 0.1397)
			(layers "F.Cu" "F.Mask" "F.Paste")
			(net "LED_DR_LED3_BLUE")
			(options
				(clearance outline)
				(anchor circle)
			)
			(primitives
				(gr_poly
					(pts
						(arc
							(start -0.1778 -0.2794)
							(mid -0.249642 -0.249642)
							(end -0.2794 -0.1778)
						)
						(arc
							(start -0.2794 0.1778)
							(mid -0.249642 0.249642)
							(end -0.1778 0.2794)
						)
						(arc
							(start 0.1778 0.2794)
							(mid 0.249642 0.249642)
							(end 0.2794 0.1778)
						)
						(arc
							(start 0.2794 -0.1778)
							(mid 0.249642 -0.249642)
							(end 0.1778 -0.2794)
						)
					)
					(width 0)
					(fill yes)
				)
			)
		)
	)
	(footprint ""
		(layer "F.Cu")
		(at 34.3916 -184.4802)
		(property "Reference" "PQ10"
			(at 0 0 0)
			(layer "F.SilkS")
			(hide yes)
			(effects
				(font
					(size 1.27 1.27)
				)
			)
		)
		(property "Value" "PMBS3904-1-GP"
			(at 0 -9.0932 0)
			(unlocked yes)
			(layer "F.Fab")
			(hide yes)
			(effects
				(font
					(size 1.016 1.016)
					(thickness 0.1524)
				)
			)
		)
		(property "Device Type" "SOT-23-10H44"
			(at 0 -10.6172 0)
			(unlocked yes)
			(layer "F.Fab")
			(hide yes)
			(effects
				(font
					(size 1.016 1.016)
					(thickness 0.1524)
				)
			)
		)
		(duplicate_pad_numbers_are_jumpers no)
		(fp_line
			(start -1.7526 1.8796)
			(end -1.7526 0.9906)
			(stroke
				(width 0.3302)
				(type default)
			)
			(layer "F.SilkS")
		)
		(fp_line
			(start -1.651 -1.778)
			(end -1.651 1.778)
			(stroke
				(width 0.1524)
				(type default)
			)
			(layer "F.SilkS")
		)
		(fp_line
			(start -1.651 1.778)
			(end 1.651 1.778)
			(stroke
				(width 0.1524)
				(type default)
			)
			(layer "F.SilkS")
		)
		(fp_line
			(start -1.279398 2.152142)
			(end -0.9906 1.86309)
			(stroke
				(width 0.0127)
				(type default)
			)
			(layer "F.SilkS")
		)
		(fp_line
			(start -1.279144 2.15265)
			(end -0.701294 2.15265)
			(stroke
				(width 0.0127)
				(type default)
			)
			(layer "F.SilkS")
		)
		(fp_line
			(start -1.260856 2.1336)
			(end -0.720344 2.1336)
			(stroke
				(width 0.0127)
				(type default)
			)
			(layer "F.SilkS")
		)
		(fp_line
			(start -1.251458 2.124202)
			(end -0.729996 2.124202)
			(stroke
				(width 0.0127)
				(type default)
			)
			(layer "F.SilkS")
		)
		(fp_line
			(start -1.241806 2.11455)
			(end -0.739394 2.11455)
			(stroke
				(width 0.0127)
				(type default)
			)
			(layer "F.SilkS")
		)
		(fp_line
			(start -1.232408 2.105152)
			(end -0.749046 2.105152)
			(stroke
				(width 0.0127)
				(type default)
			)
			(layer "F.SilkS")
		)
		(fp_line
			(start -1.222756 2.0955)
			(end -0.758444 2.0955)
			(stroke
				(width 0.0127)
				(type default)
			)
			(layer "F.SilkS")
		)
		(fp_line
			(start -1.213358 2.086102)
			(end -0.768096 2.086102)
			(stroke
				(width 0.0127)
				(type default)
			)
			(layer "F.SilkS")
		)
		(fp_line
			(start -1.203706 2.07645)
			(end -0.777494 2.07645)
			(stroke
				(width 0.0127)
				(type default)
			)
			(layer "F.SilkS")
		)
		(fp_line
			(start -1.194308 2.067052)
			(end -0.787146 2.067052)
			(stroke
				(width 0.0127)
				(type default)
			)
			(layer "F.SilkS")
		)
		(fp_line
			(start -1.184656 2.0574)
			(end -0.796544 2.0574)
			(stroke
				(width 0.0127)
				(type default)
			)
			(layer "F.SilkS")
		)
		(fp_line
			(start -1.175258 2.048002)
			(end -0.806196 2.048002)
			(stroke
				(width 0.0127)
				(type default)
			)
			(layer "F.SilkS")
		)
		(fp_line
			(start -1.165606 2.03835)
			(end -0.815594 2.03835)
			(stroke
				(width 0.0127)
				(type default)
			)
			(layer "F.SilkS")
		)
		(fp_line
			(start -1.156208 2.028952)
			(end -0.825246 2.028952)
			(stroke
				(width 0.0127)
				(type default)
			)
			(layer "F.SilkS")
		)
		(fp_line
			(start -1.146556 2.0193)
			(end -0.834644 2.0193)
			(stroke
				(width 0.0127)
				(type default)
			)
			(layer "F.SilkS")
		)
		(fp_line
			(start -1.137158 2.009902)
			(end -0.844296 2.009902)
			(stroke
				(width 0.0127)
				(type default)
			)
			(layer "F.SilkS")
		)
		(fp_line
			(start -1.127506 2.00025)
			(end -0.853694 2.00025)
			(stroke
				(width 0.0127)
				(type default)
			)
			(layer "F.SilkS")
		)
		(fp_line
			(start -1.118108 1.990852)
			(end -0.863346 1.990852)
			(stroke
				(width 0.0127)
				(type default)
			)
			(layer "F.SilkS")
		)
		(fp_line
			(start -1.108456 1.9812)
			(end -0.872744 1.9812)
			(stroke
				(width 0.0127)
				(type default)
			)
			(layer "F.SilkS")
		)
		(fp_line
			(start -1.099058 1.971802)
			(end -0.882396 1.971802)
			(stroke
				(width 0.0127)
				(type default)
			)
			(layer "F.SilkS")
		)
		(fp_line
			(start -1.089406 1.96215)
			(end -0.891794 1.96215)
			(stroke
				(width 0.0127)
				(type default)
			)
			(layer "F.SilkS")
		)
		(fp_line
			(start -1.080008 1.952752)
			(end -0.901446 1.952752)
			(stroke
				(width 0.0127)
				(type default)
			)
			(layer "F.SilkS")
		)
		(fp_line
			(start -1.070356 1.9431)
			(end -0.910844 1.9431)
			(stroke
				(width 0.0127)
				(type default)
			)
			(layer "F.SilkS")
		)
		(fp_line
			(start -1.060958 1.933702)
			(end -0.920496 1.933702)
			(stroke
				(width 0.0127)
				(type default)
			)
			(layer "F.SilkS")
		)
		(fp_line
			(start -1.051306 1.92405)
			(end -0.929894 1.92405)
			(stroke
				(width 0.0127)
				(type default)
			)
			(layer "F.SilkS")
		)
		(fp_line
			(start -1.041908 1.914652)
			(end -0.939546 1.914652)
			(stroke
				(width 0.0127)
				(type default)
			)
			(layer "F.SilkS")
		)
		(fp_line
			(start -1.032256 1.905)
			(end -0.948944 1.905)
			(stroke
				(width 0.0127)
				(type default)
			)
			(layer "F.SilkS")
		)
		(fp_line
			(start -1.022858 1.895602)
			(end -0.958596 1.895602)
			(stroke
				(width 0.0127)
				(type default)
			)
			(layer "F.SilkS")
		)
		(fp_line
			(start -1.013206 1.88595)
			(end -0.967994 1.88595)
			(stroke
				(width 0.0127)
				(type default)
			)
			(layer "F.SilkS")
		)
		(fp_line
			(start -1.003808 1.876552)
			(end -0.977646 1.876552)
			(stroke
				(width 0.0127)
				(type default)
			)
			(layer "F.SilkS")
		)
		(fp_line
			(start -0.994156 1.8669)
			(end -0.987044 1.8669)
			(stroke
				(width 0.0127)
				(type default)
			)
			(layer "F.SilkS")
		)
		(fp_line
			(start -0.9906 1.86309)
			(end -0.701294 2.15265)
			(stroke
				(width 0.0127)
				(type default)
			)
			(layer "F.SilkS")
		)
		(fp_line
			(start -0.719074 2.145538)
			(end -1.265936 2.14122)
			(stroke
				(width 0.0127)
				(type default)
			)
			(layer "F.SilkS")
		)
		(fp_line
			(start -0.71628 2.15265)
			(end -1.26492 2.15265)
			(stroke
				(width 0.0127)
				(type default)
			)
			(layer "F.SilkS")
		)
		(fp_line
			(start -0.635 1.8796)
			(end -1.7526 1.8796)
			(stroke
				(width 0.3302)
				(type default)
			)
			(layer "F.SilkS")
		)
		(fp_line
			(start 1.651 -1.778)
			(end -1.651 -1.778)
			(stroke
				(width 0.1524)
				(type default)
			)
			(layer "F.SilkS")
		)
		(fp_line
			(start 1.651 1.778)
			(end 1.651 -1.778)
			(stroke
				(width 0.1524)
				(type default)
			)
			(layer "F.SilkS")
		)
		(fp_poly
			(pts
				(xy -1.285748 2.159) (xy -1.285748 1.8796) (xy -1.778 1.8796) (xy -1.778 -1.8796) (xy 1.778 -1.8796)
				(xy 1.778 1.8796) (xy -0.694944 1.8796) (xy -0.694944 2.159)
			)
			(stroke
				(width 0)
				(type default)
			)
			(fill no)
			(layer "F.CrtYd")
		)
		(fp_poly
			(pts
				(xy -1.285748 2.159) (xy -1.285748 1.8796) (xy -1.778 1.8796) (xy -1.778 -1.8796) (xy 1.778 -1.8796)
				(xy 1.778 1.8796) (xy -0.694944 1.8796) (xy -0.694944 2.159)
			)
			(stroke
				(width 0)
				(type default)
			)
			(fill no)
			(layer "F.Fab")
		)
		(pad "1" smd rect
			(at -0.98425 0.9525)
			(size 0.762 1.143)
			(layers "F.Cu" "F.Mask" "F.Paste")
			(net "P3V3_AUX_BJT_B")
		)
		(pad "2" smd rect
			(at 0.98425 0.9525)
			(size 0.762 1.143)
			(layers "F.Cu" "F.Mask" "F.Paste")
			(net "P3V3_AUX")
		)
		(pad "3" smd rect
			(at 0 -0.9525)
			(size 0.762 1.143)
			(layers "F.Cu" "F.Mask" "F.Paste")
			(net "P12V_AUX")
		)
	)
	(footprint ""
		(layer "F.Cu")
		(at 33.401 -363.728 -90)
		(property "Reference" "C51"
			(at 0 0 270)
			(layer "F.SilkS")
			(hide yes)
			(effects
				(font
					(size 1.27 1.27)
				)
			)
		)
		(property "Value" "SCD1U10V2KX-4-LL-GP"
			(at 1.1811 -2.7051 270)
			(unlocked yes)
			(layer "F.Fab")
			(hide yes)
			(effects
				(font
					(size 1.016 1.016)
					(thickness 0.1524)
				)
			)
		)
		(property "Device Type" "C402H22"
			(at 1.1811 -4.2291 270)
			(unlocked yes)
			(layer "F.Fab")
			(hide yes)
			(effects
				(font
					(size 1.016 1.016)
					(thickness 0.1524)
				)
			)
		)
		(duplicate_pad_numbers_are_jumpers no)
		(fp_rect
			(start -0.4318 0.9525)
			(end 0.4318 -0.9525)
			(stroke
				(width 0)
				(type default)
			)
			(fill no)
			(layer "F.CrtYd")
		)
		(fp_rect
			(start -0.4318 0.9525)
			(end 0.4318 -0.9525)
			(stroke
				(width 0)
				(type default)
			)
			(fill no)
			(layer "F.Fab")
		)
		(pad "1" smd custom
			(at 0 -0.4445 270)
			(size 0.1524 0.1524)
			(layers "F.Cu" "F.Mask" "F.Paste")
			(net "TEMP_ALM#_REVERSE_R")
			(options
				(clearance outline)
				(anchor circle)
			)
			(primitives
				(gr_poly
					(pts
						(arc
							(start 0.3048 -0.2032)
							(mid 0.275042 -0.275042)
							(end 0.2032 -0.3048)
						)
						(arc
							(start -0.2032 -0.3048)
							(mid -0.275042 -0.275042)
							(end -0.3048 -0.2032)
						)
						(arc
							(start -0.3048 0.2032)
							(mid -0.275042 0.275042)
							(end -0.2032 0.3048)
						)
						(arc
							(start 0.2032 0.3048)
							(mid 0.275042 0.275042)
							(end 0.3048 0.2032)
						)
					)
					(width 0)
					(fill yes)
				)
			)
		)
		(pad "2" smd custom
			(at 0 0.4445 270)
			(size 0.1524 0.1524)
			(layers "F.Cu" "F.Mask" "F.Paste")
			(net "GND")
			(options
				(clearance outline)
				(anchor circle)
			)
			(primitives
				(gr_poly
					(pts
						(arc
							(start 0.3048 -0.2032)
							(mid 0.275042 -0.275042)
							(end 0.2032 -0.3048)
						)
						(arc
							(start -0.2032 -0.3048)
							(mid -0.275042 -0.275042)
							(end -0.3048 -0.2032)
						)
						(arc
							(start -0.3048 0.2032)
							(mid -0.275042 0.275042)
							(end -0.2032 0.3048)
						)
						(arc
							(start 0.2032 0.3048)
							(mid 0.275042 0.275042)
							(end 0.3048 0.2032)
						)
					)
					(width 0)
					(fill yes)
				)
			)
		)
	)
	(footprint ""
		(layer "F.Cu")
		(at 24.500078 -450.44995 90)
		(property "Reference" "PAD1"
			(at 0 0 90)
			(layer "F.SilkS")
			(hide yes)
			(effects
				(font
					(size 1.27 1.27)
				)
			)
		)
		(property "Value" "PAD-1P-424137-2-OG-GP"
			(at -22.9743 -0.4572 90)
			(unlocked yes)
			(layer "F.Fab")
			(hide yes)
			(effects
				(font
					(size 1.016 1.016)
					(thickness 0.1524)
				)
			)
		)
		(property "Device Type" "PAD-1P-424137-2-OG"
			(at -22.9743 -1.9812 90)
			(unlocked yes)
			(layer "F.Fab")
			(hide yes)
			(effects
				(font
					(size 1.016 1.016)
					(thickness 0.1524)
				)
			)
		)
		(duplicate_pad_numbers_are_jumpers no)
		(fp_line
			(start 21.4503 -7.0993)
			(end 21.4503 7.0993)
			(stroke
				(width 0.1524)
				(type default)
			)
			(layer "F.SilkS")
		)
		(fp_line
			(start -21.4503 -7.0993)
			(end 21.4503 -7.0993)
			(stroke
				(width 0.1524)
				(type default)
			)
			(layer "F.SilkS")
		)
		(fp_line
			(start -0.075946 5.750052)
			(end -0.075946 7.0993)
			(stroke
				(width 0.1524)
				(type default)
			)
			(layer "F.SilkS")
		)
		(fp_line
			(start 21.4503 7.0993)
			(end 2.816098 7.0993)
			(stroke
				(width 0.1524)
				(type default)
			)
			(layer "F.SilkS")
		)
		(fp_line
			(start 2.816098 7.0993)
			(end 2.816098 5.750052)
			(stroke
				(width 0.1524)
				(type default)
			)
			(layer "F.SilkS")
		)
		(fp_line
			(start -0.075946 7.0993)
			(end -21.4503 7.0993)
			(stroke
				(width 0.1524)
				(type default)
			)
			(layer "F.SilkS")
		)
		(fp_line
			(start -21.4503 7.0993)
			(end -21.4503 -7.0993)
			(stroke
				(width 0.1524)
				(type default)
			)
			(layer "F.SilkS")
		)
		(fp_arc
			(start -0.075946 5.750052)
			(mid 1.37008 4.304026)
			(end 2.816098 5.750052)
			(stroke
				(width 0.1524)
				(type default)
			)
			(layer "F.SilkS")
		)
		(fp_poly
			(pts
				(xy -21.7043 7.3533) (xy -21.7043 -7.3533) (xy 21.7043 -7.3533) (xy 21.7043 7.3533) (xy 2.562098 7.3533)
				(arc
					(start 2.562098 5.750052)
					(mid 1.370076 4.55803)
					(end 0.178054 5.750052)
				)
				(xy 0.178054 7.3533)
			)
			(stroke
				(width 0)
				(type default)
			)
			(fill no)
			(layer "F.CrtYd")
		)
		(fp_poly
			(pts
				(xy -21.7043 7.3533) (xy -21.7043 -7.3533) (xy 21.7043 -7.3533) (xy 21.7043 7.3533) (xy 2.562098 7.3533)
				(arc
					(start 2.562098 5.750052)
					(mid 1.370076 4.55803)
					(end 0.178054 5.750052)
				)
				(xy 0.178054 7.3533)
			)
			(stroke
				(width 0)
				(type default)
			)
			(fill no)
			(layer "F.Fab")
		)
		(pad "1" smd custom
			(at 0 0 90)
			(size 3.425063 3.425063)
			(layers "F.Cu" "F.Mask" "F.Paste")
			(net "P12V_AUX")
			(options
				(clearance outline)
				(anchor circle)
			)
			(primitives
				(gr_poly
					(pts
						(xy -0.329946 6.850126) (xy -21.20011 6.850126) (xy -21.20011 -6.850126) (xy 21.20011 -6.850126)
						(xy 21.20011 6.850126) (xy 3.070098 6.850126)
						(arc
							(start 3.070098 5.750052)
							(mid 1.370076 4.05003)
							(end -0.329946 5.750052)
						)
					)
					(width 0)
					(fill yes)
				)
			)
		)
	)
	(footprint ""
		(layer "F.Cu")
		(at 8.0518 -144.9832 -90)
		(property "Reference" "R64"
			(at 0 0 270)
			(layer "F.SilkS")
			(hide yes)
			(effects
				(font
					(size 1.27 1.27)
				)
			)
		)
		(property "Value" "4K7R2F-GP"
			(at 0.064008 -3.993896 270)
			(unlocked yes)
			(layer "F.Fab")
			(hide yes)
			(effects
				(font
					(size 1.016 1.016)
					(thickness 0.1524)
				)
			)
		)
		(property "Device Type" "R402H16"
			(at 0.064008 -5.517896 270)
			(unlocked yes)
			(layer "F.Fab")
			(hide yes)
			(effects
				(font
					(size 1.016 1.016)
					(thickness 0.1524)
				)
			)
		)
		(duplicate_pad_numbers_are_jumpers no)
		(fp_line
			(start -0.508 -0.9398)
			(end -0.508 0.9398)
			(stroke
				(width 0.1524)
				(type default)
			)
			(layer "F.SilkS")
		)
		(fp_line
			(start 0.508 -0.9398)
			(end -0.508 -0.9398)
			(stroke
				(width 0.1524)
				(type default)
			)
			(layer "F.SilkS")
		)
		(fp_rect
			(start -0.508 0.9398)
			(end 0.508 -0.9398)
			(stroke
				(width 0)
				(type default)
			)
			(fill no)
			(layer "F.CrtYd")
		)
		(fp_rect
			(start -0.508 0.9398)
			(end 0.508 -0.9398)
			(stroke
				(width 0)
				(type default)
			)
			(fill no)
			(layer "F.Fab")
		)
		(pad "1" smd custom
			(at 0 -0.4445 270)
			(size 0.1397 0.1397)
			(layers "F.Cu" "F.Mask" "F.Paste")
			(net "P12V")
			(options
				(clearance outline)
				(anchor circle)
			)
			(primitives
				(gr_poly
					(pts
						(arc
							(start -0.1778 -0.2794)
							(mid -0.249642 -0.249642)
							(end -0.2794 -0.1778)
						)
						(arc
							(start -0.2794 0.1778)
							(mid -0.249642 0.249642)
							(end -0.1778 0.2794)
						)
						(arc
							(start 0.1778 0.2794)
							(mid 0.249642 0.249642)
							(end 0.2794 0.1778)
						)
						(arc
							(start 0.2794 -0.1778)
							(mid 0.249642 -0.249642)
							(end 0.1778 -0.2794)
						)
					)
					(width 0)
					(fill yes)
				)
			)
		)
		(pad "2" smd custom
			(at 0 0.4445 270)
			(size 0.1397 0.1397)
			(layers "F.Cu" "F.Mask" "F.Paste")
			(net "PWM_OUT_FAN5_NET")
			(options
				(clearance outline)
				(anchor circle)
			)
			(primitives
				(gr_poly
					(pts
						(arc
							(start -0.1778 -0.2794)
							(mid -0.249642 -0.249642)
							(end -0.2794 -0.1778)
						)
						(arc
							(start -0.2794 0.1778)
							(mid -0.249642 0.249642)
							(end -0.1778 0.2794)
						)
						(arc
							(start 0.1778 0.2794)
							(mid 0.249642 0.249642)
							(end 0.2794 0.1778)
						)
						(arc
							(start 0.2794 -0.1778)
							(mid 0.249642 -0.249642)
							(end 0.1778 -0.2794)
						)
					)
					(width 0)
					(fill yes)
				)
			)
		)
	)
	(footprint ""
		(layer "F.Cu")
		(at 39.0652 -361.5436 90)
		(property "Reference" "PR46"
			(at 0 0 90)
			(layer "F.SilkS")
			(hide yes)
			(effects
				(font
					(size 1.27 1.27)
				)
			)
		)
		(property "Value" "51KR2F-L-GP"
			(at 0.064008 -3.993896 90)
			(unlocked yes)
			(layer "F.Fab")
			(hide yes)
			(effects
				(font
					(size 1.016 1.016)
					(thickness 0.1524)
				)
			)
		)
		(property "Device Type" "R402H16"
			(at 0.064008 -5.517896 90)
			(unlocked yes)
			(layer "F.Fab")
			(hide yes)
			(effects
				(font
					(size 1.016 1.016)
					(thickness 0.1524)
				)
			)
		)
		(duplicate_pad_numbers_are_jumpers no)
		(fp_line
			(start 0.508 -0.9398)
			(end -0.508 -0.9398)
			(stroke
				(width 0.1524)
				(type default)
			)
			(layer "F.SilkS")
		)
		(fp_line
			(start -0.508 -0.9398)
			(end -0.508 0.9398)
			(stroke
				(width 0.1524)
				(type default)
			)
			(layer "F.SilkS")
		)
		(fp_rect
			(start -0.508 0.9398)
			(end 0.508 -0.9398)
			(stroke
				(width 0)
				(type default)
			)
			(fill no)
			(layer "F.CrtYd")
		)
		(fp_rect
			(start -0.508 0.9398)
			(end 0.508 -0.9398)
			(stroke
				(width 0)
				(type default)
			)
			(fill no)
			(layer "F.Fab")
		)
		(pad "1" smd custom
			(at 0 -0.4445 90)
			(size 0.1397 0.1397)
			(layers "F.Cu" "F.Mask" "F.Paste")
			(net "P12V_AUX")
			(options
				(clearance outline)
				(anchor circle)
			)
			(primitives
				(gr_poly
					(pts
						(arc
							(start -0.1778 -0.2794)
							(mid -0.249642 -0.249642)
							(end -0.2794 -0.1778)
						)
						(arc
							(start -0.2794 0.1778)
							(mid -0.249642 0.249642)
							(end -0.1778 0.2794)
						)
						(arc
							(start 0.1778 0.2794)
							(mid 0.249642 0.249642)
							(end 0.2794 0.1778)
						)
						(arc
							(start 0.2794 -0.1778)
							(mid 0.249642 -0.249642)
							(end 0.1778 -0.2794)
						)
					)
					(width 0)
					(fill yes)
				)
			)
		)
		(pad "2" smd custom
			(at 0 0.4445 90)
			(size 0.1397 0.1397)
			(layers "F.Cu" "F.Mask" "F.Paste")
			(net "TEMP_ALM#_JP_1")
			(options
				(clearance outline)
				(anchor circle)
			)
			(primitives
				(gr_poly
					(pts
						(arc
							(start -0.1778 -0.2794)
							(mid -0.249642 -0.249642)
							(end -0.2794 -0.1778)
						)
						(arc
							(start -0.2794 0.1778)
							(mid -0.249642 0.249642)
							(end -0.1778 0.2794)
						)
						(arc
							(start 0.1778 0.2794)
							(mid 0.249642 0.249642)
							(end 0.2794 0.1778)
						)
						(arc
							(start 0.2794 -0.1778)
							(mid 0.249642 -0.249642)
							(end 0.1778 -0.2794)
						)
					)
					(width 0)
					(fill yes)
				)
			)
		)
	)
	(footprint ""
		(layer "F.Cu")
		(at 36.63569 -165.513766 180)
		(property "Reference" "R1"
			(at 0 0 180)
			(layer "F.SilkS")
			(hide yes)
			(effects
				(font
					(size 1.27 1.27)
				)
			)
		)
		(property "Value" "0R2J-2-GP"
			(at 0.064008 -3.993896 180)
			(unlocked yes)
			(layer "F.Fab")
			(hide yes)
			(effects
				(font
					(size 1.016 1.016)
					(thickness 0.1524)
				)
			)
		)
		(property "Device Type" "R402H16"
			(at 0.064008 -5.517896 180)
			(unlocked yes)
			(layer "F.Fab")
			(hide yes)
			(effects
				(font
					(size 1.016 1.016)
					(thickness 0.1524)
				)
			)
		)
		(duplicate_pad_numbers_are_jumpers no)
		(fp_line
			(start 0.508 -0.9398)
			(end -0.508 -0.9398)
			(stroke
				(width 0.1524)
				(type default)
			)
			(layer "F.SilkS")
		)
		(fp_line
			(start -0.508 -0.9398)
			(end -0.508 0.9398)
			(stroke
				(width 0.1524)
				(type default)
			)
			(layer "F.SilkS")
		)
		(fp_rect
			(start -0.508 0.9398)
			(end 0.508 -0.9398)
			(stroke
				(width 0)
				(type default)
			)
			(fill no)
			(layer "F.CrtYd")
		)
		(fp_rect
			(start -0.508 0.9398)
			(end 0.508 -0.9398)
			(stroke
				(width 0)
				(type default)
			)
			(fill no)
			(layer "F.Fab")
		)
		(pad "1" smd custom
			(at 0 -0.4445 180)
			(size 0.1397 0.1397)
			(layers "F.Cu" "F.Mask" "F.Paste")
			(net "I2C_C_SDA_NCT7904")
			(options
				(clearance outline)
				(anchor circle)
			)
			(primitives
				(gr_poly
					(pts
						(arc
							(start -0.1778 -0.2794)
							(mid -0.249642 -0.249642)
							(end -0.2794 -0.1778)
						)
						(arc
							(start -0.2794 0.1778)
							(mid -0.249642 0.249642)
							(end -0.1778 0.2794)
						)
						(arc
							(start 0.1778 0.2794)
							(mid 0.249642 0.249642)
							(end 0.2794 0.1778)
						)
						(arc
							(start 0.2794 -0.1778)
							(mid 0.249642 -0.249642)
							(end 0.1778 -0.2794)
						)
					)
					(width 0)
					(fill yes)
				)
			)
		)
		(pad "2" smd custom
			(at 0 0.4445 180)
			(size 0.1397 0.1397)
			(layers "F.Cu" "F.Mask" "F.Paste")
			(net "I2C_C_SDA")
			(options
				(clearance outline)
				(anchor circle)
			)
			(primitives
				(gr_poly
					(pts
						(arc
							(start -0.1778 -0.2794)
							(mid -0.249642 -0.249642)
							(end -0.2794 -0.1778)
						)
						(arc
							(start -0.2794 0.1778)
							(mid -0.249642 0.249642)
							(end -0.1778 0.2794)
						)
						(arc
							(start 0.1778 0.2794)
							(mid 0.249642 0.249642)
							(end 0.2794 0.1778)
						)
						(arc
							(start 0.2794 -0.1778)
							(mid 0.249642 -0.249642)
							(end 0.1778 -0.2794)
						)
					)
					(width 0)
					(fill yes)
				)
			)
		)
	)
	(footprint ""
		(layer "F.Cu")
		(at 16.9672 -256.9972 90)
		(property "Reference" "D7"
			(at 0 0 90)
			(layer "F.SilkS")
			(hide yes)
			(effects
				(font
					(size 1.27 1.27)
				)
			)
		)
		(property "Value" "BAS16H-GP"
			(at 0 -5.5372 90)
			(unlocked yes)
			(layer "F.Fab")
			(hide yes)
			(effects
				(font
					(size 1.016 1.016)
					(thickness 0.1524)
				)
			)
		)
		(property "Device Type" "SOD123AKH48"
			(at 0 -7.0612 90)
			(unlocked yes)
			(layer "F.Fab")
			(hide yes)
			(effects
				(font
					(size 1.016 1.016)
					(thickness 0.1524)
				)
			)
		)
		(duplicate_pad_numbers_are_jumpers no)
		(fp_line
			(start 1.016 -2.667)
			(end -1.016 -2.667)
			(stroke
				(width 0.1524)
				(type default)
			)
			(layer "F.SilkS")
		)
		(fp_line
			(start -1.016 -2.667)
			(end -1.016 2.667)
			(stroke
				(width 0.1524)
				(type default)
			)
			(layer "F.SilkS")
		)
		(fp_line
			(start 1.016 2.667)
			(end 1.016 -2.667)
			(stroke
				(width 0.1524)
				(type default)
			)
			(layer "F.SilkS")
		)
		(fp_line
			(start -1.016 2.667)
			(end 1.016 2.667)
			(stroke
				(width 0.1524)
				(type default)
			)
			(layer "F.SilkS")
		)
		(fp_line
			(start 0.889 2.921)
			(end -0.889 2.921)
			(stroke
				(width 0.508)
				(type default)
			)
			(layer "F.SilkS")
		)
		(fp_rect
			(start -1.143 3.175)
			(end 1.143 -2.794)
			(stroke
				(width 0)
				(type default)
			)
			(fill no)
			(layer "F.CrtYd")
		)
		(fp_poly
			(pts
				(xy -1.143 -2.794) (xy 1.143 -2.794) (xy 1.143 3.175) (xy -1.143 3.175)
			)
			(stroke
				(width 0)
				(type default)
			)
			(fill no)
			(layer "F.Fab")
		)
		(pad "A" smd rect
			(at 0 -1.6891 90)
			(size 0.889 1.397)
			(layers "F.Cu" "F.Mask" "F.Paste")
			(net "FAN_TACH5")
		)
		(pad "K" smd rect
			(at 0 1.6891 90)
			(size 0.889 1.397)
			(layers "F.Cu" "F.Mask" "F.Paste")
			(net "P12V")
		)
	)
	(footprint ""
		(layer "F.Cu")
		(at 31.36011 -171.677076)
		(property "Reference" "C11"
			(at 0 0 0)
			(layer "F.SilkS")
			(hide yes)
			(effects
				(font
					(size 1.27 1.27)
				)
			)
		)
		(property "Value" "SCD1U50V3KX-GP"
			(at 0 -2.8194 0)
			(unlocked yes)
			(layer "F.Fab")
			(hide yes)
			(effects
				(font
					(size 1.016 1.016)
					(thickness 0.1524)
				)
			)
		)
		(property "Device Type" "C603H36"
			(at 0 -4.3434 0)
			(unlocked yes)
			(layer "F.Fab")
			(hide yes)
			(effects
				(font
					(size 1.016 1.016)
					(thickness 0.1524)
				)
			)
		)
		(duplicate_pad_numbers_are_jumpers no)
		(fp_line
			(start 0.508 0)
			(end -0.508 0)
			(stroke
				(width 0.2032)
				(type default)
			)
			(layer "F.SilkS")
		)
		(fp_rect
			(start -0.5842 1.3335)
			(end 0.5842 -1.3335)
			(stroke
				(width 0)
				(type default)
			)
			(fill no)
			(layer "F.CrtYd")
		)
		(fp_rect
			(start -0.5842 1.3335)
			(end 0.5842 -1.3335)
			(stroke
				(width 0)
				(type default)
			)
			(fill no)
			(layer "F.Fab")
		)
		(pad "1" smd custom
			(at 0 -0.762)
			(size 0.2159 0.2159)
			(layers "F.Cu" "F.Mask" "F.Paste")
			(net "P3V3")
			(options
				(clearance outline)
				(anchor circle)
			)
			(primitives
				(gr_poly
					(pts
						(arc
							(start -0.3302 -0.4318)
							(mid -0.402042 -0.402042)
							(end -0.4318 -0.3302)
						)
						(arc
							(start -0.4318 0.3302)
							(mid -0.402042 0.402042)
							(end -0.3302 0.4318)
						)
						(arc
							(start 0.3302 0.4318)
							(mid 0.402042 0.402042)
							(end 0.4318 0.3302)
						)
						(arc
							(start 0.4318 -0.3302)
							(mid 0.402042 -0.402042)
							(end 0.3302 -0.4318)
						)
					)
					(width 0)
					(fill yes)
				)
			)
		)
		(pad "2" smd custom
			(at 0 0.762)
			(size 0.2159 0.2159)
			(layers "F.Cu" "F.Mask" "F.Paste")
			(net "GND")
			(options
				(clearance outline)
				(anchor circle)
			)
			(primitives
				(gr_poly
					(pts
						(arc
							(start -0.3302 -0.4318)
							(mid -0.402042 -0.402042)
							(end -0.4318 -0.3302)
						)
						(arc
							(start -0.4318 0.3302)
							(mid -0.402042 0.402042)
							(end -0.3302 0.4318)
						)
						(arc
							(start 0.3302 0.4318)
							(mid 0.402042 0.402042)
							(end 0.4318 0.3302)
						)
						(arc
							(start 0.4318 -0.3302)
							(mid 0.402042 -0.402042)
							(end 0.3302 -0.4318)
						)
					)
					(width 0)
					(fill yes)
				)
			)
		)
	)
	(footprint ""
		(layer "F.Cu")
		(at 23.749 -106.426 90)
		(property "Reference" "TC3"
			(at 0 0 90)
			(layer "F.SilkS")
			(hide yes)
			(effects
				(font
					(size 1.27 1.27)
				)
			)
		)
		(property "Value" "ST68U16VDM-1-GP"
			(at 0 -9.6012 90)
			(unlocked yes)
			(layer "F.Fab")
			(hide yes)
			(effects
				(font
					(size 1.016 1.016)
					(thickness 0.1524)
				)
			)
		)
		(property "Device Type" "CT7343H79"
			(at 0 -11.1252 90)
			(unlocked yes)
			(layer "F.Fab")
			(hide yes)
			(effects
				(font
					(size 1.016 1.016)
					(thickness 0.1524)
				)
			)
		)
		(duplicate_pad_numbers_are_jumpers no)
		(fp_line
			(start 2.286 -4.8768)
			(end -2.286 -4.8768)
			(stroke
				(width 0.1524)
				(type default)
			)
			(layer "F.SilkS")
		)
		(fp_line
			(start -2.286 -4.8768)
			(end -2.286 -2.032)
			(stroke
				(width 0.1524)
				(type default)
			)
			(layer "F.SilkS")
		)
		(fp_line
			(start 2.1082 -4.699)
			(end -2.1082 -4.699)
			(stroke
				(width 0.508)
				(type default)
			)
			(layer "F.SilkS")
		)
		(fp_line
			(start 2.286 -2.032)
			(end 2.286 -4.8768)
			(stroke
				(width 0.1524)
				(type default)
			)
			(layer "F.SilkS")
		)
		(fp_line
			(start 2.286 2.032)
			(end 2.286 4.8768)
			(stroke
				(width 0.1524)
				(type default)
			)
			(layer "F.SilkS")
		)
		(fp_line
			(start 2.286 4.8768)
			(end -2.286 4.8768)
			(stroke
				(width 0.1524)
				(type default)
			)
			(layer "F.SilkS")
		)
		(fp_line
			(start -2.286 4.8768)
			(end -2.286 2.032)
			(stroke
				(width 0.1524)
				(type default)
			)
			(layer "F.SilkS")
		)
		(fp_rect
			(start -2.1463 3.6449)
			(end 2.1463 -3.6449)
			(stroke
				(width 0)
				(type default)
			)
			(fill no)
			(layer "F.CrtYd")
		)
		(fp_poly
			(pts
				(xy -2.54 4.953) (xy -2.54 4.2926) (xy -3.81 4.2926) (xy -3.81 -4.2926) (xy -2.54 -4.2926) (xy -2.54 -4.953)
				(xy 2.54 -4.953) (xy 2.54 -4.2926) (xy 3.81 -4.2926) (xy 3.81 -1.6256) (xy 2.1463 -1.6256) (xy 2.1463 -3.6449)
				(xy -2.1463 -3.6449) (xy -2.1463 3.6449) (xy 2.1463 3.6449) (xy 2.1463 -1.6129) (xy 3.81 -1.6129)
				(xy 3.81 4.2926) (xy 2.54 4.2926) (xy 2.54 4.953)
			)
			(stroke
				(width 0)
				(type default)
			)
			(fill no)
			(layer "F.CrtYd")
		)
		(fp_rect
			(start 2.54 4.2926)
			(end 3.81 -4.2926)
			(stroke
				(width 0)
				(type default)
			)
			(fill no)
			(layer "F.Fab")
		)
		(fp_rect
			(start -3.81 4.2926)
			(end -2.54 -4.2926)
			(stroke
				(width 0)
				(type default)
			)
			(fill no)
			(layer "F.Fab")
		)
		(fp_rect
			(start -2.54 4.953)
			(end 2.54 -4.953)
			(stroke
				(width 0)
				(type default)
			)
			(fill no)
			(layer "F.Fab")
		)
		(pad "1" smd rect
			(at 0 -3.1496 90)
			(size 2.413 2.286)
			(layers "F.Cu" "F.Mask" "F.Paste")
			(net "P12VU")
		)
		(pad "2" smd rect
			(at 0 3.1496 90)
			(size 2.413 2.286)
			(layers "F.Cu" "F.Mask" "F.Paste")
			(net "GND")
		)
		(zone
			(layer "F.Cu")
			(hatch none 0.5)
			(connect_pads
				(clearance 0)
			)
			(min_thickness 0.25)
			(keepout
				(tracks allowed)
				(vias not_allowed)
				(pads allowed)
				(copperpour not_allowed)
				(footprints allowed)
			)
			(placement
				(enabled no)
				(sheetname "")
			)
			(fill
				(thermal_gap 0.5)
				(thermal_bridge_width 0.5)
				(island_removal_mode 0)
			)
			(polygon
				(pts
					(xy 22.0599 -107.9373) (xy 19.1516 -107.9373) (xy 19.1516 -104.9147) (xy 22.0472 -104.9147) (xy 22.3774 -104.9147)
					(xy 22.3774 -107.9373)
				)
			)
		)
		(zone
			(layer "F.Cu")
			(hatch none 0.5)
			(connect_pads
				(clearance 0)
			)
			(min_thickness 0.25)
			(keepout
				(tracks allowed)
				(vias not_allowed)
				(pads allowed)
				(copperpour not_allowed)
				(footprints allowed)
			)
			(placement
				(enabled no)
				(sheetname "")
			)
			(fill
				(thermal_gap 0.5)
				(thermal_bridge_width 0.5)
				(island_removal_mode 0)
			)
			(polygon
				(pts
					(xy 28.3464 -104.9147) (xy 28.3464 -107.9373) (xy 25.4508 -107.9373) (xy 25.1206 -107.9373) (xy 25.1206 -104.9147)
					(xy 25.4508 -104.9147)
				)
			)
		)
	)
	(footprint ""
		(layer "F.Cu")
		(at 38.67531 -153.713434)
		(property "Reference" "C1"
			(at 0 0 0)
			(layer "F.SilkS")
			(hide yes)
			(effects
				(font
					(size 1.27 1.27)
				)
			)
		)
		(property "Value" "SC10U25V5KX-GP"
			(at -0.0762 -6.1214 0)
			(unlocked yes)
			(layer "F.Fab")
			(hide yes)
			(effects
				(font
					(size 1.016 1.016)
					(thickness 0.1524)
				)
			)
		)
		(property "Device Type" "C805H56"
			(at -0.0762 -8.1534 0)
			(unlocked yes)
			(layer "F.Fab")
			(hide yes)
			(effects
				(font
					(size 1.016 1.016)
					(thickness 0.1524)
				)
			)
		)
		(duplicate_pad_numbers_are_jumpers no)
		(fp_line
			(start 0.635 0)
			(end -0.635 0)
			(stroke
				(width 0.508)
				(type default)
			)
			(layer "F.SilkS")
		)
		(fp_rect
			(start -0.9652 1.778)
			(end 0.9652 -1.778)
			(stroke
				(width 0)
				(type default)
			)
			(fill no)
			(layer "F.CrtYd")
		)
		(fp_poly
			(pts
				(xy -0.9652 -1.778) (xy 0.9652 -1.778) (xy 0.9652 1.778) (xy -0.9652 1.778)
			)
			(stroke
				(width 0)
				(type default)
			)
			(fill no)
			(layer "F.Fab")
		)
		(pad "1" smd rect
			(at 0 -0.9652)
			(size 1.397 1.143)
			(layers "F.Cu" "F.Mask" "F.Paste")
			(net "NCT7904_3VDD")
		)
		(pad "2" smd rect
			(at 0 0.9652)
			(size 1.397 1.143)
			(layers "F.Cu" "F.Mask" "F.Paste")
			(net "GND")
		)
	)
	(footprint ""
		(layer "F.Cu")
		(at 35.59429 -150.680166 180)
		(property "Reference" "TP11"
			(at 0 0 180)
			(layer "F.SilkS")
			(hide yes)
			(effects
				(font
					(size 1.27 1.27)
				)
			)
		)
		(property "Value" "TPAD32-GP"
			(at 0 -3.166364 180)
			(unlocked yes)
			(layer "F.Fab")
			(hide yes)
			(effects
				(font
					(size 1.016 1.016)
					(thickness 0.1524)
				)
			)
		)
		(property "Device Type" "TPAD32"
			(at 0 -4.690618 180)
			(unlocked yes)
			(layer "F.Fab")
			(hide yes)
			(effects
				(font
					(size 1.016 1.016)
					(thickness 0.1524)
				)
			)
		)
		(duplicate_pad_numbers_are_jumpers no)
		(fp_poly
			(pts
				(arc
					(start 0.7112 0)
					(mid -0.7112 0)
					(end 0.7112 0)
				)
			)
			(stroke
				(width 0)
				(type default)
			)
			(fill no)
			(layer "F.CrtYd")
		)
		(fp_poly
			(pts
				(arc
					(start 0.7112 0)
					(mid -0.7112 0)
					(end 0.7112 0)
				)
			)
			(stroke
				(width 0)
				(type default)
			)
			(fill no)
			(layer "F.Fab")
		)
		(pad "1" smd circle
			(at 0 0 180)
			(size 0.8128 0.8128)
			(layers "F.Cu" "F.Mask" "F.Paste")
			(net "NCT7904_VSEN12")
		)
	)
	(footprint ""
		(layer "F.Cu")
		(at 30.6832 -149.073616)
		(property "Reference" "R35"
			(at 0 0 0)
			(layer "F.SilkS")
			(hide yes)
			(effects
				(font
					(size 1.27 1.27)
				)
			)
		)
		(property "Value" "10KR2F-2-GP"
			(at 0.064008 -3.993896 0)
			(unlocked yes)
			(layer "F.Fab")
			(hide yes)
			(effects
				(font
					(size 1.016 1.016)
					(thickness 0.1524)
				)
			)
		)
		(property "Device Type" "R402H16"
			(at 0.064008 -5.517896 0)
			(unlocked yes)
			(layer "F.Fab")
			(hide yes)
			(effects
				(font
					(size 1.016 1.016)
					(thickness 0.1524)
				)
			)
		)
		(duplicate_pad_numbers_are_jumpers no)
		(fp_line
			(start -0.508 -0.9398)
			(end -0.508 0.9398)
			(stroke
				(width 0.1524)
				(type default)
			)
			(layer "F.SilkS")
		)
		(fp_line
			(start 0.508 -0.9398)
			(end -0.508 -0.9398)
			(stroke
				(width 0.1524)
				(type default)
			)
			(layer "F.SilkS")
		)
		(fp_rect
			(start -0.508 0.9398)
			(end 0.508 -0.9398)
			(stroke
				(width 0)
				(type default)
			)
			(fill no)
			(layer "F.CrtYd")
		)
		(fp_rect
			(start -0.508 0.9398)
			(end 0.508 -0.9398)
			(stroke
				(width 0)
				(type default)
			)
			(fill no)
			(layer "F.Fab")
		)
		(pad "1" smd custom
			(at 0 -0.4445)
			(size 0.1397 0.1397)
			(layers "F.Cu" "F.Mask" "F.Paste")
			(net "NCT7904_VSEN6")
			(options
				(clearance outline)
				(anchor circle)
			)
			(primitives
				(gr_poly
					(pts
						(arc
							(start -0.1778 -0.2794)
							(mid -0.249642 -0.249642)
							(end -0.2794 -0.1778)
						)
						(arc
							(start -0.2794 0.1778)
							(mid -0.249642 0.249642)
							(end -0.1778 0.2794)
						)
						(arc
							(start 0.1778 0.2794)
							(mid 0.249642 0.249642)
							(end 0.2794 0.1778)
						)
						(arc
							(start 0.2794 -0.1778)
							(mid 0.249642 -0.249642)
							(end 0.1778 -0.2794)
						)
					)
					(width 0)
					(fill yes)
				)
			)
		)
		(pad "2" smd custom
			(at 0 0.4445)
			(size 0.1397 0.1397)
			(layers "F.Cu" "F.Mask" "F.Paste")
			(net "GND")
			(options
				(clearance outline)
				(anchor circle)
			)
			(primitives
				(gr_poly
					(pts
						(arc
							(start -0.1778 -0.2794)
							(mid -0.249642 -0.249642)
							(end -0.2794 -0.1778)
						)
						(arc
							(start -0.2794 0.1778)
							(mid -0.249642 0.249642)
							(end -0.1778 0.2794)
						)
						(arc
							(start 0.1778 0.2794)
							(mid 0.249642 0.249642)
							(end 0.2794 0.1778)
						)
						(arc
							(start 0.2794 -0.1778)
							(mid 0.249642 -0.249642)
							(end 0.1778 -0.2794)
						)
					)
					(width 0)
					(fill yes)
				)
			)
		)
	)
	(footprint ""
		(layer "F.Cu")
		(at 4.040124 -372.65991 -90)
		(property "Reference" "CN2"
			(at 0 0 270)
			(layer "F.SilkS")
			(hide yes)
			(effects
				(font
					(size 1.27 1.27)
				)
			)
		)
		(property "Value" "JWT-CON5-42-GP"
			(at -7.8105 2.9591 270)
			(unlocked yes)
			(layer "F.Fab")
			(hide yes)
			(effects
				(font
					(size 1.016 1.016)
					(thickness 0.1524)
				)
			)
		)
		(property "Device Type" "A2541WR0-1TX5PA-6T-0E"
			(at -7.8105 1.4351 270)
			(unlocked yes)
			(layer "F.Fab")
			(hide yes)
			(effects
				(font
					(size 1.016 1.016)
					(thickness 0.1524)
				)
			)
		)
		(duplicate_pad_numbers_are_jumpers no)
		(fp_line
			(start -6.604 10.287)
			(end 6.604 10.287)
			(stroke
				(width 0.1524)
				(type default)
			)
			(layer "F.SilkS")
		)
		(fp_line
			(start 6.604 10.287)
			(end 6.604 -0.9652)
			(stroke
				(width 0.1524)
				(type default)
			)
			(layer "F.SilkS")
		)
		(fp_line
			(start -6.604 -0.9652)
			(end -6.604 10.287)
			(stroke
				(width 0.1524)
				(type default)
			)
			(layer "F.SilkS")
		)
		(fp_line
			(start 6.604 -0.9652)
			(end -6.604 -0.9652)
			(stroke
				(width 0.1524)
				(type default)
			)
			(layer "F.SilkS")
		)
		(fp_line
			(start -6.731 -1.0922)
			(end -6.731 0.1778)
			(stroke
				(width 0.4064)
				(type default)
			)
			(layer "F.SilkS")
		)
		(fp_line
			(start -5.461 -1.0922)
			(end -6.731 -1.0922)
			(stroke
				(width 0.4064)
				(type default)
			)
			(layer "F.SilkS")
		)
		(fp_circle
			(center -5.08 0)
			(end -5.08 -1.0668)
			(stroke
				(width 0.3048)
				(type default)
			)
			(fill no)
			(layer "F.SilkS")
		)
		(fp_circle
			(center -2.54 0)
			(end -2.54 -1.0668)
			(stroke
				(width 0.3048)
				(type default)
			)
			(fill no)
			(layer "F.SilkS")
		)
		(fp_circle
			(center 0 0)
			(end 0 -1.0668)
			(stroke
				(width 0.3048)
				(type default)
			)
			(fill no)
			(layer "F.SilkS")
		)
		(fp_circle
			(center 2.54 0)
			(end 2.54 -1.0668)
			(stroke
				(width 0.3048)
				(type default)
			)
			(fill no)
			(layer "F.SilkS")
		)
		(fp_circle
			(center 5.08 0)
			(end 5.08 -1.0668)
			(stroke
				(width 0.3048)
				(type default)
			)
			(fill no)
			(layer "F.SilkS")
		)
		(fp_rect
			(start -6.35 10.033)
			(end 6.35 -0.3302)
			(stroke
				(width 0)
				(type default)
			)
			(fill no)
			(layer "F.CrtYd")
		)
		(fp_poly
			(pts
				(xy -6.35 -0.3302) (xy 6.858 -0.3302) (xy 6.858 -1.2192) (xy -6.858 -1.2192) (xy -6.858 10.541)
				(xy 6.858 10.541) (xy 6.858 -0.3175) (xy 6.35 -0.3175) (xy 6.35 10.033) (xy -6.35 10.033)
			)
			(stroke
				(width 0)
				(type default)
			)
			(fill no)
			(layer "F.CrtYd")
		)
		(fp_rect
			(start -6.858 10.541)
			(end 6.858 -1.2192)
			(stroke
				(width 0)
				(type default)
			)
			(fill no)
			(layer "F.Fab")
		)
		(pad "1" thru_hole circle
			(at -5.08 0 270)
			(size 1.4224 1.4224)
			(drill 1.016)
			(layers "*.Cu" "*.Mask")
			(remove_unused_layers no)
			(net "GND")
			(clearance 0.1524)
			(thermal_gap 0.1524)
		)
		(pad "2" thru_hole circle
			(at -2.54 0 270)
			(size 1.4224 1.4224)
			(drill 1.016)
			(layers "*.Cu" "*.Mask")
			(remove_unused_layers no)
			(net "P12V_FAN2")
			(clearance 0.1524)
			(thermal_gap 0.1524)
		)
		(pad "3" thru_hole circle
			(at 0 0 270)
			(size 1.4224 1.4224)
			(drill 1.016)
			(layers "*.Cu" "*.Mask")
			(remove_unused_layers no)
			(net "FAN_TACH4")
			(clearance 0.1524)
			(thermal_gap 0.1524)
		)
		(pad "4" thru_hole circle
			(at 2.54 0 270)
			(size 1.4224 1.4224)
			(drill 1.016)
			(layers "*.Cu" "*.Mask")
			(remove_unused_layers no)
			(net "PWM_OUT_FAN2_NET")
			(clearance 0.1524)
			(thermal_gap 0.1524)
		)
		(pad "5" thru_hole circle
			(at 5.08 0 270)
			(size 1.4224 1.4224)
			(drill 1.016)
			(layers "*.Cu" "*.Mask")
			(remove_unused_layers no)
			(net "FAN_TACH3")
			(clearance 0.1524)
			(thermal_gap 0.1524)
		)
	)
	(footprint ""
		(layer "F.Cu")
		(at 43.019726 -366.069626)
		(property "Reference" "PQ6"
			(at 0 0 0)
			(layer "F.SilkS")
			(hide yes)
			(effects
				(font
					(size 1.27 1.27)
				)
			)
		)
		(property "Value" "PMBS3904-1-GP"
			(at 0 -9.0932 0)
			(unlocked yes)
			(layer "F.Fab")
			(hide yes)
			(effects
				(font
					(size 1.016 1.016)
					(thickness 0.1524)
				)
			)
		)
		(property "Device Type" "SOT-23-10H44"
			(at 0 -10.6172 0)
			(unlocked yes)
			(layer "F.Fab")
			(hide yes)
			(effects
				(font
					(size 1.016 1.016)
					(thickness 0.1524)
				)
			)
		)
		(duplicate_pad_numbers_are_jumpers no)
		(fp_line
			(start -1.7526 1.8796)
			(end -1.7526 0.9906)
			(stroke
				(width 0.3302)
				(type default)
			)
			(layer "F.SilkS")
		)
		(fp_line
			(start -1.651 -1.778)
			(end -1.651 1.778)
			(stroke
				(width 0.1524)
				(type default)
			)
			(layer "F.SilkS")
		)
		(fp_line
			(start -1.651 1.778)
			(end 1.651 1.778)
			(stroke
				(width 0.1524)
				(type default)
			)
			(layer "F.SilkS")
		)
		(fp_line
			(start -1.279398 2.152142)
			(end -0.9906 1.86309)
			(stroke
				(width 0.0127)
				(type default)
			)
			(layer "F.SilkS")
		)
		(fp_line
			(start -1.279144 2.15265)
			(end -0.701294 2.15265)
			(stroke
				(width 0.0127)
				(type default)
			)
			(layer "F.SilkS")
		)
		(fp_line
			(start -1.260856 2.1336)
			(end -0.720344 2.1336)
			(stroke
				(width 0.0127)
				(type default)
			)
			(layer "F.SilkS")
		)
		(fp_line
			(start -1.251458 2.124202)
			(end -0.729996 2.124202)
			(stroke
				(width 0.0127)
				(type default)
			)
			(layer "F.SilkS")
		)
		(fp_line
			(start -1.241806 2.11455)
			(end -0.739394 2.11455)
			(stroke
				(width 0.0127)
				(type default)
			)
			(layer "F.SilkS")
		)
		(fp_line
			(start -1.232408 2.105152)
			(end -0.749046 2.105152)
			(stroke
				(width 0.0127)
				(type default)
			)
			(layer "F.SilkS")
		)
		(fp_line
			(start -1.222756 2.0955)
			(end -0.758444 2.0955)
			(stroke
				(width 0.0127)
				(type default)
			)
			(layer "F.SilkS")
		)
		(fp_line
			(start -1.213358 2.086102)
			(end -0.768096 2.086102)
			(stroke
				(width 0.0127)
				(type default)
			)
			(layer "F.SilkS")
		)
		(fp_line
			(start -1.203706 2.07645)
			(end -0.777494 2.07645)
			(stroke
				(width 0.0127)
				(type default)
			)
			(layer "F.SilkS")
		)
		(fp_line
			(start -1.194308 2.067052)
			(end -0.787146 2.067052)
			(stroke
				(width 0.0127)
				(type default)
			)
			(layer "F.SilkS")
		)
		(fp_line
			(start -1.184656 2.0574)
			(end -0.796544 2.0574)
			(stroke
				(width 0.0127)
				(type default)
			)
			(layer "F.SilkS")
		)
		(fp_line
			(start -1.175258 2.048002)
			(end -0.806196 2.048002)
			(stroke
				(width 0.0127)
				(type default)
			)
			(layer "F.SilkS")
		)
		(fp_line
			(start -1.165606 2.03835)
			(end -0.815594 2.03835)
			(stroke
				(width 0.0127)
				(type default)
			)
			(layer "F.SilkS")
		)
		(fp_line
			(start -1.156208 2.028952)
			(end -0.825246 2.028952)
			(stroke
				(width 0.0127)
				(type default)
			)
			(layer "F.SilkS")
		)
		(fp_line
			(start -1.146556 2.0193)
			(end -0.834644 2.0193)
			(stroke
				(width 0.0127)
				(type default)
			)
			(layer "F.SilkS")
		)
		(fp_line
			(start -1.137158 2.009902)
			(end -0.844296 2.009902)
			(stroke
				(width 0.0127)
				(type default)
			)
			(layer "F.SilkS")
		)
		(fp_line
			(start -1.127506 2.00025)
			(end -0.853694 2.00025)
			(stroke
				(width 0.0127)
				(type default)
			)
			(layer "F.SilkS")
		)
		(fp_line
			(start -1.118108 1.990852)
			(end -0.863346 1.990852)
			(stroke
				(width 0.0127)
				(type default)
			)
			(layer "F.SilkS")
		)
		(fp_line
			(start -1.108456 1.9812)
			(end -0.872744 1.9812)
			(stroke
				(width 0.0127)
				(type default)
			)
			(layer "F.SilkS")
		)
		(fp_line
			(start -1.099058 1.971802)
			(end -0.882396 1.971802)
			(stroke
				(width 0.0127)
				(type default)
			)
			(layer "F.SilkS")
		)
		(fp_line
			(start -1.089406 1.96215)
			(end -0.891794 1.96215)
			(stroke
				(width 0.0127)
				(type default)
			)
			(layer "F.SilkS")
		)
		(fp_line
			(start -1.080008 1.952752)
			(end -0.901446 1.952752)
			(stroke
				(width 0.0127)
				(type default)
			)
			(layer "F.SilkS")
		)
		(fp_line
			(start -1.070356 1.9431)
			(end -0.910844 1.9431)
			(stroke
				(width 0.0127)
				(type default)
			)
			(layer "F.SilkS")
		)
		(fp_line
			(start -1.060958 1.933702)
			(end -0.920496 1.933702)
			(stroke
				(width 0.0127)
				(type default)
			)
			(layer "F.SilkS")
		)
		(fp_line
			(start -1.051306 1.92405)
			(end -0.929894 1.92405)
			(stroke
				(width 0.0127)
				(type default)
			)
			(layer "F.SilkS")
		)
		(fp_line
			(start -1.041908 1.914652)
			(end -0.939546 1.914652)
			(stroke
				(width 0.0127)
				(type default)
			)
			(layer "F.SilkS")
		)
		(fp_line
			(start -1.032256 1.905)
			(end -0.948944 1.905)
			(stroke
				(width 0.0127)
				(type default)
			)
			(layer "F.SilkS")
		)
		(fp_line
			(start -1.022858 1.895602)
			(end -0.958596 1.895602)
			(stroke
				(width 0.0127)
				(type default)
			)
			(layer "F.SilkS")
		)
		(fp_line
			(start -1.013206 1.88595)
			(end -0.967994 1.88595)
			(stroke
				(width 0.0127)
				(type default)
			)
			(layer "F.SilkS")
		)
		(fp_line
			(start -1.003808 1.876552)
			(end -0.977646 1.876552)
			(stroke
				(width 0.0127)
				(type default)
			)
			(layer "F.SilkS")
		)
		(fp_line
			(start -0.994156 1.8669)
			(end -0.987044 1.8669)
			(stroke
				(width 0.0127)
				(type default)
			)
			(layer "F.SilkS")
		)
		(fp_line
			(start -0.9906 1.86309)
			(end -0.701294 2.15265)
			(stroke
				(width 0.0127)
				(type default)
			)
			(layer "F.SilkS")
		)
		(fp_line
			(start -0.719074 2.145538)
			(end -1.265936 2.14122)
			(stroke
				(width 0.0127)
				(type default)
			)
			(layer "F.SilkS")
		)
		(fp_line
			(start -0.71628 2.15265)
			(end -1.26492 2.15265)
			(stroke
				(width 0.0127)
				(type default)
			)
			(layer "F.SilkS")
		)
		(fp_line
			(start -0.635 1.8796)
			(end -1.7526 1.8796)
			(stroke
				(width 0.3302)
				(type default)
			)
			(layer "F.SilkS")
		)
		(fp_line
			(start 1.651 -1.778)
			(end -1.651 -1.778)
			(stroke
				(width 0.1524)
				(type default)
			)
			(layer "F.SilkS")
		)
		(fp_line
			(start 1.651 1.778)
			(end 1.651 -1.778)
			(stroke
				(width 0.1524)
				(type default)
			)
			(layer "F.SilkS")
		)
		(fp_poly
			(pts
				(xy -1.285748 2.159) (xy -1.285748 1.8796) (xy -1.778 1.8796) (xy -1.778 -1.8796) (xy 1.778 -1.8796)
				(xy 1.778 1.8796) (xy -0.694944 1.8796) (xy -0.694944 2.159)
			)
			(stroke
				(width 0)
				(type default)
			)
			(fill no)
			(layer "F.CrtYd")
		)
		(fp_poly
			(pts
				(xy -1.285748 2.159) (xy -1.285748 1.8796) (xy -1.778 1.8796) (xy -1.778 -1.8796) (xy 1.778 -1.8796)
				(xy 1.778 1.8796) (xy -0.694944 1.8796) (xy -0.694944 2.159)
			)
			(stroke
				(width 0)
				(type default)
			)
			(fill no)
			(layer "F.Fab")
		)
		(pad "1" smd rect
			(at -0.98425 0.9525)
			(size 0.762 1.143)
			(layers "F.Cu" "F.Mask" "F.Paste")
			(net "ADM1276_LATCH#")
		)
		(pad "2" smd rect
			(at 0.98425 0.9525)
			(size 0.762 1.143)
			(layers "F.Cu" "F.Mask" "F.Paste")
			(net "GND")
		)
		(pad "3" smd rect
			(at 0 -0.9525)
			(size 0.762 1.143)
			(layers "F.Cu" "F.Mask" "F.Paste")
			(net "TEMP_ALM#_REVERSE")
		)
	)
	(footprint ""
		(layer "F.Cu")
		(at 8.2296 -450.6976 -90)
		(property "Reference" "R95"
			(at 0 0 270)
			(layer "F.SilkS")
			(hide yes)
			(effects
				(font
					(size 1.27 1.27)
				)
			)
		)
		(property "Value" "4K7R2F-GP"
			(at 0.064008 -3.993896 270)
			(unlocked yes)
			(layer "F.Fab")
			(hide yes)
			(effects
				(font
					(size 1.016 1.016)
					(thickness 0.1524)
				)
			)
		)
		(property "Device Type" "R402H16"
			(at 0.064008 -5.517896 270)
			(unlocked yes)
			(layer "F.Fab")
			(hide yes)
			(effects
				(font
					(size 1.016 1.016)
					(thickness 0.1524)
				)
			)
		)
		(duplicate_pad_numbers_are_jumpers no)
		(fp_line
			(start -0.508 -0.9398)
			(end -0.508 0.9398)
			(stroke
				(width 0.1524)
				(type default)
			)
			(layer "F.SilkS")
		)
		(fp_line
			(start 0.508 -0.9398)
			(end -0.508 -0.9398)
			(stroke
				(width 0.1524)
				(type default)
			)
			(layer "F.SilkS")
		)
		(fp_rect
			(start -0.508 0.9398)
			(end 0.508 -0.9398)
			(stroke
				(width 0)
				(type default)
			)
			(fill no)
			(layer "F.CrtYd")
		)
		(fp_rect
			(start -0.508 0.9398)
			(end 0.508 -0.9398)
			(stroke
				(width 0)
				(type default)
			)
			(fill no)
			(layer "F.Fab")
		)
		(pad "1" smd custom
			(at 0 -0.4445 270)
			(size 0.1397 0.1397)
			(layers "F.Cu" "F.Mask" "F.Paste")
			(net "P12V")
			(options
				(clearance outline)
				(anchor circle)
			)
			(primitives
				(gr_poly
					(pts
						(arc
							(start -0.1778 -0.2794)
							(mid -0.249642 -0.249642)
							(end -0.2794 -0.1778)
						)
						(arc
							(start -0.2794 0.1778)
							(mid -0.249642 0.249642)
							(end -0.1778 0.2794)
						)
						(arc
							(start 0.1778 0.2794)
							(mid 0.249642 0.249642)
							(end 0.2794 0.1778)
						)
						(arc
							(start 0.2794 -0.1778)
							(mid 0.249642 -0.249642)
							(end 0.1778 -0.2794)
						)
					)
					(width 0)
					(fill yes)
				)
			)
		)
		(pad "2" smd custom
			(at 0 0.4445 270)
			(size 0.1397 0.1397)
			(layers "F.Cu" "F.Mask" "F.Paste")
			(net "FAN_TACH1")
			(options
				(clearance outline)
				(anchor circle)
			)
			(primitives
				(gr_poly
					(pts
						(arc
							(start -0.1778 -0.2794)
							(mid -0.249642 -0.249642)
							(end -0.2794 -0.1778)
						)
						(arc
							(start -0.2794 0.1778)
							(mid -0.249642 0.249642)
							(end -0.1778 0.2794)
						)
						(arc
							(start 0.1778 0.2794)
							(mid 0.249642 0.249642)
							(end 0.2794 0.1778)
						)
						(arc
							(start 0.2794 -0.1778)
							(mid 0.249642 -0.249642)
							(end 0.1778 -0.2794)
						)
					)
					(width 0)
					(fill yes)
				)
			)
		)
	)
	(footprint ""
		(layer "F.Cu")
		(at 22.5044 -136.6012 90)
		(property "Reference" "PC87"
			(at 0 0 90)
			(layer "F.SilkS")
			(hide yes)
			(effects
				(font
					(size 1.27 1.27)
				)
			)
		)
		(property "Value" "SC220P50V2KX-3GP"
			(at 1.1811 -2.7051 90)
			(unlocked yes)
			(layer "F.Fab")
			(hide yes)
			(effects
				(font
					(size 1.016 1.016)
					(thickness 0.1524)
				)
			)
		)
		(property "Device Type" "C402H22"
			(at 1.1811 -4.2291 90)
			(unlocked yes)
			(layer "F.Fab")
			(hide yes)
			(effects
				(font
					(size 1.016 1.016)
					(thickness 0.1524)
				)
			)
		)
		(duplicate_pad_numbers_are_jumpers no)
		(fp_rect
			(start -0.4318 0.9525)
			(end 0.4318 -0.9525)
			(stroke
				(width 0)
				(type default)
			)
			(fill no)
			(layer "F.CrtYd")
		)
		(fp_rect
			(start -0.4318 0.9525)
			(end 0.4318 -0.9525)
			(stroke
				(width 0)
				(type default)
			)
			(fill no)
			(layer "F.Fab")
		)
		(pad "1" smd custom
			(at 0 -0.4445 90)
			(size 0.1524 0.1524)
			(layers "F.Cu" "F.Mask" "F.Paste")
			(net "P12VU_2490_SENSE")
			(options
				(clearance outline)
				(anchor circle)
			)
			(primitives
				(gr_poly
					(pts
						(arc
							(start 0.3048 -0.2032)
							(mid 0.275042 -0.275042)
							(end 0.2032 -0.3048)
						)
						(arc
							(start -0.2032 -0.3048)
							(mid -0.275042 -0.275042)
							(end -0.3048 -0.2032)
						)
						(arc
							(start -0.3048 0.2032)
							(mid -0.275042 0.275042)
							(end -0.2032 0.3048)
						)
						(arc
							(start 0.2032 0.3048)
							(mid 0.275042 0.275042)
							(end 0.3048 0.2032)
						)
					)
					(width 0)
					(fill yes)
				)
			)
		)
		(pad "2" smd custom
			(at 0 0.4445 90)
			(size 0.1524 0.1524)
			(layers "F.Cu" "F.Mask" "F.Paste")
			(net "P12VU_2490_VCC")
			(options
				(clearance outline)
				(anchor circle)
			)
			(primitives
				(gr_poly
					(pts
						(arc
							(start 0.3048 -0.2032)
							(mid 0.275042 -0.275042)
							(end 0.2032 -0.3048)
						)
						(arc
							(start -0.2032 -0.3048)
							(mid -0.275042 -0.275042)
							(end -0.3048 -0.2032)
						)
						(arc
							(start -0.3048 0.2032)
							(mid -0.275042 0.275042)
							(end -0.2032 0.3048)
						)
						(arc
							(start 0.2032 0.3048)
							(mid 0.275042 0.275042)
							(end 0.3048 0.2032)
						)
					)
					(width 0)
					(fill yes)
				)
			)
		)
	)
	(footprint ""
		(layer "F.Cu")
		(at 41.0464 -138.5824 90)
		(property "Reference" "PR101"
			(at 0 0 90)
			(layer "F.SilkS")
			(hide yes)
			(effects
				(font
					(size 1.27 1.27)
				)
			)
		)
		(property "Value" "100R2F-L1-GP-U"
			(at 0.064008 -3.993896 90)
			(unlocked yes)
			(layer "F.Fab")
			(hide yes)
			(effects
				(font
					(size 1.016 1.016)
					(thickness 0.1524)
				)
			)
		)
		(property "Device Type" "R402H14"
			(at 0.064008 -5.517896 90)
			(unlocked yes)
			(layer "F.Fab")
			(hide yes)
			(effects
				(font
					(size 1.016 1.016)
					(thickness 0.1524)
				)
			)
		)
		(duplicate_pad_numbers_are_jumpers no)
		(fp_line
			(start 0.508 -0.9398)
			(end -0.508 -0.9398)
			(stroke
				(width 0.1524)
				(type default)
			)
			(layer "F.SilkS")
		)
		(fp_line
			(start -0.508 -0.9398)
			(end -0.508 0.9398)
			(stroke
				(width 0.1524)
				(type default)
			)
			(layer "F.SilkS")
		)
		(fp_rect
			(start -0.508 0.9398)
			(end 0.508 -0.9398)
			(stroke
				(width 0)
				(type default)
			)
			(fill no)
			(layer "F.CrtYd")
		)
		(fp_rect
			(start -0.508 0.9398)
			(end 0.508 -0.9398)
			(stroke
				(width 0)
				(type default)
			)
			(fill no)
			(layer "F.Fab")
		)
		(pad "1" smd custom
			(at 0 -0.4445 90)
			(size 0.1397 0.1397)
			(layers "F.Cu" "F.Mask" "F.Paste")
			(net "P12VL_2490_GATE")
			(options
				(clearance outline)
				(anchor circle)
			)
			(primitives
				(gr_poly
					(pts
						(arc
							(start -0.1778 -0.2794)
							(mid -0.249642 -0.249642)
							(end -0.2794 -0.1778)
						)
						(arc
							(start -0.2794 0.1778)
							(mid -0.249642 0.249642)
							(end -0.1778 0.2794)
						)
						(arc
							(start 0.1778 0.2794)
							(mid 0.249642 0.249642)
							(end 0.2794 0.1778)
						)
						(arc
							(start 0.2794 -0.1778)
							(mid 0.249642 -0.249642)
							(end 0.1778 -0.2794)
						)
					)
					(width 0)
					(fill yes)
				)
			)
		)
		(pad "2" smd custom
			(at 0 0.4445 90)
			(size 0.1397 0.1397)
			(layers "F.Cu" "F.Mask" "F.Paste")
			(net "P12VL_2490_RC")
			(options
				(clearance outline)
				(anchor circle)
			)
			(primitives
				(gr_poly
					(pts
						(arc
							(start -0.1778 -0.2794)
							(mid -0.249642 -0.249642)
							(end -0.2794 -0.1778)
						)
						(arc
							(start -0.2794 0.1778)
							(mid -0.249642 0.249642)
							(end -0.1778 0.2794)
						)
						(arc
							(start 0.1778 0.2794)
							(mid 0.249642 0.249642)
							(end 0.2794 0.1778)
						)
						(arc
							(start 0.2794 -0.1778)
							(mid 0.249642 -0.249642)
							(end 0.1778 -0.2794)
						)
					)
					(width 0)
					(fill yes)
				)
			)
		)
	)
	(footprint ""
		(layer "F.Cu")
		(at 22.86 -122.555)
		(property "Reference" "PR61"
			(at 0 0 0)
			(layer "F.SilkS")
			(hide yes)
			(effects
				(font
					(size 1.27 1.27)
				)
			)
		)
		(property "Value" "D002R2512F-GP"
			(at -3.228594 -1.194054 0)
			(unlocked yes)
			(layer "F.Fab")
			(hide yes)
			(effects
				(font
					(size 1.016 1.016)
					(thickness 0.1524)
				)
			)
		)
		(property "Device Type" "R2512-2H32"
			(at -3.228594 -2.718054 0)
			(unlocked yes)
			(layer "F.Fab")
			(hide yes)
			(effects
				(font
					(size 1.016 1.016)
					(thickness 0.1524)
				)
			)
		)
		(duplicate_pad_numbers_are_jumpers no)
		(fp_line
			(start -1.9685 -3.81)
			(end 1.9685 -3.81)
			(stroke
				(width 0.1524)
				(type default)
			)
			(layer "F.SilkS")
		)
		(fp_line
			(start -1.9685 3.81)
			(end -1.9685 -3.81)
			(stroke
				(width 0.1524)
				(type default)
			)
			(layer "F.SilkS")
		)
		(fp_line
			(start 1.9685 -3.81)
			(end 1.9685 3.81)
			(stroke
				(width 0.1524)
				(type default)
			)
			(layer "F.SilkS")
		)
		(fp_line
			(start 1.9685 3.81)
			(end -1.9685 3.81)
			(stroke
				(width 0.1524)
				(type default)
			)
			(layer "F.SilkS")
		)
		(fp_rect
			(start -1.5875 3.175)
			(end 1.5875 -3.175)
			(stroke
				(width 0)
				(type default)
			)
			(fill no)
			(layer "F.CrtYd")
		)
		(fp_poly
			(pts
				(xy -2.2225 3.8862) (xy -2.2225 0.00254) (xy -1.5875 0.00254) (xy -1.5875 3.175) (xy 1.5875 3.175)
				(xy 1.5875 -3.175) (xy -1.5875 -3.175) (xy -1.5875 -0.00254) (xy -2.2225 -0.00254) (xy -2.2225 -3.8862)
				(xy 2.2225 -3.8862) (xy 2.2225 3.8862)
			)
			(stroke
				(width 0)
				(type default)
			)
			(fill no)
			(layer "F.CrtYd")
		)
		(fp_rect
			(start -2.2225 3.8862)
			(end 2.2225 -3.8862)
			(stroke
				(width 0)
				(type default)
			)
			(fill no)
			(layer "F.Fab")
		)
		(pad "1" smd rect
			(at 0 -2.273808)
			(size 3.429 2.5654)
			(layers "F.Cu" "F.Mask" "F.Paste")
			(net "P12V")
		)
		(pad "2" smd rect
			(at 0 2.273808)
			(size 3.429 2.5654)
			(layers "F.Cu" "F.Mask" "F.Paste")
			(net "P12VU_NET")
		)
	)
	(footprint ""
		(layer "F.Cu")
		(at 44.831 -111.633)
		(property "Reference" "PQ12"
			(at 0 0 0)
			(layer "F.SilkS")
			(hide yes)
			(effects
				(font
					(size 1.27 1.27)
				)
			)
		)
		(property "Value" "PH0925CL-GP"
			(at -4.2799 -0.4572 0)
			(unlocked yes)
			(layer "F.Fab")
			(hide yes)
			(effects
				(font
					(size 1.016 1.016)
					(thickness 0.1524)
				)
			)
		)
		(property "Device Type" "LFPAK-5PH48-U"
			(at -4.2799 -1.9812 0)
			(unlocked yes)
			(layer "F.Fab")
			(hide yes)
			(effects
				(font
					(size 1.016 1.016)
					(thickness 0.1524)
				)
			)
		)
		(duplicate_pad_numbers_are_jumpers no)
		(fp_line
			(start -2.7559 -6.5532)
			(end -2.7559 1.0668)
			(stroke
				(width 0.1524)
				(type default)
			)
			(layer "F.SilkS")
		)
		(fp_line
			(start -2.7559 1.0668)
			(end 2.7559 1.0668)
			(stroke
				(width 0.1524)
				(type default)
			)
			(layer "F.SilkS")
		)
		(fp_line
			(start -1.7272 1.1684)
			(end -2.1082 1.1684)
			(stroke
				(width 0.3302)
				(type default)
			)
			(layer "F.SilkS")
		)
		(fp_line
			(start 2.7559 -6.5532)
			(end -2.7559 -6.5532)
			(stroke
				(width 0.1524)
				(type default)
			)
			(layer "F.SilkS")
		)
		(fp_line
			(start 2.7559 1.0668)
			(end 2.7559 -6.5532)
			(stroke
				(width 0.1524)
				(type default)
			)
			(layer "F.SilkS")
		)
		(fp_poly
			(pts
				(xy -2.3368 1.5748) (xy -1.905 1.143) (xy -1.4732 1.5748)
			)
			(stroke
				(width 0)
				(type default)
			)
			(fill yes)
			(layer "F.SilkS")
		)
		(fp_poly
			(pts
				(xy -2.5019 -4.02971) (xy -0.3302 -4.02971) (xy -0.3302 -6.30301) (xy -2.5019 -6.30301)
			)
			(stroke
				(width 0)
				(type default)
			)
			(fill yes)
			(layer "F.Paste")
		)
		(fp_poly
			(pts
				(xy -2.5019 -1.09601) (xy -0.3302 -1.09601) (xy -0.3302 -3.36931) (xy -2.5019 -3.36931)
			)
			(stroke
				(width 0)
				(type default)
			)
			(fill yes)
			(layer "F.Paste")
		)
		(fp_poly
			(pts
				(xy 0.3302 -4.02971) (xy 2.5019 -4.02971) (xy 2.5019 -6.30301) (xy 0.3302 -6.30301)
			)
			(stroke
				(width 0)
				(type default)
			)
			(fill yes)
			(layer "F.Paste")
		)
		(fp_poly
			(pts
				(xy 0.3302 -1.09601) (xy 2.5019 -1.09601) (xy 2.5019 -3.36931) (xy 0.3302 -3.36931)
			)
			(stroke
				(width 0)
				(type default)
			)
			(fill yes)
			(layer "F.Paste")
		)
		(fp_rect
			(start -2.4511 0.3048)
			(end 2.4511 -5.6896)
			(stroke
				(width 0)
				(type default)
			)
			(fill no)
			(layer "F.CrtYd")
		)
		(fp_poly
			(pts
				(xy -3.0099 1.3208) (xy -3.0099 -6.8072) (xy 3.0099 -6.8072) (xy 3.0099 -1.016) (xy 2.4511 -1.016)
				(xy 2.4511 -5.6896) (xy -2.4511 -5.6896) (xy -2.4511 0.3048) (xy 2.4511 0.3048) (xy 2.4511 -1.0033)
				(xy 3.0099 -1.0033) (xy 3.0099 1.3208)
			)
			(stroke
				(width 0)
				(type default)
			)
			(fill no)
			(layer "F.CrtYd")
		)
		(fp_rect
			(start -3.0099 1.3208)
			(end 3.0099 -6.8072)
			(stroke
				(width 0)
				(type default)
			)
			(fill no)
			(layer "F.Fab")
		)
		(pad "1" smd rect
			(at -1.905 0)
			(size 0.762 1.6256)
			(layers "F.Cu" "F.Mask" "F.Paste")
			(net "P12VL")
		)
		(pad "2" smd rect
			(at -0.635 0)
			(size 0.762 1.6256)
			(layers "F.Cu" "F.Mask" "F.Paste")
			(net "P12VL")
		)
		(pad "3" smd rect
			(at 0.635 0)
			(size 0.762 1.6256)
			(layers "F.Cu" "F.Mask" "F.Paste")
			(net "P12VL")
		)
		(pad "4" smd rect
			(at 1.905 0)
			(size 0.762 1.6256)
			(layers "F.Cu" "F.Mask" "F.Paste")
			(net "P12VL_2490_GATE_DRV_2")
		)
		(pad "5" smd rect
			(at 0 -3.69951)
			(size 5.0038 5.207)
			(layers "F.Cu" "F.Mask" "F.Paste")
			(net "P12VL_NET")
		)
	)
	(footprint ""
		(layer "F.Cu")
		(at 20.385024 -175.37811 90)
		(property "Reference" "R23"
			(at 0 0 90)
			(layer "F.SilkS")
			(hide yes)
			(effects
				(font
					(size 1.27 1.27)
				)
			)
		)
		(property "Value" "4K7R2F-GP"
			(at 0.064008 -3.993896 90)
			(unlocked yes)
			(layer "F.Fab")
			(hide yes)
			(effects
				(font
					(size 1.016 1.016)
					(thickness 0.1524)
				)
			)
		)
		(property "Device Type" "R402H16"
			(at 0.064008 -5.517896 90)
			(unlocked yes)
			(layer "F.Fab")
			(hide yes)
			(effects
				(font
					(size 1.016 1.016)
					(thickness 0.1524)
				)
			)
		)
		(duplicate_pad_numbers_are_jumpers no)
		(fp_line
			(start 0.508 -0.9398)
			(end -0.508 -0.9398)
			(stroke
				(width 0.1524)
				(type default)
			)
			(layer "F.SilkS")
		)
		(fp_line
			(start -0.508 -0.9398)
			(end -0.508 0.9398)
			(stroke
				(width 0.1524)
				(type default)
			)
			(layer "F.SilkS")
		)
		(fp_rect
			(start -0.508 0.9398)
			(end 0.508 -0.9398)
			(stroke
				(width 0)
				(type default)
			)
			(fill no)
			(layer "F.CrtYd")
		)
		(fp_rect
			(start -0.508 0.9398)
			(end 0.508 -0.9398)
			(stroke
				(width 0)
				(type default)
			)
			(fill no)
			(layer "F.Fab")
		)
		(pad "1" smd custom
			(at 0 -0.4445 90)
			(size 0.1397 0.1397)
			(layers "F.Cu" "F.Mask" "F.Paste")
			(net "P3V3")
			(options
				(clearance outline)
				(anchor circle)
			)
			(primitives
				(gr_poly
					(pts
						(arc
							(start -0.1778 -0.2794)
							(mid -0.249642 -0.249642)
							(end -0.2794 -0.1778)
						)
						(arc
							(start -0.2794 0.1778)
							(mid -0.249642 0.249642)
							(end -0.1778 0.2794)
						)
						(arc
							(start 0.1778 0.2794)
							(mid 0.249642 0.249642)
							(end 0.2794 0.1778)
						)
						(arc
							(start 0.2794 -0.1778)
							(mid 0.249642 -0.249642)
							(end 0.1778 -0.2794)
						)
					)
					(width 0)
					(fill yes)
				)
			)
		)
		(pad "2" smd custom
			(at 0 0.4445 90)
			(size 0.1397 0.1397)
			(layers "F.Cu" "F.Mask" "F.Paste")
			(net "NCT7368S_SEL")
			(options
				(clearance outline)
				(anchor circle)
			)
			(primitives
				(gr_poly
					(pts
						(arc
							(start -0.1778 -0.2794)
							(mid -0.249642 -0.249642)
							(end -0.2794 -0.1778)
						)
						(arc
							(start -0.2794 0.1778)
							(mid -0.249642 0.249642)
							(end -0.1778 0.2794)
						)
						(arc
							(start 0.1778 0.2794)
							(mid 0.249642 0.249642)
							(end 0.2794 0.1778)
						)
						(arc
							(start 0.2794 -0.1778)
							(mid 0.249642 -0.249642)
							(end 0.1778 -0.2794)
						)
					)
					(width 0)
					(fill yes)
				)
			)
		)
	)
	(footprint ""
		(layer "F.Cu")
		(at 31.877 -22.479 90)
		(property "Reference" "TC13"
			(at 0 0 90)
			(layer "F.SilkS")
			(hide yes)
			(effects
				(font
					(size 1.27 1.27)
				)
			)
		)
		(property "Value" "ST15U25VDM-1-GP"
			(at 0 -9.6012 90)
			(unlocked yes)
			(layer "F.Fab")
			(hide yes)
			(effects
				(font
					(size 1.016 1.016)
					(thickness 0.1524)
				)
			)
		)
		(property "Device Type" "CT7343H79"
			(at 0 -11.1252 90)
			(unlocked yes)
			(layer "F.Fab")
			(hide yes)
			(effects
				(font
					(size 1.016 1.016)
					(thickness 0.1524)
				)
			)
		)
		(duplicate_pad_numbers_are_jumpers no)
		(fp_line
			(start 2.286 -4.8768)
			(end -2.286 -4.8768)
			(stroke
				(width 0.1524)
				(type default)
			)
			(layer "F.SilkS")
		)
		(fp_line
			(start -2.286 -4.8768)
			(end -2.286 -2.032)
			(stroke
				(width 0.1524)
				(type default)
			)
			(layer "F.SilkS")
		)
		(fp_line
			(start 2.1082 -4.699)
			(end -2.1082 -4.699)
			(stroke
				(width 0.508)
				(type default)
			)
			(layer "F.SilkS")
		)
		(fp_line
			(start 2.286 -2.032)
			(end 2.286 -4.8768)
			(stroke
				(width 0.1524)
				(type default)
			)
			(layer "F.SilkS")
		)
		(fp_line
			(start 2.286 2.032)
			(end 2.286 4.8768)
			(stroke
				(width 0.1524)
				(type default)
			)
			(layer "F.SilkS")
		)
		(fp_line
			(start 2.286 4.8768)
			(end -2.286 4.8768)
			(stroke
				(width 0.1524)
				(type default)
			)
			(layer "F.SilkS")
		)
		(fp_line
			(start -2.286 4.8768)
			(end -2.286 2.032)
			(stroke
				(width 0.1524)
				(type default)
			)
			(layer "F.SilkS")
		)
		(fp_rect
			(start -2.1463 3.6449)
			(end 2.1463 -3.6449)
			(stroke
				(width 0)
				(type default)
			)
			(fill no)
			(layer "F.CrtYd")
		)
		(fp_poly
			(pts
				(xy -2.54 4.953) (xy -2.54 4.2926) (xy -3.81 4.2926) (xy -3.81 -4.2926) (xy -2.54 -4.2926) (xy -2.54 -4.953)
				(xy 2.54 -4.953) (xy 2.54 -4.2926) (xy 3.81 -4.2926) (xy 3.81 -1.6256) (xy 2.1463 -1.6256) (xy 2.1463 -3.6449)
				(xy -2.1463 -3.6449) (xy -2.1463 3.6449) (xy 2.1463 3.6449) (xy 2.1463 -1.6129) (xy 3.81 -1.6129)
				(xy 3.81 4.2926) (xy 2.54 4.2926) (xy 2.54 4.953)
			)
			(stroke
				(width 0)
				(type default)
			)
			(fill no)
			(layer "F.CrtYd")
		)
		(fp_rect
			(start 2.54 4.2926)
			(end 3.81 -4.2926)
			(stroke
				(width 0)
				(type default)
			)
			(fill no)
			(layer "F.Fab")
		)
		(fp_rect
			(start -3.81 4.2926)
			(end -2.54 -4.2926)
			(stroke
				(width 0)
				(type default)
			)
			(fill no)
			(layer "F.Fab")
		)
		(fp_rect
			(start -2.54 4.953)
			(end 2.54 -4.953)
			(stroke
				(width 0)
				(type default)
			)
			(fill no)
			(layer "F.Fab")
		)
		(pad "1" smd rect
			(at 0 -3.1496 90)
			(size 2.413 2.286)
			(layers "F.Cu" "F.Mask" "F.Paste")
			(net "P12V")
		)
		(pad "2" smd rect
			(at 0 3.1496 90)
			(size 2.413 2.286)
			(layers "F.Cu" "F.Mask" "F.Paste")
			(net "GND")
		)
		(zone
			(layer "F.Cu")
			(hatch none 0.5)
			(connect_pads
				(clearance 0)
			)
			(min_thickness 0.25)
			(keepout
				(tracks allowed)
				(vias not_allowed)
				(pads allowed)
				(copperpour not_allowed)
				(footprints allowed)
			)
			(placement
				(enabled no)
				(sheetname "")
			)
			(fill
				(thermal_gap 0.5)
				(thermal_bridge_width 0.5)
				(island_removal_mode 0)
			)
			(polygon
				(pts
					(xy 30.1879 -23.9903) (xy 27.2796 -23.9903) (xy 27.2796 -20.9677) (xy 30.1752 -20.9677) (xy 30.5054 -20.9677)
					(xy 30.5054 -23.9903)
				)
			)
		)
		(zone
			(layer "F.Cu")
			(hatch none 0.5)
			(connect_pads
				(clearance 0)
			)
			(min_thickness 0.25)
			(keepout
				(tracks allowed)
				(vias not_allowed)
				(pads allowed)
				(copperpour not_allowed)
				(footprints allowed)
			)
			(placement
				(enabled no)
				(sheetname "")
			)
			(fill
				(thermal_gap 0.5)
				(thermal_bridge_width 0.5)
				(island_removal_mode 0)
			)
			(polygon
				(pts
					(xy 36.4744 -20.9677) (xy 36.4744 -23.9903) (xy 33.5788 -23.9903) (xy 33.2486 -23.9903) (xy 33.2486 -20.9677)
					(xy 33.5788 -20.9677)
				)
			)
		)
	)
	(footprint ""
		(layer "F.Cu")
		(at 13.923518 -230.153972 180)
		(property "Reference" "Q5"
			(at 0 0 180)
			(layer "F.SilkS")
			(hide yes)
			(effects
				(font
					(size 1.27 1.27)
				)
			)
		)
		(property "Value" "PMBS3904-1-GP"
			(at 0 -9.0932 180)
			(unlocked yes)
			(layer "F.Fab")
			(hide yes)
			(effects
				(font
					(size 1.016 1.016)
					(thickness 0.1524)
				)
			)
		)
		(property "Device Type" "SOT-23-10H44"
			(at 0 -10.6172 180)
			(unlocked yes)
			(layer "F.Fab")
			(hide yes)
			(effects
				(font
					(size 1.016 1.016)
					(thickness 0.1524)
				)
			)
		)
		(duplicate_pad_numbers_are_jumpers no)
		(fp_line
			(start 1.651 1.778)
			(end 1.651 -1.778)
			(stroke
				(width 0.1524)
				(type default)
			)
			(layer "F.SilkS")
		)
		(fp_line
			(start 1.651 -1.778)
			(end -1.651 -1.778)
			(stroke
				(width 0.1524)
				(type default)
			)
			(layer "F.SilkS")
		)
		(fp_line
			(start -0.635 1.8796)
			(end -1.7526 1.8796)
			(stroke
				(width 0.3302)
				(type default)
			)
			(layer "F.SilkS")
		)
		(fp_line
			(start -0.71628 2.15265)
			(end -1.26492 2.15265)
			(stroke
				(width 0.0127)
				(type default)
			)
			(layer "F.SilkS")
		)
		(fp_line
			(start -0.719074 2.145538)
			(end -1.265936 2.14122)
			(stroke
				(width 0.0127)
				(type default)
			)
			(layer "F.SilkS")
		)
		(fp_line
			(start -0.9906 1.86309)
			(end -0.701294 2.15265)
			(stroke
				(width 0.0127)
				(type default)
			)
			(layer "F.SilkS")
		)
		(fp_line
			(start -0.994156 1.8669)
			(end -0.987044 1.8669)
			(stroke
				(width 0.0127)
				(type default)
			)
			(layer "F.SilkS")
		)
		(fp_line
			(start -1.003808 1.876552)
			(end -0.977646 1.876552)
			(stroke
				(width 0.0127)
				(type default)
			)
			(layer "F.SilkS")
		)
		(fp_line
			(start -1.013206 1.88595)
			(end -0.967994 1.88595)
			(stroke
				(width 0.0127)
				(type default)
			)
			(layer "F.SilkS")
		)
		(fp_line
			(start -1.022858 1.895602)
			(end -0.958596 1.895602)
			(stroke
				(width 0.0127)
				(type default)
			)
			(layer "F.SilkS")
		)
		(fp_line
			(start -1.032256 1.905)
			(end -0.948944 1.905)
			(stroke
				(width 0.0127)
				(type default)
			)
			(layer "F.SilkS")
		)
		(fp_line
			(start -1.041908 1.914652)
			(end -0.939546 1.914652)
			(stroke
				(width 0.0127)
				(type default)
			)
			(layer "F.SilkS")
		)
		(fp_line
			(start -1.051306 1.92405)
			(end -0.929894 1.92405)
			(stroke
				(width 0.0127)
				(type default)
			)
			(layer "F.SilkS")
		)
		(fp_line
			(start -1.060958 1.933702)
			(end -0.920496 1.933702)
			(stroke
				(width 0.0127)
				(type default)
			)
			(layer "F.SilkS")
		)
		(fp_line
			(start -1.070356 1.9431)
			(end -0.910844 1.9431)
			(stroke
				(width 0.0127)
				(type default)
			)
			(layer "F.SilkS")
		)
		(fp_line
			(start -1.080008 1.952752)
			(end -0.901446 1.952752)
			(stroke
				(width 0.0127)
				(type default)
			)
			(layer "F.SilkS")
		)
		(fp_line
			(start -1.089406 1.96215)
			(end -0.891794 1.96215)
			(stroke
				(width 0.0127)
				(type default)
			)
			(layer "F.SilkS")
		)
		(fp_line
			(start -1.099058 1.971802)
			(end -0.882396 1.971802)
			(stroke
				(width 0.0127)
				(type default)
			)
			(layer "F.SilkS")
		)
		(fp_line
			(start -1.108456 1.9812)
			(end -0.872744 1.9812)
			(stroke
				(width 0.0127)
				(type default)
			)
			(layer "F.SilkS")
		)
		(fp_line
			(start -1.118108 1.990852)
			(end -0.863346 1.990852)
			(stroke
				(width 0.0127)
				(type default)
			)
			(layer "F.SilkS")
		)
		(fp_line
			(start -1.127506 2.00025)
			(end -0.853694 2.00025)
			(stroke
				(width 0.0127)
				(type default)
			)
			(layer "F.SilkS")
		)
		(fp_line
			(start -1.137158 2.009902)
			(end -0.844296 2.009902)
			(stroke
				(width 0.0127)
				(type default)
			)
			(layer "F.SilkS")
		)
		(fp_line
			(start -1.146556 2.0193)
			(end -0.834644 2.0193)
			(stroke
				(width 0.0127)
				(type default)
			)
			(layer "F.SilkS")
		)
		(fp_line
			(start -1.156208 2.028952)
			(end -0.825246 2.028952)
			(stroke
				(width 0.0127)
				(type default)
			)
			(layer "F.SilkS")
		)
		(fp_line
			(start -1.165606 2.03835)
			(end -0.815594 2.03835)
			(stroke
				(width 0.0127)
				(type default)
			)
			(layer "F.SilkS")
		)
		(fp_line
			(start -1.175258 2.048002)
			(end -0.806196 2.048002)
			(stroke
				(width 0.0127)
				(type default)
			)
			(layer "F.SilkS")
		)
		(fp_line
			(start -1.184656 2.0574)
			(end -0.796544 2.0574)
			(stroke
				(width 0.0127)
				(type default)
			)
			(layer "F.SilkS")
		)
		(fp_line
			(start -1.194308 2.067052)
			(end -0.787146 2.067052)
			(stroke
				(width 0.0127)
				(type default)
			)
			(layer "F.SilkS")
		)
		(fp_line
			(start -1.203706 2.07645)
			(end -0.777494 2.07645)
			(stroke
				(width 0.0127)
				(type default)
			)
			(layer "F.SilkS")
		)
		(fp_line
			(start -1.213358 2.086102)
			(end -0.768096 2.086102)
			(stroke
				(width 0.0127)
				(type default)
			)
			(layer "F.SilkS")
		)
		(fp_line
			(start -1.222756 2.0955)
			(end -0.758444 2.0955)
			(stroke
				(width 0.0127)
				(type default)
			)
			(layer "F.SilkS")
		)
		(fp_line
			(start -1.232408 2.105152)
			(end -0.749046 2.105152)
			(stroke
				(width 0.0127)
				(type default)
			)
			(layer "F.SilkS")
		)
		(fp_line
			(start -1.241806 2.11455)
			(end -0.739394 2.11455)
			(stroke
				(width 0.0127)
				(type default)
			)
			(layer "F.SilkS")
		)
		(fp_line
			(start -1.251458 2.124202)
			(end -0.729996 2.124202)
			(stroke
				(width 0.0127)
				(type default)
			)
			(layer "F.SilkS")
		)
		(fp_line
			(start -1.260856 2.1336)
			(end -0.720344 2.1336)
			(stroke
				(width 0.0127)
				(type default)
			)
			(layer "F.SilkS")
		)
		(fp_line
			(start -1.279144 2.15265)
			(end -0.701294 2.15265)
			(stroke
				(width 0.0127)
				(type default)
			)
			(layer "F.SilkS")
		)
		(fp_line
			(start -1.279398 2.152142)
			(end -0.9906 1.86309)
			(stroke
				(width 0.0127)
				(type default)
			)
			(layer "F.SilkS")
		)
		(fp_line
			(start -1.651 1.778)
			(end 1.651 1.778)
			(stroke
				(width 0.1524)
				(type default)
			)
			(layer "F.SilkS")
		)
		(fp_line
			(start -1.651 -1.778)
			(end -1.651 1.778)
			(stroke
				(width 0.1524)
				(type default)
			)
			(layer "F.SilkS")
		)
		(fp_line
			(start -1.7526 1.8796)
			(end -1.7526 0.9906)
			(stroke
				(width 0.3302)
				(type default)
			)
			(layer "F.SilkS")
		)
		(fp_poly
			(pts
				(xy -1.285748 2.159) (xy -1.285748 1.8796) (xy -1.778 1.8796) (xy -1.778 -1.8796) (xy 1.778 -1.8796)
				(xy 1.778 1.8796) (xy -0.694944 1.8796) (xy -0.694944 2.159)
			)
			(stroke
				(width 0)
				(type default)
			)
			(fill no)
			(layer "F.CrtYd")
		)
		(fp_poly
			(pts
				(xy -1.285748 2.159) (xy -1.285748 1.8796) (xy -1.778 1.8796) (xy -1.778 -1.8796) (xy 1.778 -1.8796)
				(xy 1.778 1.8796) (xy -0.694944 1.8796) (xy -0.694944 2.159)
			)
			(stroke
				(width 0)
				(type default)
			)
			(fill no)
			(layer "F.Fab")
		)
		(pad "1" smd rect
			(at -0.98425 0.9525 180)
			(size 0.762 1.143)
			(layers "F.Cu" "F.Mask" "F.Paste")
			(net "LED_DR_LED3_B")
		)
		(pad "2" smd rect
			(at 0.98425 0.9525 180)
			(size 0.762 1.143)
			(layers "F.Cu" "F.Mask" "F.Paste")
			(net "GND")
		)
		(pad "3" smd rect
			(at 0 -0.9525 180)
			(size 0.762 1.143)
			(layers "F.Cu" "F.Mask" "F.Paste")
			(net "LED_DR_LED3_BLUE")
		)
	)
	(footprint ""
		(layer "F.Cu")
		(at 17.2466 -400.2024)
		(property "Reference" "PQ13"
			(at 0 0 0)
			(layer "F.SilkS")
			(hide yes)
			(effects
				(font
					(size 1.27 1.27)
				)
			)
		)
		(property "Value" "PH0925CL-GP"
			(at -4.2799 -0.4572 0)
			(unlocked yes)
			(layer "F.Fab")
			(hide yes)
			(effects
				(font
					(size 1.016 1.016)
					(thickness 0.1524)
				)
			)
		)
		(property "Device Type" "LFPAK-5PH48-U"
			(at -4.2799 -1.9812 0)
			(unlocked yes)
			(layer "F.Fab")
			(hide yes)
			(effects
				(font
					(size 1.016 1.016)
					(thickness 0.1524)
				)
			)
		)
		(duplicate_pad_numbers_are_jumpers no)
		(fp_line
			(start -2.7559 -6.5532)
			(end -2.7559 1.0668)
			(stroke
				(width 0.1524)
				(type default)
			)
			(layer "F.SilkS")
		)
		(fp_line
			(start -2.7559 1.0668)
			(end 2.7559 1.0668)
			(stroke
				(width 0.1524)
				(type default)
			)
			(layer "F.SilkS")
		)
		(fp_line
			(start -1.7272 1.1684)
			(end -2.1082 1.1684)
			(stroke
				(width 0.3302)
				(type default)
			)
			(layer "F.SilkS")
		)
		(fp_line
			(start 2.7559 -6.5532)
			(end -2.7559 -6.5532)
			(stroke
				(width 0.1524)
				(type default)
			)
			(layer "F.SilkS")
		)
		(fp_line
			(start 2.7559 1.0668)
			(end 2.7559 -6.5532)
			(stroke
				(width 0.1524)
				(type default)
			)
			(layer "F.SilkS")
		)
		(fp_poly
			(pts
				(xy -2.3368 1.5748) (xy -1.905 1.143) (xy -1.4732 1.5748)
			)
			(stroke
				(width 0)
				(type default)
			)
			(fill yes)
			(layer "F.SilkS")
		)
		(fp_poly
			(pts
				(xy -2.5019 -4.02971) (xy -0.3302 -4.02971) (xy -0.3302 -6.30301) (xy -2.5019 -6.30301)
			)
			(stroke
				(width 0)
				(type default)
			)
			(fill yes)
			(layer "F.Paste")
		)
		(fp_poly
			(pts
				(xy -2.5019 -1.09601) (xy -0.3302 -1.09601) (xy -0.3302 -3.36931) (xy -2.5019 -3.36931)
			)
			(stroke
				(width 0)
				(type default)
			)
			(fill yes)
			(layer "F.Paste")
		)
		(fp_poly
			(pts
				(xy 0.3302 -4.02971) (xy 2.5019 -4.02971) (xy 2.5019 -6.30301) (xy 0.3302 -6.30301)
			)
			(stroke
				(width 0)
				(type default)
			)
			(fill yes)
			(layer "F.Paste")
		)
		(fp_poly
			(pts
				(xy 0.3302 -1.09601) (xy 2.5019 -1.09601) (xy 2.5019 -3.36931) (xy 0.3302 -3.36931)
			)
			(stroke
				(width 0)
				(type default)
			)
			(fill yes)
			(layer "F.Paste")
		)
		(fp_rect
			(start -2.4511 0.3048)
			(end 2.4511 -5.6896)
			(stroke
				(width 0)
				(type default)
			)
			(fill no)
			(layer "F.CrtYd")
		)
		(fp_poly
			(pts
				(xy -3.0099 1.3208) (xy -3.0099 -6.8072) (xy 3.0099 -6.8072) (xy 3.0099 -1.016) (xy 2.4511 -1.016)
				(xy 2.4511 -5.6896) (xy -2.4511 -5.6896) (xy -2.4511 0.3048) (xy 2.4511 0.3048) (xy 2.4511 -1.0033)
				(xy 3.0099 -1.0033) (xy 3.0099 1.3208)
			)
			(stroke
				(width 0)
				(type default)
			)
			(fill no)
			(layer "F.CrtYd")
		)
		(fp_rect
			(start -3.0099 1.3208)
			(end 3.0099 -6.8072)
			(stroke
				(width 0)
				(type default)
			)
			(fill no)
			(layer "F.Fab")
		)
		(pad "1" smd rect
			(at -1.905 0)
			(size 0.762 1.6256)
			(layers "F.Cu" "F.Mask" "F.Paste")
			(net "P12V")
		)
		(pad "2" smd rect
			(at -0.635 0)
			(size 0.762 1.6256)
			(layers "F.Cu" "F.Mask" "F.Paste")
			(net "P12V")
		)
		(pad "3" smd rect
			(at 0.635 0)
			(size 0.762 1.6256)
			(layers "F.Cu" "F.Mask" "F.Paste")
			(net "P12V")
		)
		(pad "4" smd rect
			(at 1.905 0)
			(size 0.762 1.6256)
			(layers "F.Cu" "F.Mask" "F.Paste")
			(net "ADM1276_GATE_DRV0")
		)
		(pad "5" smd rect
			(at 0 -3.69951)
			(size 5.0038 5.207)
			(layers "F.Cu" "F.Mask" "F.Paste")
			(net "P12V_SENSE_TRACE")
		)
	)
	(footprint ""
		(layer "F.Cu")
		(at 37.70249 -165.513766 180)
		(property "Reference" "R2"
			(at 0 0 180)
			(layer "F.SilkS")
			(hide yes)
			(effects
				(font
					(size 1.27 1.27)
				)
			)
		)
		(property "Value" "0R2J-2-GP"
			(at 0.064008 -3.993896 180)
			(unlocked yes)
			(layer "F.Fab")
			(hide yes)
			(effects
				(font
					(size 1.016 1.016)
					(thickness 0.1524)
				)
			)
		)
		(property "Device Type" "R402H16"
			(at 0.064008 -5.517896 180)
			(unlocked yes)
			(layer "F.Fab")
			(hide yes)
			(effects
				(font
					(size 1.016 1.016)
					(thickness 0.1524)
				)
			)
		)
		(duplicate_pad_numbers_are_jumpers no)
		(fp_line
			(start 0.508 -0.9398)
			(end -0.508 -0.9398)
			(stroke
				(width 0.1524)
				(type default)
			)
			(layer "F.SilkS")
		)
		(fp_line
			(start -0.508 -0.9398)
			(end -0.508 0.9398)
			(stroke
				(width 0.1524)
				(type default)
			)
			(layer "F.SilkS")
		)
		(fp_rect
			(start -0.508 0.9398)
			(end 0.508 -0.9398)
			(stroke
				(width 0)
				(type default)
			)
			(fill no)
			(layer "F.CrtYd")
		)
		(fp_rect
			(start -0.508 0.9398)
			(end 0.508 -0.9398)
			(stroke
				(width 0)
				(type default)
			)
			(fill no)
			(layer "F.Fab")
		)
		(pad "1" smd custom
			(at 0 -0.4445 180)
			(size 0.1397 0.1397)
			(layers "F.Cu" "F.Mask" "F.Paste")
			(net "I2C_C_SCL_NCT7904")
			(options
				(clearance outline)
				(anchor circle)
			)
			(primitives
				(gr_poly
					(pts
						(arc
							(start -0.1778 -0.2794)
							(mid -0.249642 -0.249642)
							(end -0.2794 -0.1778)
						)
						(arc
							(start -0.2794 0.1778)
							(mid -0.249642 0.249642)
							(end -0.1778 0.2794)
						)
						(arc
							(start 0.1778 0.2794)
							(mid 0.249642 0.249642)
							(end 0.2794 0.1778)
						)
						(arc
							(start 0.2794 -0.1778)
							(mid 0.249642 -0.249642)
							(end 0.1778 -0.2794)
						)
					)
					(width 0)
					(fill yes)
				)
			)
		)
		(pad "2" smd custom
			(at 0 0.4445 180)
			(size 0.1397 0.1397)
			(layers "F.Cu" "F.Mask" "F.Paste")
			(net "I2C_C_SCL")
			(options
				(clearance outline)
				(anchor circle)
			)
			(primitives
				(gr_poly
					(pts
						(arc
							(start -0.1778 -0.2794)
							(mid -0.249642 -0.249642)
							(end -0.2794 -0.1778)
						)
						(arc
							(start -0.2794 0.1778)
							(mid -0.249642 0.249642)
							(end -0.1778 0.2794)
						)
						(arc
							(start 0.1778 0.2794)
							(mid 0.249642 0.249642)
							(end 0.2794 0.1778)
						)
						(arc
							(start 0.2794 -0.1778)
							(mid 0.249642 -0.249642)
							(end 0.1778 -0.2794)
						)
					)
					(width 0)
					(fill yes)
				)
			)
		)
	)
	(footprint ""
		(layer "F.Cu")
		(at 30.904434 -238.266224 180)
		(property "Reference" "R41"
			(at 0 0 180)
			(layer "F.SilkS")
			(hide yes)
			(effects
				(font
					(size 1.27 1.27)
				)
			)
		)
		(property "Value" "4K7R2J-2-GP"
			(at 0.064008 -3.993896 180)
			(unlocked yes)
			(layer "F.Fab")
			(hide yes)
			(effects
				(font
					(size 1.016 1.016)
					(thickness 0.1524)
				)
			)
		)
		(property "Device Type" "R402H16"
			(at 0.064008 -5.517896 180)
			(unlocked yes)
			(layer "F.Fab")
			(hide yes)
			(effects
				(font
					(size 1.016 1.016)
					(thickness 0.1524)
				)
			)
		)
		(duplicate_pad_numbers_are_jumpers no)
		(fp_line
			(start 0.508 -0.9398)
			(end -0.508 -0.9398)
			(stroke
				(width 0.1524)
				(type default)
			)
			(layer "F.SilkS")
		)
		(fp_line
			(start -0.508 -0.9398)
			(end -0.508 0.9398)
			(stroke
				(width 0.1524)
				(type default)
			)
			(layer "F.SilkS")
		)
		(fp_rect
			(start -0.508 0.9398)
			(end 0.508 -0.9398)
			(stroke
				(width 0)
				(type default)
			)
			(fill no)
			(layer "F.CrtYd")
		)
		(fp_rect
			(start -0.508 0.9398)
			(end 0.508 -0.9398)
			(stroke
				(width 0)
				(type default)
			)
			(fill no)
			(layer "F.Fab")
		)
		(pad "1" smd custom
			(at 0 -0.4445 180)
			(size 0.1397 0.1397)
			(layers "F.Cu" "F.Mask" "F.Paste")
			(net "P3V3")
			(options
				(clearance outline)
				(anchor circle)
			)
			(primitives
				(gr_poly
					(pts
						(arc
							(start -0.1778 -0.2794)
							(mid -0.249642 -0.249642)
							(end -0.2794 -0.1778)
						)
						(arc
							(start -0.2794 0.1778)
							(mid -0.249642 0.249642)
							(end -0.1778 0.2794)
						)
						(arc
							(start 0.1778 0.2794)
							(mid 0.249642 0.249642)
							(end 0.2794 0.1778)
						)
						(arc
							(start 0.2794 -0.1778)
							(mid 0.249642 -0.249642)
							(end 0.1778 -0.2794)
						)
					)
					(width 0)
					(fill yes)
				)
			)
		)
		(pad "2" smd custom
			(at 0 0.4445 180)
			(size 0.1397 0.1397)
			(layers "F.Cu" "F.Mask" "F.Paste")
			(net "FCB_EEPROM_A2")
			(options
				(clearance outline)
				(anchor circle)
			)
			(primitives
				(gr_poly
					(pts
						(arc
							(start -0.1778 -0.2794)
							(mid -0.249642 -0.249642)
							(end -0.2794 -0.1778)
						)
						(arc
							(start -0.2794 0.1778)
							(mid -0.249642 0.249642)
							(end -0.1778 0.2794)
						)
						(arc
							(start 0.1778 0.2794)
							(mid 0.249642 0.249642)
							(end 0.2794 0.1778)
						)
						(arc
							(start 0.2794 -0.1778)
							(mid 0.249642 -0.249642)
							(end 0.1778 -0.2794)
						)
					)
					(width 0)
					(fill yes)
				)
			)
		)
	)
	(footprint ""
		(layer "F.Cu")
		(at 20.9296 -174.3456 90)
		(property "Reference" "R22"
			(at 0 0 90)
			(layer "F.SilkS")
			(hide yes)
			(effects
				(font
					(size 1.27 1.27)
				)
			)
		)
		(property "Value" "4K7R2F-GP"
			(at 0.064008 -3.993896 90)
			(unlocked yes)
			(layer "F.Fab")
			(hide yes)
			(effects
				(font
					(size 1.016 1.016)
					(thickness 0.1524)
				)
			)
		)
		(property "Device Type" "R402H16"
			(at 0.064008 -5.517896 90)
			(unlocked yes)
			(layer "F.Fab")
			(hide yes)
			(effects
				(font
					(size 1.016 1.016)
					(thickness 0.1524)
				)
			)
		)
		(duplicate_pad_numbers_are_jumpers no)
		(fp_line
			(start 0.508 -0.9398)
			(end -0.508 -0.9398)
			(stroke
				(width 0.1524)
				(type default)
			)
			(layer "F.SilkS")
		)
		(fp_line
			(start -0.508 -0.9398)
			(end -0.508 0.9398)
			(stroke
				(width 0.1524)
				(type default)
			)
			(layer "F.SilkS")
		)
		(fp_rect
			(start -0.508 0.9398)
			(end 0.508 -0.9398)
			(stroke
				(width 0)
				(type default)
			)
			(fill no)
			(layer "F.CrtYd")
		)
		(fp_rect
			(start -0.508 0.9398)
			(end 0.508 -0.9398)
			(stroke
				(width 0)
				(type default)
			)
			(fill no)
			(layer "F.Fab")
		)
		(pad "1" smd custom
			(at 0 -0.4445 90)
			(size 0.1397 0.1397)
			(layers "F.Cu" "F.Mask" "F.Paste")
			(net "P3V3")
			(options
				(clearance outline)
				(anchor circle)
			)
			(primitives
				(gr_poly
					(pts
						(arc
							(start -0.1778 -0.2794)
							(mid -0.249642 -0.249642)
							(end -0.2794 -0.1778)
						)
						(arc
							(start -0.2794 0.1778)
							(mid -0.249642 0.249642)
							(end -0.1778 0.2794)
						)
						(arc
							(start 0.1778 0.2794)
							(mid 0.249642 0.249642)
							(end 0.2794 0.1778)
						)
						(arc
							(start 0.2794 -0.1778)
							(mid 0.249642 -0.249642)
							(end 0.1778 -0.2794)
						)
					)
					(width 0)
					(fill yes)
				)
			)
		)
		(pad "2" smd custom
			(at 0 0.4445 90)
			(size 0.1397 0.1397)
			(layers "F.Cu" "F.Mask" "F.Paste")
			(net "THERMHOT#")
			(options
				(clearance outline)
				(anchor circle)
			)
			(primitives
				(gr_poly
					(pts
						(arc
							(start -0.1778 -0.2794)
							(mid -0.249642 -0.249642)
							(end -0.2794 -0.1778)
						)
						(arc
							(start -0.2794 0.1778)
							(mid -0.249642 0.249642)
							(end -0.1778 0.2794)
						)
						(arc
							(start 0.1778 0.2794)
							(mid 0.249642 0.249642)
							(end 0.2794 0.1778)
						)
						(arc
							(start 0.2794 -0.1778)
							(mid 0.249642 -0.249642)
							(end 0.1778 -0.2794)
						)
					)
					(width 0)
					(fill yes)
				)
			)
		)
	)
	(footprint ""
		(layer "F.Cu")
		(at 47.0154 -419.7858 90)
		(property "Reference" "C26"
			(at 0 0 90)
			(layer "F.SilkS")
			(hide yes)
			(effects
				(font
					(size 1.27 1.27)
				)
			)
		)
		(property "Value" "SC1U25V3KX-1-GP"
			(at 0 -2.8194 90)
			(unlocked yes)
			(layer "F.Fab")
			(hide yes)
			(effects
				(font
					(size 1.016 1.016)
					(thickness 0.1524)
				)
			)
		)
		(property "Device Type" "C603H36"
			(at 0 -4.3434 90)
			(unlocked yes)
			(layer "F.Fab")
			(hide yes)
			(effects
				(font
					(size 1.016 1.016)
					(thickness 0.1524)
				)
			)
		)
		(duplicate_pad_numbers_are_jumpers no)
		(fp_line
			(start 0.508 0)
			(end -0.508 0)
			(stroke
				(width 0.2032)
				(type default)
			)
			(layer "F.SilkS")
		)
		(fp_rect
			(start -0.5842 1.3335)
			(end 0.5842 -1.3335)
			(stroke
				(width 0)
				(type default)
			)
			(fill no)
			(layer "F.CrtYd")
		)
		(fp_rect
			(start -0.5842 1.3335)
			(end 0.5842 -1.3335)
			(stroke
				(width 0)
				(type default)
			)
			(fill no)
			(layer "F.Fab")
		)
		(pad "1" smd custom
			(at 0 -0.762 90)
			(size 0.2159 0.2159)
			(layers "F.Cu" "F.Mask" "F.Paste")
			(net "P12V_AUX")
			(options
				(clearance outline)
				(anchor circle)
			)
			(primitives
				(gr_poly
					(pts
						(arc
							(start -0.3302 -0.4318)
							(mid -0.402042 -0.402042)
							(end -0.4318 -0.3302)
						)
						(arc
							(start -0.4318 0.3302)
							(mid -0.402042 0.402042)
							(end -0.3302 0.4318)
						)
						(arc
							(start 0.3302 0.4318)
							(mid 0.402042 0.402042)
							(end 0.4318 0.3302)
						)
						(arc
							(start 0.4318 -0.3302)
							(mid 0.402042 -0.402042)
							(end 0.3302 -0.4318)
						)
					)
					(width 0)
					(fill yes)
				)
			)
		)
		(pad "2" smd custom
			(at 0 0.762 90)
			(size 0.2159 0.2159)
			(layers "F.Cu" "F.Mask" "F.Paste")
			(net "GND")
			(options
				(clearance outline)
				(anchor circle)
			)
			(primitives
				(gr_poly
					(pts
						(arc
							(start -0.3302 -0.4318)
							(mid -0.402042 -0.402042)
							(end -0.4318 -0.3302)
						)
						(arc
							(start -0.4318 0.3302)
							(mid -0.402042 0.402042)
							(end -0.3302 0.4318)
						)
						(arc
							(start 0.3302 0.4318)
							(mid 0.402042 0.402042)
							(end 0.4318 0.3302)
						)
						(arc
							(start 0.4318 -0.3302)
							(mid 0.402042 -0.402042)
							(end 0.3302 -0.4318)
						)
					)
					(width 0)
					(fill yes)
				)
			)
		)
	)
	(footprint ""
		(layer "F.Cu")
		(at 24.1808 -168.656)
		(property "Reference" "R20"
			(at 0 0 0)
			(layer "F.SilkS")
			(hide yes)
			(effects
				(font
					(size 1.27 1.27)
				)
			)
		)
		(property "Value" "4K7R2F-GP"
			(at 0.064008 -3.993896 0)
			(unlocked yes)
			(layer "F.Fab")
			(hide yes)
			(effects
				(font
					(size 1.016 1.016)
					(thickness 0.1524)
				)
			)
		)
		(property "Device Type" "R402H16"
			(at 0.064008 -5.517896 0)
			(unlocked yes)
			(layer "F.Fab")
			(hide yes)
			(effects
				(font
					(size 1.016 1.016)
					(thickness 0.1524)
				)
			)
		)
		(duplicate_pad_numbers_are_jumpers no)
		(fp_line
			(start -0.508 -0.9398)
			(end -0.508 0.9398)
			(stroke
				(width 0.1524)
				(type default)
			)
			(layer "F.SilkS")
		)
		(fp_line
			(start 0.508 -0.9398)
			(end -0.508 -0.9398)
			(stroke
				(width 0.1524)
				(type default)
			)
			(layer "F.SilkS")
		)
		(fp_rect
			(start -0.508 0.9398)
			(end 0.508 -0.9398)
			(stroke
				(width 0)
				(type default)
			)
			(fill no)
			(layer "F.CrtYd")
		)
		(fp_rect
			(start -0.508 0.9398)
			(end 0.508 -0.9398)
			(stroke
				(width 0)
				(type default)
			)
			(fill no)
			(layer "F.Fab")
		)
		(pad "1" smd custom
			(at 0 -0.4445)
			(size 0.1397 0.1397)
			(layers "F.Cu" "F.Mask" "F.Paste")
			(net "P3V3")
			(options
				(clearance outline)
				(anchor circle)
			)
			(primitives
				(gr_poly
					(pts
						(arc
							(start -0.1778 -0.2794)
							(mid -0.249642 -0.249642)
							(end -0.2794 -0.1778)
						)
						(arc
							(start -0.2794 0.1778)
							(mid -0.249642 0.249642)
							(end -0.1778 0.2794)
						)
						(arc
							(start 0.1778 0.2794)
							(mid 0.249642 0.249642)
							(end 0.2794 0.1778)
						)
						(arc
							(start 0.2794 -0.1778)
							(mid 0.249642 -0.249642)
							(end 0.1778 -0.2794)
						)
					)
					(width 0)
					(fill yes)
				)
			)
		)
		(pad "2" smd custom
			(at 0 0.4445)
			(size 0.1397 0.1397)
			(layers "F.Cu" "F.Mask" "F.Paste")
			(net "PWM_BUFFER_IN_FAN5_FAN6")
			(options
				(clearance outline)
				(anchor circle)
			)
			(primitives
				(gr_poly
					(pts
						(arc
							(start -0.1778 -0.2794)
							(mid -0.249642 -0.249642)
							(end -0.2794 -0.1778)
						)
						(arc
							(start -0.2794 0.1778)
							(mid -0.249642 0.249642)
							(end -0.1778 0.2794)
						)
						(arc
							(start 0.1778 0.2794)
							(mid 0.249642 0.249642)
							(end 0.2794 0.1778)
						)
						(arc
							(start 0.2794 -0.1778)
							(mid 0.249642 -0.249642)
							(end 0.1778 -0.2794)
						)
					)
					(width 0)
					(fill yes)
				)
			)
		)
	)
	(footprint ""
		(layer "F.Cu")
		(at 37.846508 -282.993338)
		(property "Reference" "C47"
			(at 0 0 0)
			(layer "F.SilkS")
			(hide yes)
			(effects
				(font
					(size 1.27 1.27)
				)
			)
		)
		(property "Value" "SCD1U50V3KX-GP"
			(at 0 -2.8194 0)
			(unlocked yes)
			(layer "F.Fab")
			(hide yes)
			(effects
				(font
					(size 1.016 1.016)
					(thickness 0.1524)
				)
			)
		)
		(property "Device Type" "C603H36"
			(at 0 -4.3434 0)
			(unlocked yes)
			(layer "F.Fab")
			(hide yes)
			(effects
				(font
					(size 1.016 1.016)
					(thickness 0.1524)
				)
			)
		)
		(duplicate_pad_numbers_are_jumpers no)
		(fp_line
			(start 0.508 0)
			(end -0.508 0)
			(stroke
				(width 0.2032)
				(type default)
			)
			(layer "F.SilkS")
		)
		(fp_rect
			(start -0.5842 1.3335)
			(end 0.5842 -1.3335)
			(stroke
				(width 0)
				(type default)
			)
			(fill no)
			(layer "F.CrtYd")
		)
		(fp_rect
			(start -0.5842 1.3335)
			(end 0.5842 -1.3335)
			(stroke
				(width 0)
				(type default)
			)
			(fill no)
			(layer "F.Fab")
		)
		(pad "1" smd custom
			(at 0 -0.762)
			(size 0.2159 0.2159)
			(layers "F.Cu" "F.Mask" "F.Paste")
			(net "P12V")
			(options
				(clearance outline)
				(anchor circle)
			)
			(primitives
				(gr_poly
					(pts
						(arc
							(start -0.3302 -0.4318)
							(mid -0.402042 -0.402042)
							(end -0.4318 -0.3302)
						)
						(arc
							(start -0.4318 0.3302)
							(mid -0.402042 0.402042)
							(end -0.3302 0.4318)
						)
						(arc
							(start 0.3302 0.4318)
							(mid 0.402042 0.402042)
							(end 0.4318 0.3302)
						)
						(arc
							(start 0.4318 -0.3302)
							(mid 0.402042 -0.402042)
							(end 0.3302 -0.4318)
						)
					)
					(width 0)
					(fill yes)
				)
			)
		)
		(pad "2" smd custom
			(at 0 0.762)
			(size 0.2159 0.2159)
			(layers "F.Cu" "F.Mask" "F.Paste")
			(net "GND")
			(options
				(clearance outline)
				(anchor circle)
			)
			(primitives
				(gr_poly
					(pts
						(arc
							(start -0.3302 -0.4318)
							(mid -0.402042 -0.402042)
							(end -0.4318 -0.3302)
						)
						(arc
							(start -0.4318 0.3302)
							(mid -0.402042 0.402042)
							(end -0.3302 0.4318)
						)
						(arc
							(start 0.3302 0.4318)
							(mid 0.402042 0.402042)
							(end 0.4318 0.3302)
						)
						(arc
							(start 0.4318 -0.3302)
							(mid 0.402042 -0.402042)
							(end 0.3302 -0.4318)
						)
					)
					(width 0)
					(fill yes)
				)
			)
		)
	)
	(footprint ""
		(layer "F.Cu")
		(at 31.96209 -150.781766 180)
		(property "Reference" "TP6"
			(at 0 0 180)
			(layer "F.SilkS")
			(hide yes)
			(effects
				(font
					(size 1.27 1.27)
				)
			)
		)
		(property "Value" "TPAD32-GP"
			(at 0 -3.166364 180)
			(unlocked yes)
			(layer "F.Fab")
			(hide yes)
			(effects
				(font
					(size 1.016 1.016)
					(thickness 0.1524)
				)
			)
		)
		(property "Device Type" "TPAD32"
			(at 0 -4.690618 180)
			(unlocked yes)
			(layer "F.Fab")
			(hide yes)
			(effects
				(font
					(size 1.016 1.016)
					(thickness 0.1524)
				)
			)
		)
		(duplicate_pad_numbers_are_jumpers no)
		(fp_poly
			(pts
				(arc
					(start 0.7112 0)
					(mid -0.7112 0)
					(end 0.7112 0)
				)
			)
			(stroke
				(width 0)
				(type default)
			)
			(fill no)
			(layer "F.CrtYd")
		)
		(fp_poly
			(pts
				(arc
					(start 0.7112 0)
					(mid -0.7112 0)
					(end 0.7112 0)
				)
			)
			(stroke
				(width 0)
				(type default)
			)
			(fill no)
			(layer "F.Fab")
		)
		(pad "1" smd circle
			(at 0 0 180)
			(size 0.8128 0.8128)
			(layers "F.Cu" "F.Mask" "F.Paste")
			(net "NCT7904_VSEN8")
		)
	)
	(footprint ""
		(layer "F.Cu")
		(at 24.257 -371.475 180)
		(property "Reference" "PR36"
			(at 0 0 180)
			(layer "F.SilkS")
			(hide yes)
			(effects
				(font
					(size 1.27 1.27)
				)
			)
		)
		(property "Value" "4K02R2F-GP"
			(at 0.064008 -3.993896 180)
			(unlocked yes)
			(layer "F.Fab")
			(hide yes)
			(effects
				(font
					(size 1.016 1.016)
					(thickness 0.1524)
				)
			)
		)
		(property "Device Type" "R402H16"
			(at 0.064008 -5.517896 180)
			(unlocked yes)
			(layer "F.Fab")
			(hide yes)
			(effects
				(font
					(size 1.016 1.016)
					(thickness 0.1524)
				)
			)
		)
		(duplicate_pad_numbers_are_jumpers no)
		(fp_line
			(start 0.508 -0.9398)
			(end -0.508 -0.9398)
			(stroke
				(width 0.1524)
				(type default)
			)
			(layer "F.SilkS")
		)
		(fp_line
			(start -0.508 -0.9398)
			(end -0.508 0.9398)
			(stroke
				(width 0.1524)
				(type default)
			)
			(layer "F.SilkS")
		)
		(fp_rect
			(start -0.508 0.9398)
			(end 0.508 -0.9398)
			(stroke
				(width 0)
				(type default)
			)
			(fill no)
			(layer "F.CrtYd")
		)
		(fp_rect
			(start -0.508 0.9398)
			(end 0.508 -0.9398)
			(stroke
				(width 0)
				(type default)
			)
			(fill no)
			(layer "F.Fab")
		)
		(pad "1" smd custom
			(at 0 -0.4445 180)
			(size 0.1397 0.1397)
			(layers "F.Cu" "F.Mask" "F.Paste")
			(net "ADM1276_OV")
			(options
				(clearance outline)
				(anchor circle)
			)
			(primitives
				(gr_poly
					(pts
						(arc
							(start -0.1778 -0.2794)
							(mid -0.249642 -0.249642)
							(end -0.2794 -0.1778)
						)
						(arc
							(start -0.2794 0.1778)
							(mid -0.249642 0.249642)
							(end -0.1778 0.2794)
						)
						(arc
							(start 0.1778 0.2794)
							(mid 0.249642 0.249642)
							(end 0.2794 0.1778)
						)
						(arc
							(start 0.2794 -0.1778)
							(mid 0.249642 -0.249642)
							(end 0.1778 -0.2794)
						)
					)
					(width 0)
					(fill yes)
				)
			)
		)
		(pad "2" smd custom
			(at 0 0.4445 180)
			(size 0.1397 0.1397)
			(layers "F.Cu" "F.Mask" "F.Paste")
			(net "GND")
			(options
				(clearance outline)
				(anchor circle)
			)
			(primitives
				(gr_poly
					(pts
						(arc
							(start -0.1778 -0.2794)
							(mid -0.249642 -0.249642)
							(end -0.2794 -0.1778)
						)
						(arc
							(start -0.2794 0.1778)
							(mid -0.249642 0.249642)
							(end -0.1778 0.2794)
						)
						(arc
							(start 0.1778 0.2794)
							(mid 0.249642 0.249642)
							(end 0.2794 0.1778)
						)
						(arc
							(start 0.2794 -0.1778)
							(mid 0.249642 -0.249642)
							(end 0.1778 -0.2794)
						)
					)
					(width 0)
					(fill yes)
				)
			)
		)
	)
	(footprint ""
		(layer "F.Cu")
		(at 38.692074 -363.062774 180)
		(property "Reference" "PR40"
			(at 0 0 180)
			(layer "F.SilkS")
			(hide yes)
			(effects
				(font
					(size 1.27 1.27)
				)
			)
		)
		(property "Value" "54K9R2F-L-GP"
			(at 0.064008 -3.993896 180)
			(unlocked yes)
			(layer "F.Fab")
			(hide yes)
			(effects
				(font
					(size 1.016 1.016)
					(thickness 0.1524)
				)
			)
		)
		(property "Device Type" "R402H16"
			(at 0.064008 -5.517896 180)
			(unlocked yes)
			(layer "F.Fab")
			(hide yes)
			(effects
				(font
					(size 1.016 1.016)
					(thickness 0.1524)
				)
			)
		)
		(duplicate_pad_numbers_are_jumpers no)
		(fp_line
			(start 0.508 -0.9398)
			(end -0.508 -0.9398)
			(stroke
				(width 0.1524)
				(type default)
			)
			(layer "F.SilkS")
		)
		(fp_line
			(start -0.508 -0.9398)
			(end -0.508 0.9398)
			(stroke
				(width 0.1524)
				(type default)
			)
			(layer "F.SilkS")
		)
		(fp_rect
			(start -0.508 0.9398)
			(end 0.508 -0.9398)
			(stroke
				(width 0)
				(type default)
			)
			(fill no)
			(layer "F.CrtYd")
		)
		(fp_rect
			(start -0.508 0.9398)
			(end 0.508 -0.9398)
			(stroke
				(width 0)
				(type default)
			)
			(fill no)
			(layer "F.Fab")
		)
		(pad "1" smd custom
			(at 0 -0.4445 180)
			(size 0.1397 0.1397)
			(layers "F.Cu" "F.Mask" "F.Paste")
			(net "P12V_AUX")
			(options
				(clearance outline)
				(anchor circle)
			)
			(primitives
				(gr_poly
					(pts
						(arc
							(start -0.1778 -0.2794)
							(mid -0.249642 -0.249642)
							(end -0.2794 -0.1778)
						)
						(arc
							(start -0.2794 0.1778)
							(mid -0.249642 0.249642)
							(end -0.1778 0.2794)
						)
						(arc
							(start 0.1778 0.2794)
							(mid 0.249642 0.249642)
							(end 0.2794 0.1778)
						)
						(arc
							(start 0.2794 -0.1778)
							(mid 0.249642 -0.249642)
							(end 0.1778 -0.2794)
						)
					)
					(width 0)
					(fill yes)
				)
			)
		)
		(pad "2" smd custom
			(at 0 0.4445 180)
			(size 0.1397 0.1397)
			(layers "F.Cu" "F.Mask" "F.Paste")
			(net "TEMP_ALM#_REVERSE")
			(options
				(clearance outline)
				(anchor circle)
			)
			(primitives
				(gr_poly
					(pts
						(arc
							(start -0.1778 -0.2794)
							(mid -0.249642 -0.249642)
							(end -0.2794 -0.1778)
						)
						(arc
							(start -0.2794 0.1778)
							(mid -0.249642 0.249642)
							(end -0.1778 0.2794)
						)
						(arc
							(start 0.1778 0.2794)
							(mid 0.249642 0.249642)
							(end 0.2794 0.1778)
						)
						(arc
							(start 0.2794 -0.1778)
							(mid 0.249642 -0.249642)
							(end 0.1778 -0.2794)
						)
					)
					(width 0)
					(fill yes)
				)
			)
		)
	)
	(footprint ""
		(layer "F.Cu")
		(at 19.1008 -187.8838)
		(property "Reference" "C37"
			(at 0 0 0)
			(layer "F.SilkS")
			(hide yes)
			(effects
				(font
					(size 1.27 1.27)
				)
			)
		)
		(property "Value" "SCD1U16V2KX-3GP"
			(at 1.1811 -2.7051 0)
			(unlocked yes)
			(layer "F.Fab")
			(hide yes)
			(effects
				(font
					(size 1.016 1.016)
					(thickness 0.1524)
				)
			)
		)
		(property "Device Type" "C402H22"
			(at 1.1811 -4.2291 0)
			(unlocked yes)
			(layer "F.Fab")
			(hide yes)
			(effects
				(font
					(size 1.016 1.016)
					(thickness 0.1524)
				)
			)
		)
		(duplicate_pad_numbers_are_jumpers no)
		(fp_rect
			(start -0.4318 0.9525)
			(end 0.4318 -0.9525)
			(stroke
				(width 0)
				(type default)
			)
			(fill no)
			(layer "F.CrtYd")
		)
		(fp_rect
			(start -0.4318 0.9525)
			(end 0.4318 -0.9525)
			(stroke
				(width 0)
				(type default)
			)
			(fill no)
			(layer "F.Fab")
		)
		(pad "1" smd custom
			(at 0 -0.4445)
			(size 0.1524 0.1524)
			(layers "F.Cu" "F.Mask" "F.Paste")
			(net "FAN_TACH8")
			(options
				(clearance outline)
				(anchor circle)
			)
			(primitives
				(gr_poly
					(pts
						(arc
							(start 0.3048 -0.2032)
							(mid 0.275042 -0.275042)
							(end 0.2032 -0.3048)
						)
						(arc
							(start -0.2032 -0.3048)
							(mid -0.275042 -0.275042)
							(end -0.3048 -0.2032)
						)
						(arc
							(start -0.3048 0.2032)
							(mid -0.275042 0.275042)
							(end -0.2032 0.3048)
						)
						(arc
							(start 0.2032 0.3048)
							(mid 0.275042 0.275042)
							(end 0.3048 0.2032)
						)
					)
					(width 0)
					(fill yes)
				)
			)
		)
		(pad "2" smd custom
			(at 0 0.4445)
			(size 0.1524 0.1524)
			(layers "F.Cu" "F.Mask" "F.Paste")
			(net "GND")
			(options
				(clearance outline)
				(anchor circle)
			)
			(primitives
				(gr_poly
					(pts
						(arc
							(start 0.3048 -0.2032)
							(mid 0.275042 -0.275042)
							(end 0.2032 -0.3048)
						)
						(arc
							(start -0.2032 -0.3048)
							(mid -0.275042 -0.275042)
							(end -0.3048 -0.2032)
						)
						(arc
							(start -0.3048 0.2032)
							(mid -0.275042 0.275042)
							(end -0.2032 0.3048)
						)
						(arc
							(start 0.2032 0.3048)
							(mid 0.275042 0.275042)
							(end 0.3048 0.2032)
						)
					)
					(width 0)
					(fill yes)
				)
			)
		)
	)
	(footprint ""
		(layer "F.Cu")
		(at 15.5702 -259.2324 -90)
		(property "Reference" "R88"
			(at 0 0 270)
			(layer "F.SilkS")
			(hide yes)
			(effects
				(font
					(size 1.27 1.27)
				)
			)
		)
		(property "Value" "10KR2F-2-GP"
			(at 0.064008 -3.993896 270)
			(unlocked yes)
			(layer "F.Fab")
			(hide yes)
			(effects
				(font
					(size 1.016 1.016)
					(thickness 0.1524)
				)
			)
		)
		(property "Device Type" "R402H16"
			(at 0.064008 -5.517896 270)
			(unlocked yes)
			(layer "F.Fab")
			(hide yes)
			(effects
				(font
					(size 1.016 1.016)
					(thickness 0.1524)
				)
			)
		)
		(duplicate_pad_numbers_are_jumpers no)
		(fp_line
			(start -0.508 -0.9398)
			(end -0.508 0.9398)
			(stroke
				(width 0.1524)
				(type default)
			)
			(layer "F.SilkS")
		)
		(fp_line
			(start 0.508 -0.9398)
			(end -0.508 -0.9398)
			(stroke
				(width 0.1524)
				(type default)
			)
			(layer "F.SilkS")
		)
		(fp_rect
			(start -0.508 0.9398)
			(end 0.508 -0.9398)
			(stroke
				(width 0)
				(type default)
			)
			(fill no)
			(layer "F.CrtYd")
		)
		(fp_rect
			(start -0.508 0.9398)
			(end 0.508 -0.9398)
			(stroke
				(width 0)
				(type default)
			)
			(fill no)
			(layer "F.Fab")
		)
		(pad "1" smd custom
			(at 0 -0.4445 270)
			(size 0.1397 0.1397)
			(layers "F.Cu" "F.Mask" "F.Paste")
			(net "FANIN_6")
			(options
				(clearance outline)
				(anchor circle)
			)
			(primitives
				(gr_poly
					(pts
						(arc
							(start -0.1778 -0.2794)
							(mid -0.249642 -0.249642)
							(end -0.2794 -0.1778)
						)
						(arc
							(start -0.2794 0.1778)
							(mid -0.249642 0.249642)
							(end -0.1778 0.2794)
						)
						(arc
							(start 0.1778 0.2794)
							(mid 0.249642 0.249642)
							(end 0.2794 0.1778)
						)
						(arc
							(start 0.2794 -0.1778)
							(mid 0.249642 -0.249642)
							(end 0.1778 -0.2794)
						)
					)
					(width 0)
					(fill yes)
				)
			)
		)
		(pad "2" smd custom
			(at 0 0.4445 270)
			(size 0.1397 0.1397)
			(layers "F.Cu" "F.Mask" "F.Paste")
			(net "GND")
			(options
				(clearance outline)
				(anchor circle)
			)
			(primitives
				(gr_poly
					(pts
						(arc
							(start -0.1778 -0.2794)
							(mid -0.249642 -0.249642)
							(end -0.2794 -0.1778)
						)
						(arc
							(start -0.2794 0.1778)
							(mid -0.249642 0.249642)
							(end -0.1778 0.2794)
						)
						(arc
							(start 0.1778 0.2794)
							(mid 0.249642 0.249642)
							(end 0.2794 0.1778)
						)
						(arc
							(start 0.2794 -0.1778)
							(mid 0.249642 -0.249642)
							(end 0.1778 -0.2794)
						)
					)
					(width 0)
					(fill yes)
				)
			)
		)
	)
	(footprint ""
		(layer "F.Cu")
		(at 37.1602 -246.5324)
		(property "Reference" "U6"
			(at 0 0 0)
			(layer "F.SilkS")
			(hide yes)
			(effects
				(font
					(size 1.27 1.27)
				)
			)
		)
		(property "Value" "PCA9551PW-T-2GP-U"
			(at 0.127 -12.573 0)
			(unlocked yes)
			(layer "F.Fab")
			(hide yes)
			(effects
				(font
					(size 1.016 1.016)
					(thickness 0.1524)
				)
			)
		)
		(property "Device Type" "TSOIC16H44"
			(at 0.1016 -14.5796 0)
			(unlocked yes)
			(layer "F.Fab")
			(hide yes)
			(effects
				(font
					(size 1.016 1.016)
					(thickness 0.1524)
				)
			)
		)
		(duplicate_pad_numbers_are_jumpers no)
		(fp_line
			(start -3.0988 -1.778)
			(end -3.0988 1.778)
			(stroke
				(width 0.1524)
				(type default)
			)
			(layer "F.SilkS")
		)
		(fp_line
			(start -3.0988 -1.778)
			(end 2.3622 -1.778)
			(stroke
				(width 0.1524)
				(type default)
			)
			(layer "F.SilkS")
		)
		(fp_line
			(start -2.921 3.81)
			(end -2.921 1.778)
			(stroke
				(width 0.508)
				(type default)
			)
			(layer "F.SilkS")
		)
		(fp_line
			(start -2.54 0)
			(end -3.0988 -0.5588)
			(stroke
				(width 0.1524)
				(type default)
			)
			(layer "F.SilkS")
		)
		(fp_line
			(start -2.54 0)
			(end -3.0988 0.5588)
			(stroke
				(width 0.1524)
				(type default)
			)
			(layer "F.SilkS")
		)
		(fp_line
			(start 2.3622 -1.778)
			(end 2.3622 1.778)
			(stroke
				(width 0.1524)
				(type default)
			)
			(layer "F.SilkS")
		)
		(fp_line
			(start 2.3622 1.778)
			(end -2.921 1.778)
			(stroke
				(width 0.1524)
				(type default)
			)
			(layer "F.SilkS")
		)
		(fp_poly
			(pts
				(xy -2.4638 -1.778) (xy -2.4638 1.778) (xy 2.3622 1.778) (xy 2.3622 -1.778)
			)
			(stroke
				(width 0)
				(type default)
			)
			(fill yes)
			(layer "F.SilkS")
		)
		(fp_rect
			(start -3.175 4.064)
			(end 3.175 -4.064)
			(stroke
				(width 0)
				(type default)
			)
			(fill no)
			(layer "F.CrtYd")
		)
		(fp_poly
			(pts
				(xy -3.175 -4.064) (xy 3.175 -4.064) (xy 3.175 4.064) (xy -3.175 4.064)
			)
			(stroke
				(width 0)
				(type default)
			)
			(fill no)
			(layer "F.Fab")
		)
		(pad "1" smd rect
			(at -2.27584 2.8194)
			(size 0.3556 1.524)
			(layers "F.Cu" "F.Mask" "F.Paste")
			(net "LED_DRV_A0")
		)
		(pad "2" smd rect
			(at -1.6256 2.8194)
			(size 0.3556 1.524)
			(layers "F.Cu" "F.Mask" "F.Paste")
			(net "LED_DRV_A1")
		)
		(pad "3" smd rect
			(at -0.97536 2.8194)
			(size 0.3556 1.524)
			(layers "F.Cu" "F.Mask" "F.Paste")
			(net "LED_DRV_A2")
		)
		(pad "4" smd rect
			(at -0.32512 2.8194)
			(size 0.3556 1.524)
			(layers "F.Cu" "F.Mask" "F.Paste")
			(net "LED_DR_LED0")
		)
		(pad "5" smd rect
			(at 0.32512 2.8194)
			(size 0.3556 1.524)
			(layers "F.Cu" "F.Mask" "F.Paste")
			(net "LED_DR_LED1")
		)
		(pad "6" smd rect
			(at 0.97536 2.8194)
			(size 0.3556 1.524)
			(layers "F.Cu" "F.Mask" "F.Paste")
			(net "LED_DR_LED2")
		)
		(pad "7" smd rect
			(at 1.6256 2.8194)
			(size 0.3556 1.524)
			(layers "F.Cu" "F.Mask" "F.Paste")
			(net "LED_DR_LED3")
		)
		(pad "8" smd rect
			(at 2.27584 2.8194)
			(size 0.3556 1.524)
			(layers "F.Cu" "F.Mask" "F.Paste")
			(net "GND")
		)
		(pad "9" smd rect
			(at 2.27584 -2.8194)
			(size 0.3556 1.524)
			(layers "F.Cu" "F.Mask" "F.Paste")
			(net "LED_DR_LED4")
		)
		(pad "10" smd rect
			(at 1.6256 -2.8194)
			(size 0.3556 1.524)
			(layers "F.Cu" "F.Mask" "F.Paste")
			(net "LED_DR_LED5")
		)
		(pad "11" smd rect
			(at 0.97536 -2.8194)
			(size 0.3556 1.524)
			(layers "F.Cu" "F.Mask" "F.Paste")
			(net "LED_DR_LED6_RESERVE")
		)
		(pad "12" smd rect
			(at 0.32512 -2.8194)
			(size 0.3556 1.524)
			(layers "F.Cu" "F.Mask" "F.Paste")
			(net "LED_DR_LED7_RESERVE")
		)
		(pad "13" smd rect
			(at -0.32512 -2.8194)
			(size 0.3556 1.524)
			(layers "F.Cu" "F.Mask" "F.Paste")
			(net "LED_DRV_RST")
		)
		(pad "14" smd rect
			(at -0.97536 -2.8194)
			(size 0.3556 1.524)
			(layers "F.Cu" "F.Mask" "F.Paste")
			(net "I2C_C_SCL_LEDDRV")
		)
		(pad "15" smd rect
			(at -1.6256 -2.8194)
			(size 0.3556 1.524)
			(layers "F.Cu" "F.Mask" "F.Paste")
			(net "I2C_C_SDA_LEDDRV")
		)
		(pad "16" smd rect
			(at -2.27584 -2.8194)
			(size 0.3556 1.524)
			(layers "F.Cu" "F.Mask" "F.Paste")
			(net "P3V3")
		)
	)
	(footprint ""
		(layer "F.Cu")
		(at 45.500036 -480.000056)
		(property "Reference" "H3"
			(at 0 0 0)
			(layer "F.SilkS")
			(hide yes)
			(effects
				(font
					(size 1.27 1.27)
				)
			)
		)
		(property "Value" "HOLE315R158"
			(at -5.08 -0.4572 0)
			(unlocked yes)
			(layer "F.Fab")
			(hide yes)
			(effects
				(font
					(size 1.016 1.016)
					(thickness 0.1524)
				)
			)
		)
		(property "Device Type" "HOLE315R158"
			(at -5.08 -1.9812 0)
			(unlocked yes)
			(layer "F.Fab")
			(hide yes)
			(effects
				(font
					(size 1.016 1.016)
					(thickness 0.1524)
				)
			)
		)
		(duplicate_pad_numbers_are_jumpers no)
		(fp_poly
			(pts
				(arc
					(start -4.3053 0)
					(mid 4.3053 0)
					(end -4.3053 0)
				)
			)
			(stroke
				(width 0)
				(type default)
			)
			(fill no)
			(layer "B.CrtYd")
		)
		(fp_poly
			(pts
				(arc
					(start -4.3053 0)
					(mid 4.3053 0)
					(end -4.3053 0)
				)
			)
			(stroke
				(width 0)
				(type default)
			)
			(fill no)
			(layer "F.CrtYd")
		)
		(fp_poly
			(pts
				(arc
					(start -4.3053 0)
					(mid 4.3053 0)
					(end -4.3053 0)
				)
			)
			(stroke
				(width 0)
				(type default)
			)
			(fill no)
			(layer "B.Fab")
		)
		(fp_poly
			(pts
				(arc
					(start -4.3053 0)
					(mid 4.3053 0)
					(end -4.3053 0)
				)
			)
			(stroke
				(width 0)
				(type default)
			)
			(fill no)
			(layer "F.Fab")
		)
		(pad "1" thru_hole circle
			(at 0 0)
			(size 8.001 8.001)
			(drill 4.0132)
			(layers "*.Cu" "*.Mask")
			(remove_unused_layers no)
			(net "GND")
			(clearance -1.4859)
			(thermal_gap 0.3048)
			(padstack
				(mode front_inner_back)
				(layer "Inner"
					(shape circle)
					(size 4.4196 4.4196)
					(clearance 0.3048)
				)
				(layer "B.Cu"
					(shape circle)
					(size 8.001 8.001)
					(clearance -1.4859)
				)
			)
		)
	)
	(footprint ""
		(layer "F.Cu")
		(at 36.6522 -282.9814)
		(property "Reference" "C48"
			(at 0 0 0)
			(layer "F.SilkS")
			(hide yes)
			(effects
				(font
					(size 1.27 1.27)
				)
			)
		)
		(property "Value" "SC1U25V3KX-1-GP"
			(at 0 -2.8194 0)
			(unlocked yes)
			(layer "F.Fab")
			(hide yes)
			(effects
				(font
					(size 1.016 1.016)
					(thickness 0.1524)
				)
			)
		)
		(property "Device Type" "C603H36"
			(at 0 -4.3434 0)
			(unlocked yes)
			(layer "F.Fab")
			(hide yes)
			(effects
				(font
					(size 1.016 1.016)
					(thickness 0.1524)
				)
			)
		)
		(duplicate_pad_numbers_are_jumpers no)
		(fp_line
			(start 0.508 0)
			(end -0.508 0)
			(stroke
				(width 0.2032)
				(type default)
			)
			(layer "F.SilkS")
		)
		(fp_rect
			(start -0.5842 1.3335)
			(end 0.5842 -1.3335)
			(stroke
				(width 0)
				(type default)
			)
			(fill no)
			(layer "F.CrtYd")
		)
		(fp_rect
			(start -0.5842 1.3335)
			(end 0.5842 -1.3335)
			(stroke
				(width 0)
				(type default)
			)
			(fill no)
			(layer "F.Fab")
		)
		(pad "1" smd custom
			(at 0 -0.762)
			(size 0.2159 0.2159)
			(layers "F.Cu" "F.Mask" "F.Paste")
			(net "P12V")
			(options
				(clearance outline)
				(anchor circle)
			)
			(primitives
				(gr_poly
					(pts
						(arc
							(start -0.3302 -0.4318)
							(mid -0.402042 -0.402042)
							(end -0.4318 -0.3302)
						)
						(arc
							(start -0.4318 0.3302)
							(mid -0.402042 0.402042)
							(end -0.3302 0.4318)
						)
						(arc
							(start 0.3302 0.4318)
							(mid 0.402042 0.402042)
							(end 0.4318 0.3302)
						)
						(arc
							(start 0.4318 -0.3302)
							(mid 0.402042 -0.402042)
							(end 0.3302 -0.4318)
						)
					)
					(width 0)
					(fill yes)
				)
			)
		)
		(pad "2" smd custom
			(at 0 0.762)
			(size 0.2159 0.2159)
			(layers "F.Cu" "F.Mask" "F.Paste")
			(net "GND")
			(options
				(clearance outline)
				(anchor circle)
			)
			(primitives
				(gr_poly
					(pts
						(arc
							(start -0.3302 -0.4318)
							(mid -0.402042 -0.402042)
							(end -0.4318 -0.3302)
						)
						(arc
							(start -0.4318 0.3302)
							(mid -0.402042 0.402042)
							(end -0.3302 0.4318)
						)
						(arc
							(start 0.3302 0.4318)
							(mid 0.402042 0.402042)
							(end 0.4318 0.3302)
						)
						(arc
							(start 0.4318 -0.3302)
							(mid 0.402042 -0.402042)
							(end 0.3302 -0.4318)
						)
					)
					(width 0)
					(fill yes)
				)
			)
		)
	)
	(footprint ""
		(layer "F.Cu")
		(at 5.947918 -434.623972 180)
		(property "Reference" "Q8"
			(at 0 0 180)
			(layer "F.SilkS")
			(hide yes)
			(effects
				(font
					(size 1.27 1.27)
				)
			)
		)
		(property "Value" "PMBS3904-1-GP"
			(at 0 -9.0932 180)
			(unlocked yes)
			(layer "F.Fab")
			(hide yes)
			(effects
				(font
					(size 1.016 1.016)
					(thickness 0.1524)
				)
			)
		)
		(property "Device Type" "SOT-23-10H44"
			(at 0 -10.6172 180)
			(unlocked yes)
			(layer "F.Fab")
			(hide yes)
			(effects
				(font
					(size 1.016 1.016)
					(thickness 0.1524)
				)
			)
		)
		(duplicate_pad_numbers_are_jumpers no)
		(fp_line
			(start 1.651 1.778)
			(end 1.651 -1.778)
			(stroke
				(width 0.1524)
				(type default)
			)
			(layer "F.SilkS")
		)
		(fp_line
			(start 1.651 -1.778)
			(end -1.651 -1.778)
			(stroke
				(width 0.1524)
				(type default)
			)
			(layer "F.SilkS")
		)
		(fp_line
			(start -0.635 1.8796)
			(end -1.7526 1.8796)
			(stroke
				(width 0.3302)
				(type default)
			)
			(layer "F.SilkS")
		)
		(fp_line
			(start -0.71628 2.15265)
			(end -1.26492 2.15265)
			(stroke
				(width 0.0127)
				(type default)
			)
			(layer "F.SilkS")
		)
		(fp_line
			(start -0.719074 2.145538)
			(end -1.265936 2.14122)
			(stroke
				(width 0.0127)
				(type default)
			)
			(layer "F.SilkS")
		)
		(fp_line
			(start -0.9906 1.86309)
			(end -0.701294 2.15265)
			(stroke
				(width 0.0127)
				(type default)
			)
			(layer "F.SilkS")
		)
		(fp_line
			(start -0.994156 1.8669)
			(end -0.987044 1.8669)
			(stroke
				(width 0.0127)
				(type default)
			)
			(layer "F.SilkS")
		)
		(fp_line
			(start -1.003808 1.876552)
			(end -0.977646 1.876552)
			(stroke
				(width 0.0127)
				(type default)
			)
			(layer "F.SilkS")
		)
		(fp_line
			(start -1.013206 1.88595)
			(end -0.967994 1.88595)
			(stroke
				(width 0.0127)
				(type default)
			)
			(layer "F.SilkS")
		)
		(fp_line
			(start -1.022858 1.895602)
			(end -0.958596 1.895602)
			(stroke
				(width 0.0127)
				(type default)
			)
			(layer "F.SilkS")
		)
		(fp_line
			(start -1.032256 1.905)
			(end -0.948944 1.905)
			(stroke
				(width 0.0127)
				(type default)
			)
			(layer "F.SilkS")
		)
		(fp_line
			(start -1.041908 1.914652)
			(end -0.939546 1.914652)
			(stroke
				(width 0.0127)
				(type default)
			)
			(layer "F.SilkS")
		)
		(fp_line
			(start -1.051306 1.92405)
			(end -0.929894 1.92405)
			(stroke
				(width 0.0127)
				(type default)
			)
			(layer "F.SilkS")
		)
		(fp_line
			(start -1.060958 1.933702)
			(end -0.920496 1.933702)
			(stroke
				(width 0.0127)
				(type default)
			)
			(layer "F.SilkS")
		)
		(fp_line
			(start -1.070356 1.9431)
			(end -0.910844 1.9431)
			(stroke
				(width 0.0127)
				(type default)
			)
			(layer "F.SilkS")
		)
		(fp_line
			(start -1.080008 1.952752)
			(end -0.901446 1.952752)
			(stroke
				(width 0.0127)
				(type default)
			)
			(layer "F.SilkS")
		)
		(fp_line
			(start -1.089406 1.96215)
			(end -0.891794 1.96215)
			(stroke
				(width 0.0127)
				(type default)
			)
			(layer "F.SilkS")
		)
		(fp_line
			(start -1.099058 1.971802)
			(end -0.882396 1.971802)
			(stroke
				(width 0.0127)
				(type default)
			)
			(layer "F.SilkS")
		)
		(fp_line
			(start -1.108456 1.9812)
			(end -0.872744 1.9812)
			(stroke
				(width 0.0127)
				(type default)
			)
			(layer "F.SilkS")
		)
		(fp_line
			(start -1.118108 1.990852)
			(end -0.863346 1.990852)
			(stroke
				(width 0.0127)
				(type default)
			)
			(layer "F.SilkS")
		)
		(fp_line
			(start -1.127506 2.00025)
			(end -0.853694 2.00025)
			(stroke
				(width 0.0127)
				(type default)
			)
			(layer "F.SilkS")
		)
		(fp_line
			(start -1.137158 2.009902)
			(end -0.844296 2.009902)
			(stroke
				(width 0.0127)
				(type default)
			)
			(layer "F.SilkS")
		)
		(fp_line
			(start -1.146556 2.0193)
			(end -0.834644 2.0193)
			(stroke
				(width 0.0127)
				(type default)
			)
			(layer "F.SilkS")
		)
		(fp_line
			(start -1.156208 2.028952)
			(end -0.825246 2.028952)
			(stroke
				(width 0.0127)
				(type default)
			)
			(layer "F.SilkS")
		)
		(fp_line
			(start -1.165606 2.03835)
			(end -0.815594 2.03835)
			(stroke
				(width 0.0127)
				(type default)
			)
			(layer "F.SilkS")
		)
		(fp_line
			(start -1.175258 2.048002)
			(end -0.806196 2.048002)
			(stroke
				(width 0.0127)
				(type default)
			)
			(layer "F.SilkS")
		)
		(fp_line
			(start -1.184656 2.0574)
			(end -0.796544 2.0574)
			(stroke
				(width 0.0127)
				(type default)
			)
			(layer "F.SilkS")
		)
		(fp_line
			(start -1.194308 2.067052)
			(end -0.787146 2.067052)
			(stroke
				(width 0.0127)
				(type default)
			)
			(layer "F.SilkS")
		)
		(fp_line
			(start -1.203706 2.07645)
			(end -0.777494 2.07645)
			(stroke
				(width 0.0127)
				(type default)
			)
			(layer "F.SilkS")
		)
		(fp_line
			(start -1.213358 2.086102)
			(end -0.768096 2.086102)
			(stroke
				(width 0.0127)
				(type default)
			)
			(layer "F.SilkS")
		)
		(fp_line
			(start -1.222756 2.0955)
			(end -0.758444 2.0955)
			(stroke
				(width 0.0127)
				(type default)
			)
			(layer "F.SilkS")
		)
		(fp_line
			(start -1.232408 2.105152)
			(end -0.749046 2.105152)
			(stroke
				(width 0.0127)
				(type default)
			)
			(layer "F.SilkS")
		)
		(fp_line
			(start -1.241806 2.11455)
			(end -0.739394 2.11455)
			(stroke
				(width 0.0127)
				(type default)
			)
			(layer "F.SilkS")
		)
		(fp_line
			(start -1.251458 2.124202)
			(end -0.729996 2.124202)
			(stroke
				(width 0.0127)
				(type default)
			)
			(layer "F.SilkS")
		)
		(fp_line
			(start -1.260856 2.1336)
			(end -0.720344 2.1336)
			(stroke
				(width 0.0127)
				(type default)
			)
			(layer "F.SilkS")
		)
		(fp_line
			(start -1.279144 2.15265)
			(end -0.701294 2.15265)
			(stroke
				(width 0.0127)
				(type default)
			)
			(layer "F.SilkS")
		)
		(fp_line
			(start -1.279398 2.152142)
			(end -0.9906 1.86309)
			(stroke
				(width 0.0127)
				(type default)
			)
			(layer "F.SilkS")
		)
		(fp_line
			(start -1.651 1.778)
			(end 1.651 1.778)
			(stroke
				(width 0.1524)
				(type default)
			)
			(layer "F.SilkS")
		)
		(fp_line
			(start -1.651 -1.778)
			(end -1.651 1.778)
			(stroke
				(width 0.1524)
				(type default)
			)
			(layer "F.SilkS")
		)
		(fp_line
			(start -1.7526 1.8796)
			(end -1.7526 0.9906)
			(stroke
				(width 0.3302)
				(type default)
			)
			(layer "F.SilkS")
		)
		(fp_poly
			(pts
				(xy -1.285748 2.159) (xy -1.285748 1.8796) (xy -1.778 1.8796) (xy -1.778 -1.8796) (xy 1.778 -1.8796)
				(xy 1.778 1.8796) (xy -0.694944 1.8796) (xy -0.694944 2.159)
			)
			(stroke
				(width 0)
				(type default)
			)
			(fill no)
			(layer "F.CrtYd")
		)
		(fp_poly
			(pts
				(xy -1.285748 2.159) (xy -1.285748 1.8796) (xy -1.778 1.8796) (xy -1.778 -1.8796) (xy 1.778 -1.8796)
				(xy 1.778 1.8796) (xy -0.694944 1.8796) (xy -0.694944 2.159)
			)
			(stroke
				(width 0)
				(type default)
			)
			(fill no)
			(layer "F.Fab")
		)
		(pad "1" smd rect
			(at -0.98425 0.9525 180)
			(size 0.762 1.143)
			(layers "F.Cu" "F.Mask" "F.Paste")
			(net "LED_DR_LED0_B")
		)
		(pad "2" smd rect
			(at 0.98425 0.9525 180)
			(size 0.762 1.143)
			(layers "F.Cu" "F.Mask" "F.Paste")
			(net "GND")
		)
		(pad "3" smd rect
			(at 0 -0.9525 180)
			(size 0.762 1.143)
			(layers "F.Cu" "F.Mask" "F.Paste")
			(net "LED_DR_LED0_BLUE")
		)
	)
	(footprint ""
		(layer "F.Cu")
		(at 16.128492 -285.014162 180)
		(property "Reference" "R93"
			(at 0 0 180)
			(layer "F.SilkS")
			(hide yes)
			(effects
				(font
					(size 1.27 1.27)
				)
			)
		)
		(property "Value" "4K7R2F-GP"
			(at 0.064008 -3.993896 180)
			(unlocked yes)
			(layer "F.Fab")
			(hide yes)
			(effects
				(font
					(size 1.016 1.016)
					(thickness 0.1524)
				)
			)
		)
		(property "Device Type" "R402H16"
			(at 0.064008 -5.517896 180)
			(unlocked yes)
			(layer "F.Fab")
			(hide yes)
			(effects
				(font
					(size 1.016 1.016)
					(thickness 0.1524)
				)
			)
		)
		(duplicate_pad_numbers_are_jumpers no)
		(fp_line
			(start 0.508 -0.9398)
			(end -0.508 -0.9398)
			(stroke
				(width 0.1524)
				(type default)
			)
			(layer "F.SilkS")
		)
		(fp_line
			(start -0.508 -0.9398)
			(end -0.508 0.9398)
			(stroke
				(width 0.1524)
				(type default)
			)
			(layer "F.SilkS")
		)
		(fp_rect
			(start -0.508 0.9398)
			(end 0.508 -0.9398)
			(stroke
				(width 0)
				(type default)
			)
			(fill no)
			(layer "F.CrtYd")
		)
		(fp_rect
			(start -0.508 0.9398)
			(end 0.508 -0.9398)
			(stroke
				(width 0)
				(type default)
			)
			(fill no)
			(layer "F.Fab")
		)
		(pad "1" smd custom
			(at 0 -0.4445 180)
			(size 0.1397 0.1397)
			(layers "F.Cu" "F.Mask" "F.Paste")
			(net "P12V")
			(options
				(clearance outline)
				(anchor circle)
			)
			(primitives
				(gr_poly
					(pts
						(arc
							(start -0.1778 -0.2794)
							(mid -0.249642 -0.249642)
							(end -0.2794 -0.1778)
						)
						(arc
							(start -0.2794 0.1778)
							(mid -0.249642 0.249642)
							(end -0.1778 0.2794)
						)
						(arc
							(start 0.1778 0.2794)
							(mid 0.249642 0.249642)
							(end 0.2794 0.1778)
						)
						(arc
							(start 0.2794 -0.1778)
							(mid 0.249642 -0.249642)
							(end 0.1778 -0.2794)
						)
					)
					(width 0)
					(fill yes)
				)
			)
		)
		(pad "2" smd custom
			(at 0 0.4445 180)
			(size 0.1397 0.1397)
			(layers "F.Cu" "F.Mask" "F.Paste")
			(net "FAN_TACH3")
			(options
				(clearance outline)
				(anchor circle)
			)
			(primitives
				(gr_poly
					(pts
						(arc
							(start -0.1778 -0.2794)
							(mid -0.249642 -0.249642)
							(end -0.2794 -0.1778)
						)
						(arc
							(start -0.2794 0.1778)
							(mid -0.249642 0.249642)
							(end -0.1778 0.2794)
						)
						(arc
							(start 0.1778 0.2794)
							(mid 0.249642 0.249642)
							(end 0.2794 0.1778)
						)
						(arc
							(start 0.2794 -0.1778)
							(mid 0.249642 -0.249642)
							(end 0.1778 -0.2794)
						)
					)
					(width 0)
					(fill yes)
				)
			)
		)
	)
	(footprint ""
		(layer "F.Cu")
		(at 20.0406 -383.8194)
		(property "Reference" "TC11"
			(at 0 0 0)
			(layer "F.SilkS")
			(hide yes)
			(effects
				(font
					(size 1.27 1.27)
				)
			)
		)
		(property "Value" "ST68U16VDM-1-GP"
			(at 0 -9.6012 0)
			(unlocked yes)
			(layer "F.Fab")
			(hide yes)
			(effects
				(font
					(size 1.016 1.016)
					(thickness 0.1524)
				)
			)
		)
		(property "Device Type" "CT7343H79"
			(at 0 -11.1252 0)
			(unlocked yes)
			(layer "F.Fab")
			(hide yes)
			(effects
				(font
					(size 1.016 1.016)
					(thickness 0.1524)
				)
			)
		)
		(duplicate_pad_numbers_are_jumpers no)
		(fp_line
			(start -2.286 -4.8768)
			(end -2.286 -2.032)
			(stroke
				(width 0.1524)
				(type default)
			)
			(layer "F.SilkS")
		)
		(fp_line
			(start -2.286 4.8768)
			(end -2.286 2.032)
			(stroke
				(width 0.1524)
				(type default)
			)
			(layer "F.SilkS")
		)
		(fp_line
			(start 2.1082 -4.699)
			(end -2.1082 -4.699)
			(stroke
				(width 0.508)
				(type default)
			)
			(layer "F.SilkS")
		)
		(fp_line
			(start 2.286 -4.8768)
			(end -2.286 -4.8768)
			(stroke
				(width 0.1524)
				(type default)
			)
			(layer "F.SilkS")
		)
		(fp_line
			(start 2.286 -2.032)
			(end 2.286 -4.8768)
			(stroke
				(width 0.1524)
				(type default)
			)
			(layer "F.SilkS")
		)
		(fp_line
			(start 2.286 2.032)
			(end 2.286 4.8768)
			(stroke
				(width 0.1524)
				(type default)
			)
			(layer "F.SilkS")
		)
		(fp_line
			(start 2.286 4.8768)
			(end -2.286 4.8768)
			(stroke
				(width 0.1524)
				(type default)
			)
			(layer "F.SilkS")
		)
		(fp_rect
			(start -2.1463 3.6449)
			(end 2.1463 -3.6449)
			(stroke
				(width 0)
				(type default)
			)
			(fill no)
			(layer "F.CrtYd")
		)
		(fp_poly
			(pts
				(xy -2.54 4.953) (xy -2.54 4.2926) (xy -3.81 4.2926) (xy -3.81 -4.2926) (xy -2.54 -4.2926) (xy -2.54 -4.953)
				(xy 2.54 -4.953) (xy 2.54 -4.2926) (xy 3.81 -4.2926) (xy 3.81 -1.6256) (xy 2.1463 -1.6256) (xy 2.1463 -3.6449)
				(xy -2.1463 -3.6449) (xy -2.1463 3.6449) (xy 2.1463 3.6449) (xy 2.1463 -1.6129) (xy 3.81 -1.6129)
				(xy 3.81 4.2926) (xy 2.54 4.2926) (xy 2.54 4.953)
			)
			(stroke
				(width 0)
				(type default)
			)
			(fill no)
			(layer "F.CrtYd")
		)
		(fp_rect
			(start -3.81 4.2926)
			(end -2.54 -4.2926)
			(stroke
				(width 0)
				(type default)
			)
			(fill no)
			(layer "F.Fab")
		)
		(fp_rect
			(start -2.54 4.953)
			(end 2.54 -4.953)
			(stroke
				(width 0)
				(type default)
			)
			(fill no)
			(layer "F.Fab")
		)
		(fp_rect
			(start 2.54 4.2926)
			(end 3.81 -4.2926)
			(stroke
				(width 0)
				(type default)
			)
			(fill no)
			(layer "F.Fab")
		)
		(pad "1" smd rect
			(at 0 -3.1496)
			(size 2.413 2.286)
			(layers "F.Cu" "F.Mask" "F.Paste")
			(net "P12V")
		)
		(pad "2" smd rect
			(at 0 3.1496)
			(size 2.413 2.286)
			(layers "F.Cu" "F.Mask" "F.Paste")
			(net "GND")
		)
		(zone
			(layer "F.Cu")
			(hatch none 0.5)
			(connect_pads
				(clearance 0)
			)
			(min_thickness 0.25)
			(keepout
				(tracks allowed)
				(vias not_allowed)
				(pads allowed)
				(copperpour not_allowed)
				(footprints allowed)
			)
			(placement
				(enabled no)
				(sheetname "")
			)
			(fill
				(thermal_gap 0.5)
				(thermal_bridge_width 0.5)
				(island_removal_mode 0)
			)
			(polygon
				(pts
					(xy 18.5293 -379.222) (xy 21.5519 -379.222) (xy 21.5519 -382.1176) (xy 21.5519 -382.4478) (xy 18.5293 -382.4478)
					(xy 18.5293 -382.1176)
				)
			)
		)
		(zone
			(layer "F.Cu")
			(hatch none 0.5)
			(connect_pads
				(clearance 0)
			)
			(min_thickness 0.25)
			(keepout
				(tracks allowed)
				(vias not_allowed)
				(pads allowed)
				(copperpour not_allowed)
				(footprints allowed)
			)
			(placement
				(enabled no)
				(sheetname "")
			)
			(fill
				(thermal_gap 0.5)
				(thermal_bridge_width 0.5)
				(island_removal_mode 0)
			)
			(polygon
				(pts
					(xy 21.5519 -385.5085) (xy 21.5519 -388.4168) (xy 18.5293 -388.4168) (xy 18.5293 -385.5212) (xy 18.5293 -385.191)
					(xy 21.5519 -385.191)
				)
			)
		)
	)
	(footprint ""
		(layer "F.Cu")
		(at 36.659566 -152.08631 90)
		(property "Reference" "TP14"
			(at 0 0 90)
			(layer "F.SilkS")
			(hide yes)
			(effects
				(font
					(size 1.27 1.27)
				)
			)
		)
		(property "Value" "TPAD32-GP"
			(at 0 -3.166364 90)
			(unlocked yes)
			(layer "F.Fab")
			(hide yes)
			(effects
				(font
					(size 1.016 1.016)
					(thickness 0.1524)
				)
			)
		)
		(property "Device Type" "TPAD32"
			(at 0 -4.690618 90)
			(unlocked yes)
			(layer "F.Fab")
			(hide yes)
			(effects
				(font
					(size 1.016 1.016)
					(thickness 0.1524)
				)
			)
		)
		(duplicate_pad_numbers_are_jumpers no)
		(fp_poly
			(pts
				(arc
					(start 0.7112 0)
					(mid -0.7112 0)
					(end 0.7112 0)
				)
			)
			(stroke
				(width 0)
				(type default)
			)
			(fill no)
			(layer "F.CrtYd")
		)
		(fp_poly
			(pts
				(arc
					(start 0.7112 0)
					(mid -0.7112 0)
					(end 0.7112 0)
				)
			)
			(stroke
				(width 0)
				(type default)
			)
			(fill no)
			(layer "F.Fab")
		)
		(pad "1" smd circle
			(at 0 0 90)
			(size 0.8128 0.8128)
			(layers "F.Cu" "F.Mask" "F.Paste")
			(net "NCT7904_VSEN14")
		)
	)
	(footprint ""
		(layer "F.Cu")
		(at 17.018 -185.42 -90)
		(property "Reference" "R79"
			(at 0 0 270)
			(layer "F.SilkS")
			(hide yes)
			(effects
				(font
					(size 1.27 1.27)
				)
			)
		)
		(property "Value" "4K7R2F-GP"
			(at 0.064008 -3.993896 270)
			(unlocked yes)
			(layer "F.Fab")
			(hide yes)
			(effects
				(font
					(size 1.016 1.016)
					(thickness 0.1524)
				)
			)
		)
		(property "Device Type" "R402H16"
			(at 0.064008 -5.517896 270)
			(unlocked yes)
			(layer "F.Fab")
			(hide yes)
			(effects
				(font
					(size 1.016 1.016)
					(thickness 0.1524)
				)
			)
		)
		(duplicate_pad_numbers_are_jumpers no)
		(fp_line
			(start -0.508 -0.9398)
			(end -0.508 0.9398)
			(stroke
				(width 0.1524)
				(type default)
			)
			(layer "F.SilkS")
		)
		(fp_line
			(start 0.508 -0.9398)
			(end -0.508 -0.9398)
			(stroke
				(width 0.1524)
				(type default)
			)
			(layer "F.SilkS")
		)
		(fp_rect
			(start -0.508 0.9398)
			(end 0.508 -0.9398)
			(stroke
				(width 0)
				(type default)
			)
			(fill no)
			(layer "F.CrtYd")
		)
		(fp_rect
			(start -0.508 0.9398)
			(end 0.508 -0.9398)
			(stroke
				(width 0)
				(type default)
			)
			(fill no)
			(layer "F.Fab")
		)
		(pad "1" smd custom
			(at 0 -0.4445 270)
			(size 0.1397 0.1397)
			(layers "F.Cu" "F.Mask" "F.Paste")
			(net "P12V")
			(options
				(clearance outline)
				(anchor circle)
			)
			(primitives
				(gr_poly
					(pts
						(arc
							(start -0.1778 -0.2794)
							(mid -0.249642 -0.249642)
							(end -0.2794 -0.1778)
						)
						(arc
							(start -0.2794 0.1778)
							(mid -0.249642 0.249642)
							(end -0.1778 0.2794)
						)
						(arc
							(start 0.1778 0.2794)
							(mid 0.249642 0.249642)
							(end 0.2794 0.1778)
						)
						(arc
							(start 0.2794 -0.1778)
							(mid 0.249642 -0.249642)
							(end 0.1778 -0.2794)
						)
					)
					(width 0)
					(fill yes)
				)
			)
		)
		(pad "2" smd custom
			(at 0 0.4445 270)
			(size 0.1397 0.1397)
			(layers "F.Cu" "F.Mask" "F.Paste")
			(net "PWM_OUT_FAN4_NET")
			(options
				(clearance outline)
				(anchor circle)
			)
			(primitives
				(gr_poly
					(pts
						(arc
							(start -0.1778 -0.2794)
							(mid -0.249642 -0.249642)
							(end -0.2794 -0.1778)
						)
						(arc
							(start -0.2794 0.1778)
							(mid -0.249642 0.249642)
							(end -0.1778 0.2794)
						)
						(arc
							(start 0.1778 0.2794)
							(mid 0.249642 0.249642)
							(end 0.2794 0.1778)
						)
						(arc
							(start 0.2794 -0.1778)
							(mid 0.249642 -0.249642)
							(end 0.1778 -0.2794)
						)
					)
					(width 0)
					(fill yes)
				)
			)
		)
	)
	(footprint ""
		(layer "F.Cu")
		(at 43.9166 -106.2736 90)
		(property "Reference" "TC7"
			(at 0 0 90)
			(layer "F.SilkS")
			(hide yes)
			(effects
				(font
					(size 1.27 1.27)
				)
			)
		)
		(property "Value" "ST68U16VDM-1-GP"
			(at 0 -9.6012 90)
			(unlocked yes)
			(layer "F.Fab")
			(hide yes)
			(effects
				(font
					(size 1.016 1.016)
					(thickness 0.1524)
				)
			)
		)
		(property "Device Type" "CT7343H79"
			(at 0 -11.1252 90)
			(unlocked yes)
			(layer "F.Fab")
			(hide yes)
			(effects
				(font
					(size 1.016 1.016)
					(thickness 0.1524)
				)
			)
		)
		(duplicate_pad_numbers_are_jumpers no)
		(fp_line
			(start 2.286 -4.8768)
			(end -2.286 -4.8768)
			(stroke
				(width 0.1524)
				(type default)
			)
			(layer "F.SilkS")
		)
		(fp_line
			(start -2.286 -4.8768)
			(end -2.286 -2.032)
			(stroke
				(width 0.1524)
				(type default)
			)
			(layer "F.SilkS")
		)
		(fp_line
			(start 2.1082 -4.699)
			(end -2.1082 -4.699)
			(stroke
				(width 0.508)
				(type default)
			)
			(layer "F.SilkS")
		)
		(fp_line
			(start 2.286 -2.032)
			(end 2.286 -4.8768)
			(stroke
				(width 0.1524)
				(type default)
			)
			(layer "F.SilkS")
		)
		(fp_line
			(start 2.286 2.032)
			(end 2.286 4.8768)
			(stroke
				(width 0.1524)
				(type default)
			)
			(layer "F.SilkS")
		)
		(fp_line
			(start 2.286 4.8768)
			(end -2.286 4.8768)
			(stroke
				(width 0.1524)
				(type default)
			)
			(layer "F.SilkS")
		)
		(fp_line
			(start -2.286 4.8768)
			(end -2.286 2.032)
			(stroke
				(width 0.1524)
				(type default)
			)
			(layer "F.SilkS")
		)
		(fp_rect
			(start -2.1463 3.6449)
			(end 2.1463 -3.6449)
			(stroke
				(width 0)
				(type default)
			)
			(fill no)
			(layer "F.CrtYd")
		)
		(fp_poly
			(pts
				(xy -2.54 4.953) (xy -2.54 4.2926) (xy -3.81 4.2926) (xy -3.81 -4.2926) (xy -2.54 -4.2926) (xy -2.54 -4.953)
				(xy 2.54 -4.953) (xy 2.54 -4.2926) (xy 3.81 -4.2926) (xy 3.81 -1.6256) (xy 2.1463 -1.6256) (xy 2.1463 -3.6449)
				(xy -2.1463 -3.6449) (xy -2.1463 3.6449) (xy 2.1463 3.6449) (xy 2.1463 -1.6129) (xy 3.81 -1.6129)
				(xy 3.81 4.2926) (xy 2.54 4.2926) (xy 2.54 4.953)
			)
			(stroke
				(width 0)
				(type default)
			)
			(fill no)
			(layer "F.CrtYd")
		)
		(fp_rect
			(start 2.54 4.2926)
			(end 3.81 -4.2926)
			(stroke
				(width 0)
				(type default)
			)
			(fill no)
			(layer "F.Fab")
		)
		(fp_rect
			(start -3.81 4.2926)
			(end -2.54 -4.2926)
			(stroke
				(width 0)
				(type default)
			)
			(fill no)
			(layer "F.Fab")
		)
		(fp_rect
			(start -2.54 4.953)
			(end 2.54 -4.953)
			(stroke
				(width 0)
				(type default)
			)
			(fill no)
			(layer "F.Fab")
		)
		(pad "1" smd rect
			(at 0 -3.1496 90)
			(size 2.413 2.286)
			(layers "F.Cu" "F.Mask" "F.Paste")
			(net "P12VL")
		)
		(pad "2" smd rect
			(at 0 3.1496 90)
			(size 2.413 2.286)
			(layers "F.Cu" "F.Mask" "F.Paste")
			(net "GND")
		)
		(zone
			(layer "F.Cu")
			(hatch none 0.5)
			(connect_pads
				(clearance 0)
			)
			(min_thickness 0.25)
			(keepout
				(tracks allowed)
				(vias not_allowed)
				(pads allowed)
				(copperpour not_allowed)
				(footprints allowed)
			)
			(placement
				(enabled no)
				(sheetname "")
			)
			(fill
				(thermal_gap 0.5)
				(thermal_bridge_width 0.5)
				(island_removal_mode 0)
			)
			(polygon
				(pts
					(xy 42.2275 -107.7849) (xy 39.3192 -107.7849) (xy 39.3192 -104.7623) (xy 42.2148 -104.7623) (xy 42.545 -104.7623)
					(xy 42.545 -107.7849)
				)
			)
		)
		(zone
			(layer "F.Cu")
			(hatch none 0.5)
			(connect_pads
				(clearance 0)
			)
			(min_thickness 0.25)
			(keepout
				(tracks allowed)
				(vias not_allowed)
				(pads allowed)
				(copperpour not_allowed)
				(footprints allowed)
			)
			(placement
				(enabled no)
				(sheetname "")
			)
			(fill
				(thermal_gap 0.5)
				(thermal_bridge_width 0.5)
				(island_removal_mode 0)
			)
			(polygon
				(pts
					(xy 48.514 -104.7623) (xy 48.514 -107.7849) (xy 45.6184 -107.7849) (xy 45.2882 -107.7849) (xy 45.2882 -104.7623)
					(xy 45.6184 -104.7623)
				)
			)
		)
	)
	(footprint ""
		(layer "F.Cu")
		(at 29.1592 -253.8984 180)
		(property "Reference" "R45"
			(at 0 0 180)
			(layer "F.SilkS")
			(hide yes)
			(effects
				(font
					(size 1.27 1.27)
				)
			)
		)
		(property "Value" "0R2J-2-GP"
			(at 0.064008 -3.993896 180)
			(unlocked yes)
			(layer "F.Fab")
			(hide yes)
			(effects
				(font
					(size 1.016 1.016)
					(thickness 0.1524)
				)
			)
		)
		(property "Device Type" "R402H16"
			(at 0.064008 -5.517896 180)
			(unlocked yes)
			(layer "F.Fab")
			(hide yes)
			(effects
				(font
					(size 1.016 1.016)
					(thickness 0.1524)
				)
			)
		)
		(duplicate_pad_numbers_are_jumpers no)
		(fp_line
			(start 0.508 -0.9398)
			(end -0.508 -0.9398)
			(stroke
				(width 0.1524)
				(type default)
			)
			(layer "F.SilkS")
		)
		(fp_line
			(start -0.508 -0.9398)
			(end -0.508 0.9398)
			(stroke
				(width 0.1524)
				(type default)
			)
			(layer "F.SilkS")
		)
		(fp_rect
			(start -0.508 0.9398)
			(end 0.508 -0.9398)
			(stroke
				(width 0)
				(type default)
			)
			(fill no)
			(layer "F.CrtYd")
		)
		(fp_rect
			(start -0.508 0.9398)
			(end 0.508 -0.9398)
			(stroke
				(width 0)
				(type default)
			)
			(fill no)
			(layer "F.Fab")
		)
		(pad "1" smd custom
			(at 0 -0.4445 180)
			(size 0.1397 0.1397)
			(layers "F.Cu" "F.Mask" "F.Paste")
			(net "EEPROM_WP")
			(options
				(clearance outline)
				(anchor circle)
			)
			(primitives
				(gr_poly
					(pts
						(arc
							(start -0.1778 -0.2794)
							(mid -0.249642 -0.249642)
							(end -0.2794 -0.1778)
						)
						(arc
							(start -0.2794 0.1778)
							(mid -0.249642 0.249642)
							(end -0.1778 0.2794)
						)
						(arc
							(start 0.1778 0.2794)
							(mid 0.249642 0.249642)
							(end 0.2794 0.1778)
						)
						(arc
							(start 0.2794 -0.1778)
							(mid 0.249642 -0.249642)
							(end 0.1778 -0.2794)
						)
					)
					(width 0)
					(fill yes)
				)
			)
		)
		(pad "2" smd custom
			(at 0 0.4445 180)
			(size 0.1397 0.1397)
			(layers "F.Cu" "F.Mask" "F.Paste")
			(net "GND")
			(options
				(clearance outline)
				(anchor circle)
			)
			(primitives
				(gr_poly
					(pts
						(arc
							(start -0.1778 -0.2794)
							(mid -0.249642 -0.249642)
							(end -0.2794 -0.1778)
						)
						(arc
							(start -0.2794 0.1778)
							(mid -0.249642 0.249642)
							(end -0.1778 0.2794)
						)
						(arc
							(start 0.1778 0.2794)
							(mid 0.249642 0.249642)
							(end 0.2794 0.1778)
						)
						(arc
							(start 0.2794 -0.1778)
							(mid 0.249642 -0.249642)
							(end 0.1778 -0.2794)
						)
					)
					(width 0)
					(fill yes)
				)
			)
		)
	)
	(footprint ""
		(layer "F.Cu")
		(at 27.500072 -320.000122 90)
		(property "Reference" "Q2"
			(at 0 0 90)
			(layer "F.SilkS")
			(hide yes)
			(effects
				(font
					(size 1.27 1.27)
				)
			)
		)
		(property "Value" "PMBS3904-1-GP"
			(at 0 -9.0932 90)
			(unlocked yes)
			(layer "F.Fab")
			(hide yes)
			(effects
				(font
					(size 1.016 1.016)
					(thickness 0.1524)
				)
			)
		)
		(property "Device Type" "SOT-23-10H44"
			(at 0 -10.6172 90)
			(unlocked yes)
			(layer "F.Fab")
			(hide yes)
			(effects
				(font
					(size 1.016 1.016)
					(thickness 0.1524)
				)
			)
		)
		(duplicate_pad_numbers_are_jumpers no)
		(fp_line
			(start 1.651 -1.778)
			(end -1.651 -1.778)
			(stroke
				(width 0.1524)
				(type default)
			)
			(layer "F.SilkS")
		)
		(fp_line
			(start -1.651 -1.778)
			(end -1.651 1.778)
			(stroke
				(width 0.1524)
				(type default)
			)
			(layer "F.SilkS")
		)
		(fp_line
			(start 1.651 1.778)
			(end 1.651 -1.778)
			(stroke
				(width 0.1524)
				(type default)
			)
			(layer "F.SilkS")
		)
		(fp_line
			(start -1.651 1.778)
			(end 1.651 1.778)
			(stroke
				(width 0.1524)
				(type default)
			)
			(layer "F.SilkS")
		)
		(fp_line
			(start -0.9906 1.86309)
			(end -0.701294 2.15265)
			(stroke
				(width 0.0127)
				(type default)
			)
			(layer "F.SilkS")
		)
		(fp_line
			(start -0.994156 1.8669)
			(end -0.987044 1.8669)
			(stroke
				(width 0.0127)
				(type default)
			)
			(layer "F.SilkS")
		)
		(fp_line
			(start -1.003808 1.876552)
			(end -0.977646 1.876552)
			(stroke
				(width 0.0127)
				(type default)
			)
			(layer "F.SilkS")
		)
		(fp_line
			(start -0.635 1.8796)
			(end -1.7526 1.8796)
			(stroke
				(width 0.3302)
				(type default)
			)
			(layer "F.SilkS")
		)
		(fp_line
			(start -1.7526 1.8796)
			(end -1.7526 0.9906)
			(stroke
				(width 0.3302)
				(type default)
			)
			(layer "F.SilkS")
		)
		(fp_line
			(start -1.013206 1.88595)
			(end -0.967994 1.88595)
			(stroke
				(width 0.0127)
				(type default)
			)
			(layer "F.SilkS")
		)
		(fp_line
			(start -1.022858 1.895602)
			(end -0.958596 1.895602)
			(stroke
				(width 0.0127)
				(type default)
			)
			(layer "F.SilkS")
		)
		(fp_line
			(start -1.032256 1.905)
			(end -0.948944 1.905)
			(stroke
				(width 0.0127)
				(type default)
			)
			(layer "F.SilkS")
		)
		(fp_line
			(start -1.041908 1.914652)
			(end -0.939546 1.914652)
			(stroke
				(width 0.0127)
				(type default)
			)
			(layer "F.SilkS")
		)
		(fp_line
			(start -1.051306 1.92405)
			(end -0.929894 1.92405)
			(stroke
				(width 0.0127)
				(type default)
			)
			(layer "F.SilkS")
		)
		(fp_line
			(start -1.060958 1.933702)
			(end -0.920496 1.933702)
			(stroke
				(width 0.0127)
				(type default)
			)
			(layer "F.SilkS")
		)
		(fp_line
			(start -1.070356 1.9431)
			(end -0.910844 1.9431)
			(stroke
				(width 0.0127)
				(type default)
			)
			(layer "F.SilkS")
		)
		(fp_line
			(start -1.080008 1.952752)
			(end -0.901446 1.952752)
			(stroke
				(width 0.0127)
				(type default)
			)
			(layer "F.SilkS")
		)
		(fp_line
			(start -1.089406 1.96215)
			(end -0.891794 1.96215)
			(stroke
				(width 0.0127)
				(type default)
			)
			(layer "F.SilkS")
		)
		(fp_line
			(start -1.099058 1.971802)
			(end -0.882396 1.971802)
			(stroke
				(width 0.0127)
				(type default)
			)
			(layer "F.SilkS")
		)
		(fp_line
			(start -1.108456 1.9812)
			(end -0.872744 1.9812)
			(stroke
				(width 0.0127)
				(type default)
			)
			(layer "F.SilkS")
		)
		(fp_line
			(start -1.118108 1.990852)
			(end -0.863346 1.990852)
			(stroke
				(width 0.0127)
				(type default)
			)
			(layer "F.SilkS")
		)
		(fp_line
			(start -1.127506 2.00025)
			(end -0.853694 2.00025)
			(stroke
				(width 0.0127)
				(type default)
			)
			(layer "F.SilkS")
		)
		(fp_line
			(start -1.137158 2.009902)
			(end -0.844296 2.009902)
			(stroke
				(width 0.0127)
				(type default)
			)
			(layer "F.SilkS")
		)
		(fp_line
			(start -1.146556 2.0193)
			(end -0.834644 2.0193)
			(stroke
				(width 0.0127)
				(type default)
			)
			(layer "F.SilkS")
		)
		(fp_line
			(start -1.156208 2.028952)
			(end -0.825246 2.028952)
			(stroke
				(width 0.0127)
				(type default)
			)
			(layer "F.SilkS")
		)
		(fp_line
			(start -1.165606 2.03835)
			(end -0.815594 2.03835)
			(stroke
				(width 0.0127)
				(type default)
			)
			(layer "F.SilkS")
		)
		(fp_line
			(start -1.175258 2.048002)
			(end -0.806196 2.048002)
			(stroke
				(width 0.0127)
				(type default)
			)
			(layer "F.SilkS")
		)
		(fp_line
			(start -1.184656 2.0574)
			(end -0.796544 2.0574)
			(stroke
				(width 0.0127)
				(type default)
			)
			(layer "F.SilkS")
		)
		(fp_line
			(start -1.194308 2.067052)
			(end -0.787146 2.067052)
			(stroke
				(width 0.0127)
				(type default)
			)
			(layer "F.SilkS")
		)
		(fp_line
			(start -1.203706 2.07645)
			(end -0.777494 2.07645)
			(stroke
				(width 0.0127)
				(type default)
			)
			(layer "F.SilkS")
		)
		(fp_line
			(start -1.213358 2.086102)
			(end -0.768096 2.086102)
			(stroke
				(width 0.0127)
				(type default)
			)
			(layer "F.SilkS")
		)
		(fp_line
			(start -1.222756 2.0955)
			(end -0.758444 2.0955)
			(stroke
				(width 0.0127)
				(type default)
			)
			(layer "F.SilkS")
		)
		(fp_line
			(start -1.232408 2.105152)
			(end -0.749046 2.105152)
			(stroke
				(width 0.0127)
				(type default)
			)
			(layer "F.SilkS")
		)
		(fp_line
			(start -1.241806 2.11455)
			(end -0.739394 2.11455)
			(stroke
				(width 0.0127)
				(type default)
			)
			(layer "F.SilkS")
		)
		(fp_line
			(start -1.251458 2.124202)
			(end -0.729996 2.124202)
			(stroke
				(width 0.0127)
				(type default)
			)
			(layer "F.SilkS")
		)
		(fp_line
			(start -1.260856 2.1336)
			(end -0.720344 2.1336)
			(stroke
				(width 0.0127)
				(type default)
			)
			(layer "F.SilkS")
		)
		(fp_line
			(start -0.719074 2.145538)
			(end -1.265936 2.14122)
			(stroke
				(width 0.0127)
				(type default)
			)
			(layer "F.SilkS")
		)
		(fp_line
			(start -1.279398 2.152142)
			(end -0.9906 1.86309)
			(stroke
				(width 0.0127)
				(type default)
			)
			(layer "F.SilkS")
		)
		(fp_line
			(start -0.71628 2.15265)
			(end -1.26492 2.15265)
			(stroke
				(width 0.0127)
				(type default)
			)
			(layer "F.SilkS")
		)
		(fp_line
			(start -1.279144 2.15265)
			(end -0.701294 2.15265)
			(stroke
				(width 0.0127)
				(type default)
			)
			(layer "F.SilkS")
		)
		(fp_poly
			(pts
				(xy -1.285748 2.159) (xy -1.285748 1.8796) (xy -1.778 1.8796) (xy -1.778 -1.8796) (xy 1.778 -1.8796)
				(xy 1.778 1.8796) (xy -0.694944 1.8796) (xy -0.694944 2.159)
			)
			(stroke
				(width 0)
				(type default)
			)
			(fill no)
			(layer "F.CrtYd")
		)
		(fp_poly
			(pts
				(xy -1.285748 2.159) (xy -1.285748 1.8796) (xy -1.778 1.8796) (xy -1.778 -1.8796) (xy 1.778 -1.8796)
				(xy 1.778 1.8796) (xy -0.694944 1.8796) (xy -0.694944 2.159)
			)
			(stroke
				(width 0)
				(type default)
			)
			(fill no)
			(layer "F.Fab")
		)
		(pad "1" smd rect
			(at -0.98425 0.9525 90)
			(size 0.762 1.143)
			(layers "F.Cu" "F.Mask" "F.Paste")
			(net "NCT7904_D2+")
		)
		(pad "2" smd rect
			(at 0.98425 0.9525 90)
			(size 0.762 1.143)
			(layers "F.Cu" "F.Mask" "F.Paste")
			(net "NCT7904_D2-")
		)
		(pad "3" smd rect
			(at 0 -0.9525 90)
			(size 0.762 1.143)
			(layers "F.Cu" "F.Mask" "F.Paste")
			(net "NCT7904_D2+")
		)
	)
	(footprint ""
		(layer "F.Cu")
		(at 47.625 -408.051 90)
		(property "Reference" "PC7"
			(at 0 0 90)
			(layer "F.SilkS")
			(hide yes)
			(effects
				(font
					(size 1.27 1.27)
				)
			)
		)
		(property "Value" "SC1U25V5KX-1GP"
			(at -0.0762 -6.1214 90)
			(unlocked yes)
			(layer "F.Fab")
			(hide yes)
			(effects
				(font
					(size 1.016 1.016)
					(thickness 0.1524)
				)
			)
		)
		(property "Device Type" "C805H58"
			(at -0.0762 -8.1534 90)
			(unlocked yes)
			(layer "F.Fab")
			(hide yes)
			(effects
				(font
					(size 1.016 1.016)
					(thickness 0.1524)
				)
			)
		)
		(duplicate_pad_numbers_are_jumpers no)
		(fp_line
			(start 0.635 0)
			(end -0.635 0)
			(stroke
				(width 0.508)
				(type default)
			)
			(layer "F.SilkS")
		)
		(fp_rect
			(start -0.9652 1.778)
			(end 0.9652 -1.778)
			(stroke
				(width 0)
				(type default)
			)
			(fill no)
			(layer "F.CrtYd")
		)
		(fp_poly
			(pts
				(xy -0.9652 -1.778) (xy 0.9652 -1.778) (xy 0.9652 1.778) (xy -0.9652 1.778)
			)
			(stroke
				(width 0)
				(type default)
			)
			(fill no)
			(layer "F.Fab")
		)
		(pad "1" smd rect
			(at 0 -0.9652 90)
			(size 1.397 1.143)
			(layers "F.Cu" "F.Mask" "F.Paste")
			(net "P12V_SENSE_TRACE")
		)
		(pad "2" smd rect
			(at 0 0.9652 90)
			(size 1.397 1.143)
			(layers "F.Cu" "F.Mask" "F.Paste")
			(net "GND")
		)
	)
	(footprint ""
		(layer "F.Cu")
		(at 21.844508 -192.505838)
		(property "Reference" "F3"
			(at 0 0 0)
			(layer "F.SilkS")
			(hide yes)
			(effects
				(font
					(size 1.27 1.27)
				)
			)
		)
		(property "Value" "FUSE-3A15V-GP"
			(at 0.2286 -10.5918 0)
			(unlocked yes)
			(layer "F.Fab")
			(hide yes)
			(effects
				(font
					(size 1.016 1.016)
					(thickness 0.1524)
				)
			)
		)
		(property "Device Type" "FUSE-7452-UH50"
			(at 0.2286 -12.4968 0)
			(unlocked yes)
			(layer "F.Fab")
			(hide yes)
			(effects
				(font
					(size 1.016 1.016)
					(thickness 0.1524)
				)
			)
		)
		(duplicate_pad_numbers_are_jumpers no)
		(fp_line
			(start -4.9276 -2.921)
			(end 4.9276 -2.921)
			(stroke
				(width 0.1524)
				(type default)
			)
			(layer "F.SilkS")
		)
		(fp_line
			(start -4.9276 2.921)
			(end -4.9276 -2.921)
			(stroke
				(width 0.1524)
				(type default)
			)
			(layer "F.SilkS")
		)
		(fp_line
			(start 4.9276 -2.921)
			(end 4.9276 2.921)
			(stroke
				(width 0.1524)
				(type default)
			)
			(layer "F.SilkS")
		)
		(fp_line
			(start 4.9276 2.921)
			(end -4.9276 2.921)
			(stroke
				(width 0.1524)
				(type default)
			)
			(layer "F.SilkS")
		)
		(fp_poly
			(pts
				(xy -5.08 3.0988) (xy 5.08 3.0988) (xy 5.08 -3.0988) (xy -5.08 -3.0988)
			)
			(stroke
				(width 0)
				(type default)
			)
			(fill no)
			(layer "F.CrtYd")
		)
		(fp_poly
			(pts
				(xy -5.08 -3.0988) (xy 5.08 -3.0988) (xy 5.08 3.0988) (xy -5.08 3.0988)
			)
			(stroke
				(width 0)
				(type default)
			)
			(fill no)
			(layer "F.Fab")
		)
		(pad "1" smd rect
			(at -3.4036 0)
			(size 2.2098 5.2832)
			(layers "F.Cu" "F.Mask" "F.Paste")
			(net "P12V_FAN4")
		)
		(pad "2" smd rect
			(at 3.4036 0)
			(size 2.2098 5.2832)
			(layers "F.Cu" "F.Mask" "F.Paste")
			(net "P12V")
		)
	)
	(footprint ""
		(layer "F.Cu")
		(at 25.018238 -481.735892 -90)
		(property "Reference" "F6"
			(at 0 0 270)
			(layer "F.SilkS")
			(hide yes)
			(effects
				(font
					(size 1.27 1.27)
				)
			)
		)
		(property "Value" "FUSE-3A15V-GP"
			(at 0.2286 -10.5918 270)
			(unlocked yes)
			(layer "F.Fab")
			(hide yes)
			(effects
				(font
					(size 1.016 1.016)
					(thickness 0.1524)
				)
			)
		)
		(property "Device Type" "FUSE-7452-UH50"
			(at 0.2286 -12.4968 270)
			(unlocked yes)
			(layer "F.Fab")
			(hide yes)
			(effects
				(font
					(size 1.016 1.016)
					(thickness 0.1524)
				)
			)
		)
		(duplicate_pad_numbers_are_jumpers no)
		(fp_line
			(start -4.9276 2.921)
			(end -4.9276 -2.921)
			(stroke
				(width 0.1524)
				(type default)
			)
			(layer "F.SilkS")
		)
		(fp_line
			(start 4.9276 2.921)
			(end -4.9276 2.921)
			(stroke
				(width 0.1524)
				(type default)
			)
			(layer "F.SilkS")
		)
		(fp_line
			(start -4.9276 -2.921)
			(end 4.9276 -2.921)
			(stroke
				(width 0.1524)
				(type default)
			)
			(layer "F.SilkS")
		)
		(fp_line
			(start 4.9276 -2.921)
			(end 4.9276 2.921)
			(stroke
				(width 0.1524)
				(type default)
			)
			(layer "F.SilkS")
		)
		(fp_poly
			(pts
				(xy -5.08 3.0988) (xy 5.08 3.0988) (xy 5.08 -3.0988) (xy -5.08 -3.0988)
			)
			(stroke
				(width 0)
				(type default)
			)
			(fill no)
			(layer "F.CrtYd")
		)
		(fp_poly
			(pts
				(xy -5.08 -3.0988) (xy 5.08 -3.0988) (xy 5.08 3.0988) (xy -5.08 3.0988)
			)
			(stroke
				(width 0)
				(type default)
			)
			(fill no)
			(layer "F.Fab")
		)
		(pad "1" smd rect
			(at -3.4036 0 270)
			(size 2.2098 5.2832)
			(layers "F.Cu" "F.Mask" "F.Paste")
			(net "P12V_FAN1")
		)
		(pad "2" smd rect
			(at 3.4036 0 270)
			(size 2.2098 5.2832)
			(layers "F.Cu" "F.Mask" "F.Paste")
			(net "P12V")
		)
	)
	(footprint ""
		(layer "F.Cu")
		(at 39.243 -174.117)
		(property "Reference" "PR44"
			(at 0 0 0)
			(layer "F.SilkS")
			(hide yes)
			(effects
				(font
					(size 1.27 1.27)
				)
			)
		)
		(property "Value" "1KR2F-3-GP"
			(at 0.064008 -3.993896 0)
			(unlocked yes)
			(layer "F.Fab")
			(hide yes)
			(effects
				(font
					(size 1.016 1.016)
					(thickness 0.1524)
				)
			)
		)
		(property "Device Type" "R402H16"
			(at 0.064008 -5.517896 0)
			(unlocked yes)
			(layer "F.Fab")
			(hide yes)
			(effects
				(font
					(size 1.016 1.016)
					(thickness 0.1524)
				)
			)
		)
		(duplicate_pad_numbers_are_jumpers no)
		(fp_line
			(start -0.508 -0.9398)
			(end -0.508 0.9398)
			(stroke
				(width 0.1524)
				(type default)
			)
			(layer "F.SilkS")
		)
		(fp_line
			(start 0.508 -0.9398)
			(end -0.508 -0.9398)
			(stroke
				(width 0.1524)
				(type default)
			)
			(layer "F.SilkS")
		)
		(fp_rect
			(start -0.508 0.9398)
			(end 0.508 -0.9398)
			(stroke
				(width 0)
				(type default)
			)
			(fill no)
			(layer "F.CrtYd")
		)
		(fp_rect
			(start -0.508 0.9398)
			(end 0.508 -0.9398)
			(stroke
				(width 0)
				(type default)
			)
			(fill no)
			(layer "F.Fab")
		)
		(pad "1" smd custom
			(at 0 -0.4445)
			(size 0.1397 0.1397)
			(layers "F.Cu" "F.Mask" "F.Paste")
			(net "TEMP_ALM#")
			(options
				(clearance outline)
				(anchor circle)
			)
			(primitives
				(gr_poly
					(pts
						(arc
							(start -0.1778 -0.2794)
							(mid -0.249642 -0.249642)
							(end -0.2794 -0.1778)
						)
						(arc
							(start -0.2794 0.1778)
							(mid -0.249642 0.249642)
							(end -0.1778 0.2794)
						)
						(arc
							(start 0.1778 0.2794)
							(mid 0.249642 0.249642)
							(end 0.2794 0.1778)
						)
						(arc
							(start 0.2794 -0.1778)
							(mid 0.249642 -0.249642)
							(end 0.1778 -0.2794)
						)
					)
					(width 0)
					(fill yes)
				)
			)
		)
		(pad "2" smd custom
			(at 0 0.4445)
			(size 0.1397 0.1397)
			(layers "F.Cu" "F.Mask" "F.Paste")
			(net "TEMP_ALM#_IN")
			(options
				(clearance outline)
				(anchor circle)
			)
			(primitives
				(gr_poly
					(pts
						(arc
							(start -0.1778 -0.2794)
							(mid -0.249642 -0.249642)
							(end -0.2794 -0.1778)
						)
						(arc
							(start -0.2794 0.1778)
							(mid -0.249642 0.249642)
							(end -0.1778 0.2794)
						)
						(arc
							(start 0.1778 0.2794)
							(mid 0.249642 0.249642)
							(end 0.2794 0.1778)
						)
						(arc
							(start 0.2794 -0.1778)
							(mid 0.249642 -0.249642)
							(end 0.1778 -0.2794)
						)
					)
					(width 0)
					(fill yes)
				)
			)
		)
	)
	(footprint ""
		(layer "F.Cu")
		(at 41.7576 -158.1658 90)
		(property "Reference" "R50"
			(at 0 0 90)
			(layer "F.SilkS")
			(hide yes)
			(effects
				(font
					(size 1.27 1.27)
				)
			)
		)
		(property "Value" "0R2J-2-GP"
			(at 0.064008 -3.993896 90)
			(unlocked yes)
			(layer "F.Fab")
			(hide yes)
			(effects
				(font
					(size 1.016 1.016)
					(thickness 0.1524)
				)
			)
		)
		(property "Device Type" "R402H16"
			(at 0.064008 -5.517896 90)
			(unlocked yes)
			(layer "F.Fab")
			(hide yes)
			(effects
				(font
					(size 1.016 1.016)
					(thickness 0.1524)
				)
			)
		)
		(duplicate_pad_numbers_are_jumpers no)
		(fp_line
			(start 0.508 -0.9398)
			(end -0.508 -0.9398)
			(stroke
				(width 0.1524)
				(type default)
			)
			(layer "F.SilkS")
		)
		(fp_line
			(start -0.508 -0.9398)
			(end -0.508 0.9398)
			(stroke
				(width 0.1524)
				(type default)
			)
			(layer "F.SilkS")
		)
		(fp_rect
			(start -0.508 0.9398)
			(end 0.508 -0.9398)
			(stroke
				(width 0)
				(type default)
			)
			(fill no)
			(layer "F.CrtYd")
		)
		(fp_rect
			(start -0.508 0.9398)
			(end 0.508 -0.9398)
			(stroke
				(width 0)
				(type default)
			)
			(fill no)
			(layer "F.Fab")
		)
		(pad "1" smd custom
			(at 0 -0.4445 90)
			(size 0.1397 0.1397)
			(layers "F.Cu" "F.Mask" "F.Paste")
			(net "NCT7904_VSEN1")
			(options
				(clearance outline)
				(anchor circle)
			)
			(primitives
				(gr_poly
					(pts
						(arc
							(start -0.1778 -0.2794)
							(mid -0.249642 -0.249642)
							(end -0.2794 -0.1778)
						)
						(arc
							(start -0.2794 0.1778)
							(mid -0.249642 0.249642)
							(end -0.1778 0.2794)
						)
						(arc
							(start 0.1778 0.2794)
							(mid 0.249642 0.249642)
							(end 0.2794 0.1778)
						)
						(arc
							(start 0.2794 -0.1778)
							(mid 0.249642 -0.249642)
							(end 0.1778 -0.2794)
						)
					)
					(width 0)
					(fill yes)
				)
			)
		)
		(pad "2" smd custom
			(at 0 0.4445 90)
			(size 0.1397 0.1397)
			(layers "F.Cu" "F.Mask" "F.Paste")
			(net "NCT7904_VSEN_P12V_AUX")
			(options
				(clearance outline)
				(anchor circle)
			)
			(primitives
				(gr_poly
					(pts
						(arc
							(start -0.1778 -0.2794)
							(mid -0.249642 -0.249642)
							(end -0.2794 -0.1778)
						)
						(arc
							(start -0.2794 0.1778)
							(mid -0.249642 0.249642)
							(end -0.1778 0.2794)
						)
						(arc
							(start 0.1778 0.2794)
							(mid 0.249642 0.249642)
							(end 0.2794 0.1778)
						)
						(arc
							(start 0.2794 -0.1778)
							(mid 0.249642 -0.249642)
							(end 0.1778 -0.2794)
						)
					)
					(width 0)
					(fill yes)
				)
			)
		)
	)
	(footprint ""
		(layer "F.Cu")
		(at 23.622 -368.554 90)
		(property "Reference" "PR35"
			(at 0 0 90)
			(layer "F.SilkS")
			(hide yes)
			(effects
				(font
					(size 1.27 1.27)
				)
			)
		)
		(property "Value" "4K7R2J-2-GP"
			(at 0.064008 -3.993896 90)
			(unlocked yes)
			(layer "F.Fab")
			(hide yes)
			(effects
				(font
					(size 1.016 1.016)
					(thickness 0.1524)
				)
			)
		)
		(property "Device Type" "R402H16"
			(at 0.064008 -5.517896 90)
			(unlocked yes)
			(layer "F.Fab")
			(hide yes)
			(effects
				(font
					(size 1.016 1.016)
					(thickness 0.1524)
				)
			)
		)
		(duplicate_pad_numbers_are_jumpers no)
		(fp_line
			(start 0.508 -0.9398)
			(end -0.508 -0.9398)
			(stroke
				(width 0.1524)
				(type default)
			)
			(layer "F.SilkS")
		)
		(fp_line
			(start -0.508 -0.9398)
			(end -0.508 0.9398)
			(stroke
				(width 0.1524)
				(type default)
			)
			(layer "F.SilkS")
		)
		(fp_rect
			(start -0.508 0.9398)
			(end 0.508 -0.9398)
			(stroke
				(width 0)
				(type default)
			)
			(fill no)
			(layer "F.CrtYd")
		)
		(fp_rect
			(start -0.508 0.9398)
			(end 0.508 -0.9398)
			(stroke
				(width 0)
				(type default)
			)
			(fill no)
			(layer "F.Fab")
		)
		(pad "1" smd custom
			(at 0 -0.4445 90)
			(size 0.1397 0.1397)
			(layers "F.Cu" "F.Mask" "F.Paste")
			(net "ADM1276_UV")
			(options
				(clearance outline)
				(anchor circle)
			)
			(primitives
				(gr_poly
					(pts
						(arc
							(start -0.1778 -0.2794)
							(mid -0.249642 -0.249642)
							(end -0.2794 -0.1778)
						)
						(arc
							(start -0.2794 0.1778)
							(mid -0.249642 0.249642)
							(end -0.1778 0.2794)
						)
						(arc
							(start 0.1778 0.2794)
							(mid 0.249642 0.249642)
							(end 0.2794 0.1778)
						)
						(arc
							(start 0.2794 -0.1778)
							(mid 0.249642 -0.249642)
							(end 0.1778 -0.2794)
						)
					)
					(width 0)
					(fill yes)
				)
			)
		)
		(pad "2" smd custom
			(at 0 0.4445 90)
			(size 0.1397 0.1397)
			(layers "F.Cu" "F.Mask" "F.Paste")
			(net "ADM1276_VCAP")
			(options
				(clearance outline)
				(anchor circle)
			)
			(primitives
				(gr_poly
					(pts
						(arc
							(start -0.1778 -0.2794)
							(mid -0.249642 -0.249642)
							(end -0.2794 -0.1778)
						)
						(arc
							(start -0.2794 0.1778)
							(mid -0.249642 0.249642)
							(end -0.1778 0.2794)
						)
						(arc
							(start 0.1778 0.2794)
							(mid 0.249642 0.249642)
							(end 0.2794 0.1778)
						)
						(arc
							(start 0.2794 -0.1778)
							(mid 0.249642 -0.249642)
							(end 0.1778 -0.2794)
						)
					)
					(width 0)
					(fill yes)
				)
			)
		)
	)
	(footprint ""
		(layer "F.Cu")
		(at 18.7452 -250.5964 -90)
		(property "Reference" "PR53"
			(at 0 0 270)
			(layer "F.SilkS")
			(hide yes)
			(effects
				(font
					(size 1.27 1.27)
				)
			)
		)
		(property "Value" "10KR3J-L1-GP"
			(at -0.0254 -2.5146 270)
			(unlocked yes)
			(layer "F.Fab")
			(hide yes)
			(effects
				(font
					(size 1.016 1.016)
					(thickness 0.1524)
				)
			)
		)
		(property "Device Type" "R603H22"
			(at -0.0254 -4.0386 270)
			(unlocked yes)
			(layer "F.Fab")
			(hide yes)
			(effects
				(font
					(size 1.016 1.016)
					(thickness 0.1524)
				)
			)
		)
		(duplicate_pad_numbers_are_jumpers no)
		(fp_line
			(start -0.4826 0)
			(end -0.2032 0)
			(stroke
				(width 0.2032)
				(type default)
			)
			(layer "F.SilkS")
		)
		(fp_line
			(start 0.2032 0)
			(end 0.4826 0)
			(stroke
				(width 0.2032)
				(type default)
			)
			(layer "F.SilkS")
		)
		(fp_rect
			(start -0.5842 1.3335)
			(end 0.5842 -1.3335)
			(stroke
				(width 0)
				(type default)
			)
			(fill no)
			(layer "F.CrtYd")
		)
		(fp_rect
			(start -0.5842 1.3335)
			(end 0.5842 -1.3335)
			(stroke
				(width 0)
				(type default)
			)
			(fill no)
			(layer "F.Fab")
		)
		(pad "1" smd custom
			(at 0 -0.762 270)
			(size 0.2159 0.2159)
			(layers "F.Cu" "F.Mask" "F.Paste")
			(net "P3V3_EN")
			(options
				(clearance outline)
				(anchor circle)
			)
			(primitives
				(gr_poly
					(pts
						(arc
							(start -0.3302 -0.4318)
							(mid -0.402042 -0.402042)
							(end -0.4318 -0.3302)
						)
						(arc
							(start -0.4318 0.3302)
							(mid -0.402042 0.402042)
							(end -0.3302 0.4318)
						)
						(arc
							(start 0.3302 0.4318)
							(mid 0.402042 0.402042)
							(end 0.4318 0.3302)
						)
						(arc
							(start 0.4318 -0.3302)
							(mid 0.402042 -0.402042)
							(end 0.3302 -0.4318)
						)
					)
					(width 0)
					(fill yes)
				)
			)
		)
		(pad "2" smd custom
			(at 0 0.762 270)
			(size 0.2159 0.2159)
			(layers "F.Cu" "F.Mask" "F.Paste")
			(net "GND")
			(options
				(clearance outline)
				(anchor circle)
			)
			(primitives
				(gr_poly
					(pts
						(arc
							(start -0.3302 -0.4318)
							(mid -0.402042 -0.402042)
							(end -0.4318 -0.3302)
						)
						(arc
							(start -0.4318 0.3302)
							(mid -0.402042 0.402042)
							(end -0.3302 0.4318)
						)
						(arc
							(start 0.3302 0.4318)
							(mid 0.402042 0.402042)
							(end 0.4318 0.3302)
						)
						(arc
							(start 0.4318 -0.3302)
							(mid 0.402042 -0.402042)
							(end 0.3302 -0.4318)
						)
					)
					(width 0)
					(fill yes)
				)
			)
		)
	)
	(footprint ""
		(layer "F.Cu")
		(at 16.002 -67.564)
		(property "Reference" "R60"
			(at 0 0 0)
			(layer "F.SilkS")
			(hide yes)
			(effects
				(font
					(size 1.27 1.27)
				)
			)
		)
		(property "Value" "4K7R2F-GP"
			(at 0.064008 -3.993896 0)
			(unlocked yes)
			(layer "F.Fab")
			(hide yes)
			(effects
				(font
					(size 1.016 1.016)
					(thickness 0.1524)
				)
			)
		)
		(property "Device Type" "R402H16"
			(at 0.064008 -5.517896 0)
			(unlocked yes)
			(layer "F.Fab")
			(hide yes)
			(effects
				(font
					(size 1.016 1.016)
					(thickness 0.1524)
				)
			)
		)
		(duplicate_pad_numbers_are_jumpers no)
		(fp_line
			(start -0.508 -0.9398)
			(end -0.508 0.9398)
			(stroke
				(width 0.1524)
				(type default)
			)
			(layer "F.SilkS")
		)
		(fp_line
			(start 0.508 -0.9398)
			(end -0.508 -0.9398)
			(stroke
				(width 0.1524)
				(type default)
			)
			(layer "F.SilkS")
		)
		(fp_rect
			(start -0.508 0.9398)
			(end 0.508 -0.9398)
			(stroke
				(width 0)
				(type default)
			)
			(fill no)
			(layer "F.CrtYd")
		)
		(fp_rect
			(start -0.508 0.9398)
			(end 0.508 -0.9398)
			(stroke
				(width 0)
				(type default)
			)
			(fill no)
			(layer "F.Fab")
		)
		(pad "1" smd custom
			(at 0 -0.4445)
			(size 0.1397 0.1397)
			(layers "F.Cu" "F.Mask" "F.Paste")
			(net "P3V3")
			(options
				(clearance outline)
				(anchor circle)
			)
			(primitives
				(gr_poly
					(pts
						(arc
							(start -0.1778 -0.2794)
							(mid -0.249642 -0.249642)
							(end -0.2794 -0.1778)
						)
						(arc
							(start -0.2794 0.1778)
							(mid -0.249642 0.249642)
							(end -0.1778 0.2794)
						)
						(arc
							(start 0.1778 0.2794)
							(mid 0.249642 0.249642)
							(end 0.2794 0.1778)
						)
						(arc
							(start 0.2794 -0.1778)
							(mid 0.249642 -0.249642)
							(end 0.1778 -0.2794)
						)
					)
					(width 0)
					(fill yes)
				)
			)
		)
		(pad "2" smd custom
			(at 0 0.4445)
			(size 0.1397 0.1397)
			(layers "F.Cu" "F.Mask" "F.Paste")
			(net "I2C_C_SDA_CONN_R")
			(options
				(clearance outline)
				(anchor circle)
			)
			(primitives
				(gr_poly
					(pts
						(arc
							(start -0.1778 -0.2794)
							(mid -0.249642 -0.249642)
							(end -0.2794 -0.1778)
						)
						(arc
							(start -0.2794 0.1778)
							(mid -0.249642 0.249642)
							(end -0.1778 0.2794)
						)
						(arc
							(start 0.1778 0.2794)
							(mid 0.249642 0.249642)
							(end 0.2794 0.1778)
						)
						(arc
							(start 0.2794 -0.1778)
							(mid 0.249642 -0.249642)
							(end 0.1778 -0.2794)
						)
					)
					(width 0)
					(fill yes)
				)
			)
		)
	)
	(footprint ""
		(layer "F.Cu")
		(at 43.8404 -394.1064 90)
		(property "Reference" "TC10"
			(at 0 0 90)
			(layer "F.SilkS")
			(hide yes)
			(effects
				(font
					(size 1.27 1.27)
				)
			)
		)
		(property "Value" "ST68U16VDM-1-GP"
			(at 0 -9.6012 90)
			(unlocked yes)
			(layer "F.Fab")
			(hide yes)
			(effects
				(font
					(size 1.016 1.016)
					(thickness 0.1524)
				)
			)
		)
		(property "Device Type" "CT7343H79"
			(at 0 -11.1252 90)
			(unlocked yes)
			(layer "F.Fab")
			(hide yes)
			(effects
				(font
					(size 1.016 1.016)
					(thickness 0.1524)
				)
			)
		)
		(duplicate_pad_numbers_are_jumpers no)
		(fp_line
			(start 2.286 -4.8768)
			(end -2.286 -4.8768)
			(stroke
				(width 0.1524)
				(type default)
			)
			(layer "F.SilkS")
		)
		(fp_line
			(start -2.286 -4.8768)
			(end -2.286 -2.032)
			(stroke
				(width 0.1524)
				(type default)
			)
			(layer "F.SilkS")
		)
		(fp_line
			(start 2.1082 -4.699)
			(end -2.1082 -4.699)
			(stroke
				(width 0.508)
				(type default)
			)
			(layer "F.SilkS")
		)
		(fp_line
			(start 2.286 -2.032)
			(end 2.286 -4.8768)
			(stroke
				(width 0.1524)
				(type default)
			)
			(layer "F.SilkS")
		)
		(fp_line
			(start 2.286 2.032)
			(end 2.286 4.8768)
			(stroke
				(width 0.1524)
				(type default)
			)
			(layer "F.SilkS")
		)
		(fp_line
			(start 2.286 4.8768)
			(end -2.286 4.8768)
			(stroke
				(width 0.1524)
				(type default)
			)
			(layer "F.SilkS")
		)
		(fp_line
			(start -2.286 4.8768)
			(end -2.286 2.032)
			(stroke
				(width 0.1524)
				(type default)
			)
			(layer "F.SilkS")
		)
		(fp_rect
			(start -2.1463 3.6449)
			(end 2.1463 -3.6449)
			(stroke
				(width 0)
				(type default)
			)
			(fill no)
			(layer "F.CrtYd")
		)
		(fp_poly
			(pts
				(xy -2.54 4.953) (xy -2.54 4.2926) (xy -3.81 4.2926) (xy -3.81 -4.2926) (xy -2.54 -4.2926) (xy -2.54 -4.953)
				(xy 2.54 -4.953) (xy 2.54 -4.2926) (xy 3.81 -4.2926) (xy 3.81 -1.6256) (xy 2.1463 -1.6256) (xy 2.1463 -3.6449)
				(xy -2.1463 -3.6449) (xy -2.1463 3.6449) (xy 2.1463 3.6449) (xy 2.1463 -1.6129) (xy 3.81 -1.6129)
				(xy 3.81 4.2926) (xy 2.54 4.2926) (xy 2.54 4.953)
			)
			(stroke
				(width 0)
				(type default)
			)
			(fill no)
			(layer "F.CrtYd")
		)
		(fp_rect
			(start 2.54 4.2926)
			(end 3.81 -4.2926)
			(stroke
				(width 0)
				(type default)
			)
			(fill no)
			(layer "F.Fab")
		)
		(fp_rect
			(start -3.81 4.2926)
			(end -2.54 -4.2926)
			(stroke
				(width 0)
				(type default)
			)
			(fill no)
			(layer "F.Fab")
		)
		(fp_rect
			(start -2.54 4.953)
			(end 2.54 -4.953)
			(stroke
				(width 0)
				(type default)
			)
			(fill no)
			(layer "F.Fab")
		)
		(pad "1" smd rect
			(at 0 -3.1496 90)
			(size 2.413 2.286)
			(layers "F.Cu" "F.Mask" "F.Paste")
			(net "P12V")
		)
		(pad "2" smd rect
			(at 0 3.1496 90)
			(size 2.413 2.286)
			(layers "F.Cu" "F.Mask" "F.Paste")
			(net "GND")
		)
		(zone
			(layer "F.Cu")
			(hatch none 0.5)
			(connect_pads
				(clearance 0)
			)
			(min_thickness 0.25)
			(keepout
				(tracks allowed)
				(vias not_allowed)
				(pads allowed)
				(copperpour not_allowed)
				(footprints allowed)
			)
			(placement
				(enabled no)
				(sheetname "")
			)
			(fill
				(thermal_gap 0.5)
				(thermal_bridge_width 0.5)
				(island_removal_mode 0)
			)
			(polygon
				(pts
					(xy 42.1513 -395.6177) (xy 39.243 -395.6177) (xy 39.243 -392.5951) (xy 42.1386 -392.5951) (xy 42.4688 -392.5951)
					(xy 42.4688 -395.6177)
				)
			)
		)
		(zone
			(layer "F.Cu")
			(hatch none 0.5)
			(connect_pads
				(clearance 0)
			)
			(min_thickness 0.25)
			(keepout
				(tracks allowed)
				(vias not_allowed)
				(pads allowed)
				(copperpour not_allowed)
				(footprints allowed)
			)
			(placement
				(enabled no)
				(sheetname "")
			)
			(fill
				(thermal_gap 0.5)
				(thermal_bridge_width 0.5)
				(island_removal_mode 0)
			)
			(polygon
				(pts
					(xy 48.4378 -392.5951) (xy 48.4378 -395.6177) (xy 45.5422 -395.6177) (xy 45.212 -395.6177) (xy 45.212 -392.5951)
					(xy 45.5422 -392.5951)
				)
			)
		)
	)
	(footprint ""
		(layer "F.Cu")
		(at 18.644362 -157.505908 90)
		(property "Reference" "F2"
			(at 0 0 90)
			(layer "F.SilkS")
			(hide yes)
			(effects
				(font
					(size 1.27 1.27)
				)
			)
		)
		(property "Value" "FUSE-3A15V-GP"
			(at 0.2286 -10.5918 90)
			(unlocked yes)
			(layer "F.Fab")
			(hide yes)
			(effects
				(font
					(size 1.016 1.016)
					(thickness 0.1524)
				)
			)
		)
		(property "Device Type" "FUSE-7452-UH50"
			(at 0.2286 -12.4968 90)
			(unlocked yes)
			(layer "F.Fab")
			(hide yes)
			(effects
				(font
					(size 1.016 1.016)
					(thickness 0.1524)
				)
			)
		)
		(duplicate_pad_numbers_are_jumpers no)
		(fp_line
			(start 4.9276 -2.921)
			(end 4.9276 2.921)
			(stroke
				(width 0.1524)
				(type default)
			)
			(layer "F.SilkS")
		)
		(fp_line
			(start -4.9276 -2.921)
			(end 4.9276 -2.921)
			(stroke
				(width 0.1524)
				(type default)
			)
			(layer "F.SilkS")
		)
		(fp_line
			(start 4.9276 2.921)
			(end -4.9276 2.921)
			(stroke
				(width 0.1524)
				(type default)
			)
			(layer "F.SilkS")
		)
		(fp_line
			(start -4.9276 2.921)
			(end -4.9276 -2.921)
			(stroke
				(width 0.1524)
				(type default)
			)
			(layer "F.SilkS")
		)
		(fp_poly
			(pts
				(xy -5.08 3.0988) (xy 5.08 3.0988) (xy 5.08 -3.0988) (xy -5.08 -3.0988)
			)
			(stroke
				(width 0)
				(type default)
			)
			(fill no)
			(layer "F.CrtYd")
		)
		(fp_poly
			(pts
				(xy -5.08 -3.0988) (xy 5.08 -3.0988) (xy 5.08 3.0988) (xy -5.08 3.0988)
			)
			(stroke
				(width 0)
				(type default)
			)
			(fill no)
			(layer "F.Fab")
		)
		(pad "1" smd rect
			(at -3.4036 0 90)
			(size 2.2098 5.2832)
			(layers "F.Cu" "F.Mask" "F.Paste")
			(net "P12V_FAN5")
		)
		(pad "2" smd rect
			(at 3.4036 0 90)
			(size 2.2098 5.2832)
			(layers "F.Cu" "F.Mask" "F.Paste")
			(net "P12V")
		)
	)
	(footprint ""
		(layer "F.Cu")
		(at 36.068 -378.333 180)
		(property "Reference" "PR26"
			(at 0 0 180)
			(layer "F.SilkS")
			(hide yes)
			(effects
				(font
					(size 1.27 1.27)
				)
			)
		)
		(property "Value" "10R2F-L-GP"
			(at 0.064008 -3.993896 180)
			(unlocked yes)
			(layer "F.Fab")
			(hide yes)
			(effects
				(font
					(size 1.016 1.016)
					(thickness 0.1524)
				)
			)
		)
		(property "Device Type" "R402H14"
			(at 0.064008 -5.517896 180)
			(unlocked yes)
			(layer "F.Fab")
			(hide yes)
			(effects
				(font
					(size 1.016 1.016)
					(thickness 0.1524)
				)
			)
		)
		(duplicate_pad_numbers_are_jumpers no)
		(fp_line
			(start 0.508 -0.9398)
			(end -0.508 -0.9398)
			(stroke
				(width 0.1524)
				(type default)
			)
			(layer "F.SilkS")
		)
		(fp_line
			(start -0.508 -0.9398)
			(end -0.508 0.9398)
			(stroke
				(width 0.1524)
				(type default)
			)
			(layer "F.SilkS")
		)
		(fp_rect
			(start -0.508 0.9398)
			(end 0.508 -0.9398)
			(stroke
				(width 0)
				(type default)
			)
			(fill no)
			(layer "F.CrtYd")
		)
		(fp_rect
			(start -0.508 0.9398)
			(end 0.508 -0.9398)
			(stroke
				(width 0)
				(type default)
			)
			(fill no)
			(layer "F.Fab")
		)
		(pad "1" smd custom
			(at 0 -0.4445 180)
			(size 0.1397 0.1397)
			(layers "F.Cu" "F.Mask" "F.Paste")
			(net "ADM1276_GATE")
			(options
				(clearance outline)
				(anchor circle)
			)
			(primitives
				(gr_poly
					(pts
						(arc
							(start -0.1778 -0.2794)
							(mid -0.249642 -0.249642)
							(end -0.2794 -0.1778)
						)
						(arc
							(start -0.2794 0.1778)
							(mid -0.249642 0.249642)
							(end -0.1778 0.2794)
						)
						(arc
							(start 0.1778 0.2794)
							(mid 0.249642 0.249642)
							(end 0.2794 0.1778)
						)
						(arc
							(start 0.2794 -0.1778)
							(mid 0.249642 -0.249642)
							(end 0.1778 -0.2794)
						)
					)
					(width 0)
					(fill yes)
				)
			)
		)
		(pad "2" smd custom
			(at 0 0.4445 180)
			(size 0.1397 0.1397)
			(layers "F.Cu" "F.Mask" "F.Paste")
			(net "ADM1276_GATE_DRV1")
			(options
				(clearance outline)
				(anchor circle)
			)
			(primitives
				(gr_poly
					(pts
						(arc
							(start -0.1778 -0.2794)
							(mid -0.249642 -0.249642)
							(end -0.2794 -0.1778)
						)
						(arc
							(start -0.2794 0.1778)
							(mid -0.249642 0.249642)
							(end -0.1778 0.2794)
						)
						(arc
							(start 0.1778 0.2794)
							(mid 0.249642 0.249642)
							(end 0.2794 0.1778)
						)
						(arc
							(start 0.2794 -0.1778)
							(mid 0.249642 -0.249642)
							(end 0.1778 -0.2794)
						)
					)
					(width 0)
					(fill yes)
				)
			)
		)
	)
	(footprint ""
		(layer "F.Cu")
		(at 17.0688 -179.8828 180)
		(property "Reference" "C54"
			(at 0 0 180)
			(layer "F.SilkS")
			(hide yes)
			(effects
				(font
					(size 1.27 1.27)
				)
			)
		)
		(property "Value" "SCD1U50V3KX-GP"
			(at 0 -2.8194 180)
			(unlocked yes)
			(layer "F.Fab")
			(hide yes)
			(effects
				(font
					(size 1.016 1.016)
					(thickness 0.1524)
				)
			)
		)
		(property "Device Type" "C603H36"
			(at 0 -4.3434 180)
			(unlocked yes)
			(layer "F.Fab")
			(hide yes)
			(effects
				(font
					(size 1.016 1.016)
					(thickness 0.1524)
				)
			)
		)
		(duplicate_pad_numbers_are_jumpers no)
		(fp_line
			(start 0.508 0)
			(end -0.508 0)
			(stroke
				(width 0.2032)
				(type default)
			)
			(layer "F.SilkS")
		)
		(fp_rect
			(start -0.5842 1.3335)
			(end 0.5842 -1.3335)
			(stroke
				(width 0)
				(type default)
			)
			(fill no)
			(layer "F.CrtYd")
		)
		(fp_rect
			(start -0.5842 1.3335)
			(end 0.5842 -1.3335)
			(stroke
				(width 0)
				(type default)
			)
			(fill no)
			(layer "F.Fab")
		)
		(pad "1" smd custom
			(at 0 -0.762 180)
			(size 0.2159 0.2159)
			(layers "F.Cu" "F.Mask" "F.Paste")
			(net "P3V3")
			(options
				(clearance outline)
				(anchor circle)
			)
			(primitives
				(gr_poly
					(pts
						(arc
							(start -0.3302 -0.4318)
							(mid -0.402042 -0.402042)
							(end -0.4318 -0.3302)
						)
						(arc
							(start -0.4318 0.3302)
							(mid -0.402042 0.402042)
							(end -0.3302 0.4318)
						)
						(arc
							(start 0.3302 0.4318)
							(mid 0.402042 0.402042)
							(end 0.4318 0.3302)
						)
						(arc
							(start 0.4318 -0.3302)
							(mid 0.402042 -0.402042)
							(end 0.3302 -0.4318)
						)
					)
					(width 0)
					(fill yes)
				)
			)
		)
		(pad "2" smd custom
			(at 0 0.762 180)
			(size 0.2159 0.2159)
			(layers "F.Cu" "F.Mask" "F.Paste")
			(net "GND")
			(options
				(clearance outline)
				(anchor circle)
			)
			(primitives
				(gr_poly
					(pts
						(arc
							(start -0.3302 -0.4318)
							(mid -0.402042 -0.402042)
							(end -0.4318 -0.3302)
						)
						(arc
							(start -0.4318 0.3302)
							(mid -0.402042 0.402042)
							(end -0.3302 0.4318)
						)
						(arc
							(start 0.3302 0.4318)
							(mid 0.402042 0.402042)
							(end 0.4318 0.3302)
						)
						(arc
							(start 0.4318 -0.3302)
							(mid 0.402042 -0.402042)
							(end 0.3302 -0.4318)
						)
					)
					(width 0)
					(fill yes)
				)
			)
		)
	)
	(footprint ""
		(layer "F.Cu")
		(at 26.4922 -250.444 -90)
		(property "Reference" "C14"
			(at 0 0 270)
			(layer "F.SilkS")
			(hide yes)
			(effects
				(font
					(size 1.27 1.27)
				)
			)
		)
		(property "Value" "SCD1U50V3KX-GP"
			(at 0 -2.8194 270)
			(unlocked yes)
			(layer "F.Fab")
			(hide yes)
			(effects
				(font
					(size 1.016 1.016)
					(thickness 0.1524)
				)
			)
		)
		(property "Device Type" "C603H36"
			(at 0 -4.3434 270)
			(unlocked yes)
			(layer "F.Fab")
			(hide yes)
			(effects
				(font
					(size 1.016 1.016)
					(thickness 0.1524)
				)
			)
		)
		(duplicate_pad_numbers_are_jumpers no)
		(fp_line
			(start 0.508 0)
			(end -0.508 0)
			(stroke
				(width 0.2032)
				(type default)
			)
			(layer "F.SilkS")
		)
		(fp_rect
			(start -0.5842 1.3335)
			(end 0.5842 -1.3335)
			(stroke
				(width 0)
				(type default)
			)
			(fill no)
			(layer "F.CrtYd")
		)
		(fp_rect
			(start -0.5842 1.3335)
			(end 0.5842 -1.3335)
			(stroke
				(width 0)
				(type default)
			)
			(fill no)
			(layer "F.Fab")
		)
		(pad "1" smd custom
			(at 0 -0.762 270)
			(size 0.2159 0.2159)
			(layers "F.Cu" "F.Mask" "F.Paste")
			(net "P3V3")
			(options
				(clearance outline)
				(anchor circle)
			)
			(primitives
				(gr_poly
					(pts
						(arc
							(start -0.3302 -0.4318)
							(mid -0.402042 -0.402042)
							(end -0.4318 -0.3302)
						)
						(arc
							(start -0.4318 0.3302)
							(mid -0.402042 0.402042)
							(end -0.3302 0.4318)
						)
						(arc
							(start 0.3302 0.4318)
							(mid 0.402042 0.402042)
							(end 0.4318 0.3302)
						)
						(arc
							(start 0.4318 -0.3302)
							(mid 0.402042 -0.402042)
							(end 0.3302 -0.4318)
						)
					)
					(width 0)
					(fill yes)
				)
			)
		)
		(pad "2" smd custom
			(at 0 0.762 270)
			(size 0.2159 0.2159)
			(layers "F.Cu" "F.Mask" "F.Paste")
			(net "GND")
			(options
				(clearance outline)
				(anchor circle)
			)
			(primitives
				(gr_poly
					(pts
						(arc
							(start -0.3302 -0.4318)
							(mid -0.402042 -0.402042)
							(end -0.4318 -0.3302)
						)
						(arc
							(start -0.4318 0.3302)
							(mid -0.402042 0.402042)
							(end -0.3302 0.4318)
						)
						(arc
							(start 0.3302 0.4318)
							(mid 0.402042 0.402042)
							(end 0.4318 0.3302)
						)
						(arc
							(start 0.4318 -0.3302)
							(mid 0.402042 -0.402042)
							(end 0.3302 -0.4318)
						)
					)
					(width 0)
					(fill yes)
				)
			)
		)
	)
	(footprint ""
		(layer "F.Cu")
		(at 29.5402 -169.9006 180)
		(property "Reference" "R161"
			(at 0 0 180)
			(layer "F.SilkS")
			(hide yes)
			(effects
				(font
					(size 1.27 1.27)
				)
			)
		)
		(property "Value" "0R2J-2-GP"
			(at 0.064008 -3.993896 180)
			(unlocked yes)
			(layer "F.Fab")
			(hide yes)
			(effects
				(font
					(size 1.016 1.016)
					(thickness 0.1524)
				)
			)
		)
		(property "Device Type" "R402H16"
			(at 0.064008 -5.517896 180)
			(unlocked yes)
			(layer "F.Fab")
			(hide yes)
			(effects
				(font
					(size 1.016 1.016)
					(thickness 0.1524)
				)
			)
		)
		(duplicate_pad_numbers_are_jumpers no)
		(fp_line
			(start 0.508 -0.9398)
			(end -0.508 -0.9398)
			(stroke
				(width 0.1524)
				(type default)
			)
			(layer "F.SilkS")
		)
		(fp_line
			(start -0.508 -0.9398)
			(end -0.508 0.9398)
			(stroke
				(width 0.1524)
				(type default)
			)
			(layer "F.SilkS")
		)
		(fp_rect
			(start -0.508 0.9398)
			(end 0.508 -0.9398)
			(stroke
				(width 0)
				(type default)
			)
			(fill no)
			(layer "F.CrtYd")
		)
		(fp_rect
			(start -0.508 0.9398)
			(end 0.508 -0.9398)
			(stroke
				(width 0)
				(type default)
			)
			(fill no)
			(layer "F.Fab")
		)
		(pad "1" smd custom
			(at 0 -0.4445 180)
			(size 0.1397 0.1397)
			(layers "F.Cu" "F.Mask" "F.Paste")
			(net "NCT7904D_PWM1")
			(options
				(clearance outline)
				(anchor circle)
			)
			(primitives
				(gr_poly
					(pts
						(arc
							(start -0.1778 -0.2794)
							(mid -0.249642 -0.249642)
							(end -0.2794 -0.1778)
						)
						(arc
							(start -0.2794 0.1778)
							(mid -0.249642 0.249642)
							(end -0.1778 0.2794)
						)
						(arc
							(start 0.1778 0.2794)
							(mid 0.249642 0.249642)
							(end 0.2794 0.1778)
						)
						(arc
							(start 0.2794 -0.1778)
							(mid 0.249642 -0.249642)
							(end 0.1778 -0.2794)
						)
					)
					(width 0)
					(fill yes)
				)
			)
		)
		(pad "2" smd custom
			(at 0 0.4445 180)
			(size 0.1397 0.1397)
			(layers "F.Cu" "F.Mask" "F.Paste")
			(net "PWM_BUFFER_IN_FAN1_FAN2")
			(options
				(clearance outline)
				(anchor circle)
			)
			(primitives
				(gr_poly
					(pts
						(arc
							(start -0.1778 -0.2794)
							(mid -0.249642 -0.249642)
							(end -0.2794 -0.1778)
						)
						(arc
							(start -0.2794 0.1778)
							(mid -0.249642 0.249642)
							(end -0.1778 0.2794)
						)
						(arc
							(start 0.1778 0.2794)
							(mid 0.249642 0.249642)
							(end 0.2794 0.1778)
						)
						(arc
							(start 0.2794 -0.1778)
							(mid 0.249642 -0.249642)
							(end 0.1778 -0.2794)
						)
					)
					(width 0)
					(fill yes)
				)
			)
		)
	)
	(footprint ""
		(layer "F.Cu")
		(at 32.385 -361.315 180)
		(property "Reference" "R108"
			(at 0 0 180)
			(layer "F.SilkS")
			(hide yes)
			(effects
				(font
					(size 1.27 1.27)
				)
			)
		)
		(property "Value" "0R2J-2-GP"
			(at 0.064008 -3.993896 180)
			(unlocked yes)
			(layer "F.Fab")
			(hide yes)
			(effects
				(font
					(size 1.016 1.016)
					(thickness 0.1524)
				)
			)
		)
		(property "Device Type" "R402H16"
			(at 0.064008 -5.517896 180)
			(unlocked yes)
			(layer "F.Fab")
			(hide yes)
			(effects
				(font
					(size 1.016 1.016)
					(thickness 0.1524)
				)
			)
		)
		(duplicate_pad_numbers_are_jumpers no)
		(fp_line
			(start 0.508 -0.9398)
			(end -0.508 -0.9398)
			(stroke
				(width 0.1524)
				(type default)
			)
			(layer "F.SilkS")
		)
		(fp_line
			(start -0.508 -0.9398)
			(end -0.508 0.9398)
			(stroke
				(width 0.1524)
				(type default)
			)
			(layer "F.SilkS")
		)
		(fp_rect
			(start -0.508 0.9398)
			(end 0.508 -0.9398)
			(stroke
				(width 0)
				(type default)
			)
			(fill no)
			(layer "F.CrtYd")
		)
		(fp_rect
			(start -0.508 0.9398)
			(end 0.508 -0.9398)
			(stroke
				(width 0)
				(type default)
			)
			(fill no)
			(layer "F.Fab")
		)
		(pad "1" smd custom
			(at 0 -0.4445 180)
			(size 0.1397 0.1397)
			(layers "F.Cu" "F.Mask" "F.Paste")
			(net "I2C_C_SCL")
			(options
				(clearance outline)
				(anchor circle)
			)
			(primitives
				(gr_poly
					(pts
						(arc
							(start -0.1778 -0.2794)
							(mid -0.249642 -0.249642)
							(end -0.2794 -0.1778)
						)
						(arc
							(start -0.2794 0.1778)
							(mid -0.249642 0.249642)
							(end -0.1778 0.2794)
						)
						(arc
							(start 0.1778 0.2794)
							(mid 0.249642 0.249642)
							(end 0.2794 0.1778)
						)
						(arc
							(start 0.2794 -0.1778)
							(mid 0.249642 -0.249642)
							(end 0.1778 -0.2794)
						)
					)
					(width 0)
					(fill yes)
				)
			)
		)
		(pad "2" smd custom
			(at 0 0.4445 180)
			(size 0.1397 0.1397)
			(layers "F.Cu" "F.Mask" "F.Paste")
			(net "I2C_C_SCL_ADM1276")
			(options
				(clearance outline)
				(anchor circle)
			)
			(primitives
				(gr_poly
					(pts
						(arc
							(start -0.1778 -0.2794)
							(mid -0.249642 -0.249642)
							(end -0.2794 -0.1778)
						)
						(arc
							(start -0.2794 0.1778)
							(mid -0.249642 0.249642)
							(end -0.1778 0.2794)
						)
						(arc
							(start 0.1778 0.2794)
							(mid 0.249642 0.249642)
							(end 0.2794 0.1778)
						)
						(arc
							(start 0.2794 -0.1778)
							(mid 0.249642 -0.249642)
							(end 0.1778 -0.2794)
						)
					)
					(width 0)
					(fill yes)
				)
			)
		)
	)
	(footprint ""
		(layer "F.Cu")
		(at 19.6088 -178.8668 180)
		(property "Reference" "R91"
			(at 0 0 180)
			(layer "F.SilkS")
			(hide yes)
			(effects
				(font
					(size 1.27 1.27)
				)
			)
		)
		(property "Value" "10KR2F-2-GP"
			(at 0.064008 -3.993896 180)
			(unlocked yes)
			(layer "F.Fab")
			(hide yes)
			(effects
				(font
					(size 1.016 1.016)
					(thickness 0.1524)
				)
			)
		)
		(property "Device Type" "R402H16"
			(at 0.064008 -5.517896 180)
			(unlocked yes)
			(layer "F.Fab")
			(hide yes)
			(effects
				(font
					(size 1.016 1.016)
					(thickness 0.1524)
				)
			)
		)
		(duplicate_pad_numbers_are_jumpers no)
		(fp_line
			(start 0.508 -0.9398)
			(end -0.508 -0.9398)
			(stroke
				(width 0.1524)
				(type default)
			)
			(layer "F.SilkS")
		)
		(fp_line
			(start -0.508 -0.9398)
			(end -0.508 0.9398)
			(stroke
				(width 0.1524)
				(type default)
			)
			(layer "F.SilkS")
		)
		(fp_rect
			(start -0.508 0.9398)
			(end 0.508 -0.9398)
			(stroke
				(width 0)
				(type default)
			)
			(fill no)
			(layer "F.CrtYd")
		)
		(fp_rect
			(start -0.508 0.9398)
			(end 0.508 -0.9398)
			(stroke
				(width 0)
				(type default)
			)
			(fill no)
			(layer "F.Fab")
		)
		(pad "1" smd custom
			(at 0 -0.4445 180)
			(size 0.1397 0.1397)
			(layers "F.Cu" "F.Mask" "F.Paste")
			(net "FANIN_7")
			(options
				(clearance outline)
				(anchor circle)
			)
			(primitives
				(gr_poly
					(pts
						(arc
							(start -0.1778 -0.2794)
							(mid -0.249642 -0.249642)
							(end -0.2794 -0.1778)
						)
						(arc
							(start -0.2794 0.1778)
							(mid -0.249642 0.249642)
							(end -0.1778 0.2794)
						)
						(arc
							(start 0.1778 0.2794)
							(mid 0.249642 0.249642)
							(end 0.2794 0.1778)
						)
						(arc
							(start 0.2794 -0.1778)
							(mid 0.249642 -0.249642)
							(end 0.1778 -0.2794)
						)
					)
					(width 0)
					(fill yes)
				)
			)
		)
		(pad "2" smd custom
			(at 0 0.4445 180)
			(size 0.1397 0.1397)
			(layers "F.Cu" "F.Mask" "F.Paste")
			(net "GND")
			(options
				(clearance outline)
				(anchor circle)
			)
			(primitives
				(gr_poly
					(pts
						(arc
							(start -0.1778 -0.2794)
							(mid -0.249642 -0.249642)
							(end -0.2794 -0.1778)
						)
						(arc
							(start -0.2794 0.1778)
							(mid -0.249642 0.249642)
							(end -0.1778 0.2794)
						)
						(arc
							(start 0.1778 0.2794)
							(mid 0.249642 0.249642)
							(end 0.2794 0.1778)
						)
						(arc
							(start 0.2794 -0.1778)
							(mid 0.249642 -0.249642)
							(end 0.1778 -0.2794)
						)
					)
					(width 0)
					(fill yes)
				)
			)
		)
	)
	(footprint ""
		(layer "F.Cu")
		(at 43.8658 -382.9558 -90)
		(property "Reference" "D14"
			(at 0 0 270)
			(layer "F.SilkS")
			(hide yes)
			(effects
				(font
					(size 1.27 1.27)
				)
			)
		)
		(property "Value" "MBRS340T3G-GP"
			(at 0 -10.6172 270)
			(unlocked yes)
			(layer "F.Fab")
			(hide yes)
			(effects
				(font
					(size 1.016 1.016)
					(thickness 0.1524)
				)
			)
		)
		(property "Device Type" "D8059AKH101"
			(at 0 -12.1412 270)
			(unlocked yes)
			(layer "F.Fab")
			(hide yes)
			(effects
				(font
					(size 1.016 1.016)
					(thickness 0.1524)
				)
			)
		)
		(duplicate_pad_numbers_are_jumpers no)
		(fp_line
			(start 3.175 5.2832)
			(end -3.175 5.2832)
			(stroke
				(width 0.508)
				(type default)
			)
			(layer "F.SilkS")
		)
		(fp_line
			(start -3.175 5.1054)
			(end -3.175 -5.1054)
			(stroke
				(width 0.1524)
				(type default)
			)
			(layer "F.SilkS")
		)
		(fp_line
			(start 3.175 5.1054)
			(end -3.175 5.1054)
			(stroke
				(width 0.1524)
				(type default)
			)
			(layer "F.SilkS")
		)
		(fp_line
			(start -3.175 -5.1054)
			(end 3.175 -5.1054)
			(stroke
				(width 0.1524)
				(type default)
			)
			(layer "F.SilkS")
		)
		(fp_line
			(start 3.175 -5.1054)
			(end 3.175 5.1054)
			(stroke
				(width 0.1524)
				(type default)
			)
			(layer "F.SilkS")
		)
		(fp_rect
			(start -3.429 5.1816)
			(end 3.429 -5.1816)
			(stroke
				(width 0)
				(type default)
			)
			(fill no)
			(layer "F.CrtYd")
		)
		(fp_poly
			(pts
				(xy -3.429 -5.1816) (xy 3.429 -5.1816) (xy 3.429 5.1816) (xy -3.429 5.1816)
			)
			(stroke
				(width 0)
				(type default)
			)
			(fill no)
			(layer "F.Fab")
		)
		(pad "A" smd rect
			(at 0 -3.77571 270)
			(size 3.2512 2.159)
			(layers "F.Cu" "F.Mask" "F.Paste")
			(net "GND")
		)
		(pad "K" smd rect
			(at 0 3.77571 270)
			(size 3.2512 2.159)
			(layers "F.Cu" "F.Mask" "F.Paste")
			(net "P12V")
		)
	)
	(footprint ""
		(layer "F.Cu")
		(at 43.942 -95.7326 90)
		(property "Reference" "TC5"
			(at 0 0 90)
			(layer "F.SilkS")
			(hide yes)
			(effects
				(font
					(size 1.27 1.27)
				)
			)
		)
		(property "Value" "ST68U16VDM-1-GP"
			(at 0 -9.6012 90)
			(unlocked yes)
			(layer "F.Fab")
			(hide yes)
			(effects
				(font
					(size 1.016 1.016)
					(thickness 0.1524)
				)
			)
		)
		(property "Device Type" "CT7343H79"
			(at 0 -11.1252 90)
			(unlocked yes)
			(layer "F.Fab")
			(hide yes)
			(effects
				(font
					(size 1.016 1.016)
					(thickness 0.1524)
				)
			)
		)
		(duplicate_pad_numbers_are_jumpers no)
		(fp_line
			(start 2.286 -4.8768)
			(end -2.286 -4.8768)
			(stroke
				(width 0.1524)
				(type default)
			)
			(layer "F.SilkS")
		)
		(fp_line
			(start -2.286 -4.8768)
			(end -2.286 -2.032)
			(stroke
				(width 0.1524)
				(type default)
			)
			(layer "F.SilkS")
		)
		(fp_line
			(start 2.1082 -4.699)
			(end -2.1082 -4.699)
			(stroke
				(width 0.508)
				(type default)
			)
			(layer "F.SilkS")
		)
		(fp_line
			(start 2.286 -2.032)
			(end 2.286 -4.8768)
			(stroke
				(width 0.1524)
				(type default)
			)
			(layer "F.SilkS")
		)
		(fp_line
			(start 2.286 2.032)
			(end 2.286 4.8768)
			(stroke
				(width 0.1524)
				(type default)
			)
			(layer "F.SilkS")
		)
		(fp_line
			(start 2.286 4.8768)
			(end -2.286 4.8768)
			(stroke
				(width 0.1524)
				(type default)
			)
			(layer "F.SilkS")
		)
		(fp_line
			(start -2.286 4.8768)
			(end -2.286 2.032)
			(stroke
				(width 0.1524)
				(type default)
			)
			(layer "F.SilkS")
		)
		(fp_rect
			(start -2.1463 3.6449)
			(end 2.1463 -3.6449)
			(stroke
				(width 0)
				(type default)
			)
			(fill no)
			(layer "F.CrtYd")
		)
		(fp_poly
			(pts
				(xy -2.54 4.953) (xy -2.54 4.2926) (xy -3.81 4.2926) (xy -3.81 -4.2926) (xy -2.54 -4.2926) (xy -2.54 -4.953)
				(xy 2.54 -4.953) (xy 2.54 -4.2926) (xy 3.81 -4.2926) (xy 3.81 -1.6256) (xy 2.1463 -1.6256) (xy 2.1463 -3.6449)
				(xy -2.1463 -3.6449) (xy -2.1463 3.6449) (xy 2.1463 3.6449) (xy 2.1463 -1.6129) (xy 3.81 -1.6129)
				(xy 3.81 4.2926) (xy 2.54 4.2926) (xy 2.54 4.953)
			)
			(stroke
				(width 0)
				(type default)
			)
			(fill no)
			(layer "F.CrtYd")
		)
		(fp_rect
			(start 2.54 4.2926)
			(end 3.81 -4.2926)
			(stroke
				(width 0)
				(type default)
			)
			(fill no)
			(layer "F.Fab")
		)
		(fp_rect
			(start -3.81 4.2926)
			(end -2.54 -4.2926)
			(stroke
				(width 0)
				(type default)
			)
			(fill no)
			(layer "F.Fab")
		)
		(fp_rect
			(start -2.54 4.953)
			(end 2.54 -4.953)
			(stroke
				(width 0)
				(type default)
			)
			(fill no)
			(layer "F.Fab")
		)
		(pad "1" smd rect
			(at 0 -3.1496 90)
			(size 2.413 2.286)
			(layers "F.Cu" "F.Mask" "F.Paste")
			(net "P12VL")
		)
		(pad "2" smd rect
			(at 0 3.1496 90)
			(size 2.413 2.286)
			(layers "F.Cu" "F.Mask" "F.Paste")
			(net "GND")
		)
		(zone
			(layer "F.Cu")
			(hatch none 0.5)
			(connect_pads
				(clearance 0)
			)
			(min_thickness 0.25)
			(keepout
				(tracks allowed)
				(vias not_allowed)
				(pads allowed)
				(copperpour not_allowed)
				(footprints allowed)
			)
			(placement
				(enabled no)
				(sheetname "")
			)
			(fill
				(thermal_gap 0.5)
				(thermal_bridge_width 0.5)
				(island_removal_mode 0)
			)
			(polygon
				(pts
					(xy 42.2529 -97.2439) (xy 39.3446 -97.2439) (xy 39.3446 -94.2213) (xy 42.2402 -94.2213) (xy 42.5704 -94.2213)
					(xy 42.5704 -97.2439)
				)
			)
		)
		(zone
			(layer "F.Cu")
			(hatch none 0.5)
			(connect_pads
				(clearance 0)
			)
			(min_thickness 0.25)
			(keepout
				(tracks allowed)
				(vias not_allowed)
				(pads allowed)
				(copperpour not_allowed)
				(footprints allowed)
			)
			(placement
				(enabled no)
				(sheetname "")
			)
			(fill
				(thermal_gap 0.5)
				(thermal_bridge_width 0.5)
				(island_removal_mode 0)
			)
			(polygon
				(pts
					(xy 48.5394 -94.2213) (xy 48.5394 -97.2439) (xy 45.6438 -97.2439) (xy 45.3136 -97.2439) (xy 45.3136 -94.2213)
					(xy 45.6438 -94.2213)
				)
			)
		)
	)
	(footprint ""
		(layer "F.Cu")
		(at 8.0772 -275.2344 90)
		(property "Reference" "R38"
			(at 0 0 90)
			(layer "F.SilkS")
			(hide yes)
			(effects
				(font
					(size 1.27 1.27)
				)
			)
		)
		(property "Value" "0R2J-2-GP"
			(at 0.064008 -3.993896 90)
			(unlocked yes)
			(layer "F.Fab")
			(hide yes)
			(effects
				(font
					(size 1.016 1.016)
					(thickness 0.1524)
				)
			)
		)
		(property "Device Type" "R402H16"
			(at 0.064008 -5.517896 90)
			(unlocked yes)
			(layer "F.Fab")
			(hide yes)
			(effects
				(font
					(size 1.016 1.016)
					(thickness 0.1524)
				)
			)
		)
		(duplicate_pad_numbers_are_jumpers no)
		(fp_line
			(start 0.508 -0.9398)
			(end -0.508 -0.9398)
			(stroke
				(width 0.1524)
				(type default)
			)
			(layer "F.SilkS")
		)
		(fp_line
			(start -0.508 -0.9398)
			(end -0.508 0.9398)
			(stroke
				(width 0.1524)
				(type default)
			)
			(layer "F.SilkS")
		)
		(fp_rect
			(start -0.508 0.9398)
			(end 0.508 -0.9398)
			(stroke
				(width 0)
				(type default)
			)
			(fill no)
			(layer "F.CrtYd")
		)
		(fp_rect
			(start -0.508 0.9398)
			(end 0.508 -0.9398)
			(stroke
				(width 0)
				(type default)
			)
			(fill no)
			(layer "F.Fab")
		)
		(pad "1" smd custom
			(at 0 -0.4445 90)
			(size 0.1397 0.1397)
			(layers "F.Cu" "F.Mask" "F.Paste")
			(net "LED_DR_LED2_K")
			(options
				(clearance outline)
				(anchor circle)
			)
			(primitives
				(gr_poly
					(pts
						(arc
							(start -0.1778 -0.2794)
							(mid -0.249642 -0.249642)
							(end -0.2794 -0.1778)
						)
						(arc
							(start -0.2794 0.1778)
							(mid -0.249642 0.249642)
							(end -0.1778 0.2794)
						)
						(arc
							(start 0.1778 0.2794)
							(mid 0.249642 0.249642)
							(end 0.2794 0.1778)
						)
						(arc
							(start 0.2794 -0.1778)
							(mid 0.249642 -0.249642)
							(end 0.1778 -0.2794)
						)
					)
					(width 0)
					(fill yes)
				)
			)
		)
		(pad "2" smd custom
			(at 0 0.4445 90)
			(size 0.1397 0.1397)
			(layers "F.Cu" "F.Mask" "F.Paste")
			(net "GND")
			(options
				(clearance outline)
				(anchor circle)
			)
			(primitives
				(gr_poly
					(pts
						(arc
							(start -0.1778 -0.2794)
							(mid -0.249642 -0.249642)
							(end -0.2794 -0.1778)
						)
						(arc
							(start -0.2794 0.1778)
							(mid -0.249642 0.249642)
							(end -0.1778 0.2794)
						)
						(arc
							(start 0.1778 0.2794)
							(mid 0.249642 0.249642)
							(end 0.2794 0.1778)
						)
						(arc
							(start 0.2794 -0.1778)
							(mid 0.249642 -0.249642)
							(end 0.1778 -0.2794)
						)
					)
					(width 0)
					(fill yes)
				)
			)
		)
	)
	(footprint ""
		(layer "F.Cu")
		(at 27.9654 -355.5238 90)
		(property "Reference" "Q10"
			(at 0 0 90)
			(layer "F.SilkS")
			(hide yes)
			(effects
				(font
					(size 1.27 1.27)
				)
			)
		)
		(property "Value" "2N7002DW-7F-GP"
			(at -2.3622 -8.2042 90)
			(unlocked yes)
			(layer "F.Fab")
			(hide yes)
			(effects
				(font
					(size 1.016 1.016)
					(thickness 0.1524)
				)
			)
		)
		(property "Device Type" "SOT-363H44"
			(at -2.3622 -10.1092 90)
			(unlocked yes)
			(layer "F.Fab")
			(hide yes)
			(effects
				(font
					(size 1.016 1.016)
					(thickness 0.1524)
				)
			)
		)
		(duplicate_pad_numbers_are_jumpers no)
		(fp_line
			(start 1.4478 -1.7018)
			(end -1.4478 -1.7018)
			(stroke
				(width 0.1524)
				(type default)
			)
			(layer "F.SilkS")
		)
		(fp_line
			(start -1.4478 -1.7018)
			(end -1.4478 1.7018)
			(stroke
				(width 0.1524)
				(type default)
			)
			(layer "F.SilkS")
		)
		(fp_line
			(start -1.27 1.524)
			(end -1.27 0.6604)
			(stroke
				(width 0.4826)
				(type default)
			)
			(layer "F.SilkS")
		)
		(fp_line
			(start 1.4478 1.7018)
			(end 1.4478 -1.7018)
			(stroke
				(width 0.1524)
				(type default)
			)
			(layer "F.SilkS")
		)
		(fp_line
			(start -1.4478 1.7018)
			(end 1.4478 1.7018)
			(stroke
				(width 0.1524)
				(type default)
			)
			(layer "F.SilkS")
		)
		(fp_poly
			(pts
				(xy -1.524 -1.778) (xy 1.524 -1.778) (xy 1.524 1.778) (xy -1.524 1.778)
			)
			(stroke
				(width 0)
				(type default)
			)
			(fill no)
			(layer "F.CrtYd")
		)
		(fp_poly
			(pts
				(xy -1.524 -1.778) (xy 1.524 -1.778) (xy 1.524 1.778) (xy -1.524 1.778)
			)
			(stroke
				(width 0)
				(type default)
			)
			(fill no)
			(layer "F.Fab")
		)
		(pad "1" smd rect
			(at -0.65024 0.9398 90)
			(size 0.4064 1.016)
			(layers "F.Cu" "F.Mask" "F.Paste")
			(net "GND")
		)
		(pad "2" smd rect
			(at 0 0.9398 90)
			(size 0.4064 1.016)
			(layers "F.Cu" "F.Mask" "F.Paste")
			(net "TEMP_ALM#")
		)
		(pad "3" smd rect
			(at 0.65024 0.9398 90)
			(size 0.4064 1.016)
			(layers "F.Cu" "F.Mask" "F.Paste")
			(net "TEMP_ALM#_JP_2")
		)
		(pad "4" smd rect
			(at 0.65024 -0.9398 90)
			(size 0.4064 1.016)
			(layers "F.Cu" "F.Mask" "F.Paste")
			(net "GND")
		)
		(pad "5" smd rect
			(at 0 -0.9398 90)
			(size 0.4064 1.016)
			(layers "F.Cu" "F.Mask" "F.Paste")
			(net "TEMP_ALM#_G")
		)
		(pad "6" smd rect
			(at -0.65024 -0.9398 90)
			(size 0.4064 1.016)
			(layers "F.Cu" "F.Mask" "F.Paste")
			(net "TEMP_ALM#_G")
		)
	)
	(footprint ""
		(layer "F.Cu")
		(at 32.766 -374.777 180)
		(property "Reference" "PR10"
			(at 0 0 180)
			(layer "F.SilkS")
			(hide yes)
			(effects
				(font
					(size 1.27 1.27)
				)
			)
		)
		(property "Value" "0R0402-PAD-2-GP"
			(at 0 -2.8702 180)
			(unlocked yes)
			(layer "F.Fab")
			(hide yes)
			(effects
				(font
					(size 1.016 1.016)
					(thickness 0.1524)
				)
			)
		)
		(property "Device Type" "0R0402-PAD-1"
			(at 0 -4.3942 180)
			(unlocked yes)
			(layer "F.Fab")
			(hide yes)
			(effects
				(font
					(size 1.016 1.016)
					(thickness 0.1524)
				)
			)
		)
		(duplicate_pad_numbers_are_jumpers no)
		(fp_line
			(start 0.508 -0.9398)
			(end -0.508 -0.9398)
			(stroke
				(width 0.1524)
				(type default)
			)
			(layer "F.SilkS")
		)
		(fp_line
			(start -0.508 -0.9398)
			(end -0.508 0.9398)
			(stroke
				(width 0.1524)
				(type default)
			)
			(layer "F.SilkS")
		)
		(fp_rect
			(start -0.508 0.9398)
			(end 0.508 -0.9398)
			(stroke
				(width 0)
				(type default)
			)
			(fill no)
			(layer "F.CrtYd")
		)
		(fp_rect
			(start -0.508 0.9398)
			(end 0.508 -0.9398)
			(stroke
				(width 0)
				(type default)
			)
			(fill no)
			(layer "F.Fab")
		)
		(pad "1" smd custom
			(at 0 -0.4445 180)
			(size 0.1397 0.1397)
			(layers "F.Cu" "F.Mask" "F.Paste")
			(net "ADM1276_GATE_DRV")
			(options
				(clearance outline)
				(anchor circle)
			)
			(primitives
				(gr_poly
					(pts
						(xy -0.2794 0.3683)
						(arc
							(start -0.2794 -0.2667)
							(mid -0.249642 -0.338542)
							(end -0.1778 -0.3683)
						)
						(arc
							(start 0.1778 -0.3683)
							(mid 0.249642 -0.338542)
							(end 0.2794 -0.2667)
						)
						(xy 0.2794 0.3683)
					)
					(width 0)
					(fill yes)
				)
			)
		)
		(pad "2" smd custom
			(at 0 0.4445 180)
			(size 0.1397 0.1397)
			(layers "F.Cu" "F.Mask" "F.Paste")
			(net "ADM1276_GATE")
			(options
				(clearance outline)
				(anchor circle)
			)
			(primitives
				(gr_poly
					(pts
						(arc
							(start -0.1778 0.3683)
							(mid -0.249642 0.338542)
							(end -0.2794 0.2667)
						)
						(xy -0.2794 -0.3683) (xy 0.2794 -0.3683)
						(arc
							(start 0.2794 0.2667)
							(mid 0.249642 0.338542)
							(end 0.1778 0.3683)
						)
					)
					(width 0)
					(fill yes)
				)
			)
		)
	)
	(footprint ""
		(layer "F.Cu")
		(at 35.541966 -153.45791 90)
		(property "Reference" "TP13"
			(at 0 0 90)
			(layer "F.SilkS")
			(hide yes)
			(effects
				(font
					(size 1.27 1.27)
				)
			)
		)
		(property "Value" "TPAD32-GP"
			(at 0 -3.166364 90)
			(unlocked yes)
			(layer "F.Fab")
			(hide yes)
			(effects
				(font
					(size 1.016 1.016)
					(thickness 0.1524)
				)
			)
		)
		(property "Device Type" "TPAD32"
			(at 0 -4.690618 90)
			(unlocked yes)
			(layer "F.Fab")
			(hide yes)
			(effects
				(font
					(size 1.016 1.016)
					(thickness 0.1524)
				)
			)
		)
		(duplicate_pad_numbers_are_jumpers no)
		(fp_poly
			(pts
				(arc
					(start 0.7112 0)
					(mid -0.7112 0)
					(end 0.7112 0)
				)
			)
			(stroke
				(width 0)
				(type default)
			)
			(fill no)
			(layer "F.CrtYd")
		)
		(fp_poly
			(pts
				(arc
					(start 0.7112 0)
					(mid -0.7112 0)
					(end 0.7112 0)
				)
			)
			(stroke
				(width 0)
				(type default)
			)
			(fill no)
			(layer "F.Fab")
		)
		(pad "1" smd circle
			(at 0 0 90)
			(size 0.8128 0.8128)
			(layers "F.Cu" "F.Mask" "F.Paste")
			(net "NCT7904_VSEN13")
		)
	)
	(footprint ""
		(layer "F.Cu")
		(at 19.2278 -182.1942)
		(property "Reference" "C36"
			(at 0 0 0)
			(layer "F.SilkS")
			(hide yes)
			(effects
				(font
					(size 1.27 1.27)
				)
			)
		)
		(property "Value" "SCD1U16V2KX-3GP"
			(at 1.1811 -2.7051 0)
			(unlocked yes)
			(layer "F.Fab")
			(hide yes)
			(effects
				(font
					(size 1.016 1.016)
					(thickness 0.1524)
				)
			)
		)
		(property "Device Type" "C402H22"
			(at 1.1811 -4.2291 0)
			(unlocked yes)
			(layer "F.Fab")
			(hide yes)
			(effects
				(font
					(size 1.016 1.016)
					(thickness 0.1524)
				)
			)
		)
		(duplicate_pad_numbers_are_jumpers no)
		(fp_rect
			(start -0.4318 0.9525)
			(end 0.4318 -0.9525)
			(stroke
				(width 0)
				(type default)
			)
			(fill no)
			(layer "F.CrtYd")
		)
		(fp_rect
			(start -0.4318 0.9525)
			(end 0.4318 -0.9525)
			(stroke
				(width 0)
				(type default)
			)
			(fill no)
			(layer "F.Fab")
		)
		(pad "1" smd custom
			(at 0 -0.4445)
			(size 0.1524 0.1524)
			(layers "F.Cu" "F.Mask" "F.Paste")
			(net "FAN_TACH7")
			(options
				(clearance outline)
				(anchor circle)
			)
			(primitives
				(gr_poly
					(pts
						(arc
							(start 0.3048 -0.2032)
							(mid 0.275042 -0.275042)
							(end 0.2032 -0.3048)
						)
						(arc
							(start -0.2032 -0.3048)
							(mid -0.275042 -0.275042)
							(end -0.3048 -0.2032)
						)
						(arc
							(start -0.3048 0.2032)
							(mid -0.275042 0.275042)
							(end -0.2032 0.3048)
						)
						(arc
							(start 0.2032 0.3048)
							(mid 0.275042 0.275042)
							(end 0.3048 0.2032)
						)
					)
					(width 0)
					(fill yes)
				)
			)
		)
		(pad "2" smd custom
			(at 0 0.4445)
			(size 0.1524 0.1524)
			(layers "F.Cu" "F.Mask" "F.Paste")
			(net "GND")
			(options
				(clearance outline)
				(anchor circle)
			)
			(primitives
				(gr_poly
					(pts
						(arc
							(start 0.3048 -0.2032)
							(mid 0.275042 -0.275042)
							(end 0.2032 -0.3048)
						)
						(arc
							(start -0.2032 -0.3048)
							(mid -0.275042 -0.275042)
							(end -0.3048 -0.2032)
						)
						(arc
							(start -0.3048 0.2032)
							(mid -0.275042 0.275042)
							(end -0.2032 0.3048)
						)
						(arc
							(start 0.2032 0.3048)
							(mid 0.275042 0.275042)
							(end 0.3048 0.2032)
						)
					)
					(width 0)
					(fill yes)
				)
			)
		)
	)
	(footprint ""
		(layer "F.Cu")
		(at 17.8816 -255.0922 -90)
		(property "Reference" "R82"
			(at 0 0 270)
			(layer "F.SilkS")
			(hide yes)
			(effects
				(font
					(size 1.27 1.27)
				)
			)
		)
		(property "Value" "4K7R2F-GP"
			(at 0.064008 -3.993896 270)
			(unlocked yes)
			(layer "F.Fab")
			(hide yes)
			(effects
				(font
					(size 1.016 1.016)
					(thickness 0.1524)
				)
			)
		)
		(property "Device Type" "R402H16"
			(at 0.064008 -5.517896 270)
			(unlocked yes)
			(layer "F.Fab")
			(hide yes)
			(effects
				(font
					(size 1.016 1.016)
					(thickness 0.1524)
				)
			)
		)
		(duplicate_pad_numbers_are_jumpers no)
		(fp_line
			(start -0.508 -0.9398)
			(end -0.508 0.9398)
			(stroke
				(width 0.1524)
				(type default)
			)
			(layer "F.SilkS")
		)
		(fp_line
			(start 0.508 -0.9398)
			(end -0.508 -0.9398)
			(stroke
				(width 0.1524)
				(type default)
			)
			(layer "F.SilkS")
		)
		(fp_rect
			(start -0.508 0.9398)
			(end 0.508 -0.9398)
			(stroke
				(width 0)
				(type default)
			)
			(fill no)
			(layer "F.CrtYd")
		)
		(fp_rect
			(start -0.508 0.9398)
			(end 0.508 -0.9398)
			(stroke
				(width 0)
				(type default)
			)
			(fill no)
			(layer "F.Fab")
		)
		(pad "1" smd custom
			(at 0 -0.4445 270)
			(size 0.1397 0.1397)
			(layers "F.Cu" "F.Mask" "F.Paste")
			(net "P12V")
			(options
				(clearance outline)
				(anchor circle)
			)
			(primitives
				(gr_poly
					(pts
						(arc
							(start -0.1778 -0.2794)
							(mid -0.249642 -0.249642)
							(end -0.2794 -0.1778)
						)
						(arc
							(start -0.2794 0.1778)
							(mid -0.249642 0.249642)
							(end -0.1778 0.2794)
						)
						(arc
							(start 0.1778 0.2794)
							(mid 0.249642 0.249642)
							(end 0.2794 0.1778)
						)
						(arc
							(start 0.2794 -0.1778)
							(mid 0.249642 -0.249642)
							(end 0.1778 -0.2794)
						)
					)
					(width 0)
					(fill yes)
				)
			)
		)
		(pad "2" smd custom
			(at 0 0.4445 270)
			(size 0.1397 0.1397)
			(layers "F.Cu" "F.Mask" "F.Paste")
			(net "FAN_TACH5")
			(options
				(clearance outline)
				(anchor circle)
			)
			(primitives
				(gr_poly
					(pts
						(arc
							(start -0.1778 -0.2794)
							(mid -0.249642 -0.249642)
							(end -0.2794 -0.1778)
						)
						(arc
							(start -0.2794 0.1778)
							(mid -0.249642 0.249642)
							(end -0.1778 0.2794)
						)
						(arc
							(start 0.1778 0.2794)
							(mid 0.249642 0.249642)
							(end 0.2794 0.1778)
						)
						(arc
							(start 0.2794 -0.1778)
							(mid 0.249642 -0.249642)
							(end 0.1778 -0.2794)
						)
					)
					(width 0)
					(fill yes)
				)
			)
		)
	)
	(footprint ""
		(layer "F.Cu")
		(at 18.796 -260.4516 -90)
		(property "Reference" "R80"
			(at 0 0 270)
			(layer "F.SilkS")
			(hide yes)
			(effects
				(font
					(size 1.27 1.27)
				)
			)
		)
		(property "Value" "4K7R2F-GP"
			(at 0.064008 -3.993896 270)
			(unlocked yes)
			(layer "F.Fab")
			(hide yes)
			(effects
				(font
					(size 1.016 1.016)
					(thickness 0.1524)
				)
			)
		)
		(property "Device Type" "R402H16"
			(at 0.064008 -5.517896 270)
			(unlocked yes)
			(layer "F.Fab")
			(hide yes)
			(effects
				(font
					(size 1.016 1.016)
					(thickness 0.1524)
				)
			)
		)
		(duplicate_pad_numbers_are_jumpers no)
		(fp_line
			(start -0.508 -0.9398)
			(end -0.508 0.9398)
			(stroke
				(width 0.1524)
				(type default)
			)
			(layer "F.SilkS")
		)
		(fp_line
			(start 0.508 -0.9398)
			(end -0.508 -0.9398)
			(stroke
				(width 0.1524)
				(type default)
			)
			(layer "F.SilkS")
		)
		(fp_rect
			(start -0.508 0.9398)
			(end 0.508 -0.9398)
			(stroke
				(width 0)
				(type default)
			)
			(fill no)
			(layer "F.CrtYd")
		)
		(fp_rect
			(start -0.508 0.9398)
			(end 0.508 -0.9398)
			(stroke
				(width 0)
				(type default)
			)
			(fill no)
			(layer "F.Fab")
		)
		(pad "1" smd custom
			(at 0 -0.4445 270)
			(size 0.1397 0.1397)
			(layers "F.Cu" "F.Mask" "F.Paste")
			(net "P12V")
			(options
				(clearance outline)
				(anchor circle)
			)
			(primitives
				(gr_poly
					(pts
						(arc
							(start -0.1778 -0.2794)
							(mid -0.249642 -0.249642)
							(end -0.2794 -0.1778)
						)
						(arc
							(start -0.2794 0.1778)
							(mid -0.249642 0.249642)
							(end -0.1778 0.2794)
						)
						(arc
							(start 0.1778 0.2794)
							(mid 0.249642 0.249642)
							(end 0.2794 0.1778)
						)
						(arc
							(start 0.2794 -0.1778)
							(mid 0.249642 -0.249642)
							(end 0.1778 -0.2794)
						)
					)
					(width 0)
					(fill yes)
				)
			)
		)
		(pad "2" smd custom
			(at 0 0.4445 270)
			(size 0.1397 0.1397)
			(layers "F.Cu" "F.Mask" "F.Paste")
			(net "FAN_TACH6")
			(options
				(clearance outline)
				(anchor circle)
			)
			(primitives
				(gr_poly
					(pts
						(arc
							(start -0.1778 -0.2794)
							(mid -0.249642 -0.249642)
							(end -0.2794 -0.1778)
						)
						(arc
							(start -0.2794 0.1778)
							(mid -0.249642 0.249642)
							(end -0.1778 0.2794)
						)
						(arc
							(start 0.1778 0.2794)
							(mid 0.249642 0.249642)
							(end 0.2794 0.1778)
						)
						(arc
							(start 0.2794 -0.1778)
							(mid 0.249642 -0.249642)
							(end 0.1778 -0.2794)
						)
					)
					(width 0)
					(fill yes)
				)
			)
		)
	)
	(footprint ""
		(layer "F.Cu")
		(at 7.949946 -56.099964 -90)
		(property "Reference" "LED6"
			(at 0 0 270)
			(layer "F.SilkS")
			(hide yes)
			(effects
				(font
					(size 1.27 1.27)
				)
			)
		)
		(property "Value" "LED-RB-6-GP"
			(at -4.6736 3.8354 270)
			(unlocked yes)
			(layer "F.Fab")
			(hide yes)
			(effects
				(font
					(size 1.016 1.016)
					(thickness 0.1524)
				)
			)
		)
		(property "Device Type" "LED-100-3P-067106H325"
			(at -4.6736 2.3114 270)
			(unlocked yes)
			(layer "F.Fab")
			(hide yes)
			(effects
				(font
					(size 1.016 1.016)
					(thickness 0.1524)
				)
			)
		)
		(duplicate_pad_numbers_are_jumpers no)
		(fp_line
			(start -1.7526 10.414)
			(end -1.7526 6.6548)
			(stroke
				(width 0.1524)
				(type default)
			)
			(layer "F.SilkS")
		)
		(fp_line
			(start 1.7526 10.414)
			(end -1.7526 10.414)
			(stroke
				(width 0.1524)
				(type default)
			)
			(layer "F.SilkS")
		)
		(fp_line
			(start -3.6068 6.6548)
			(end -3.6068 -0.889)
			(stroke
				(width 0.1524)
				(type default)
			)
			(layer "F.SilkS")
		)
		(fp_line
			(start -1.7526 6.6548)
			(end -3.6068 6.6548)
			(stroke
				(width 0.1524)
				(type default)
			)
			(layer "F.SilkS")
		)
		(fp_line
			(start 1.7526 6.6548)
			(end 1.7526 10.414)
			(stroke
				(width 0.1524)
				(type default)
			)
			(layer "F.SilkS")
		)
		(fp_line
			(start 3.6068 6.6548)
			(end 1.7526 6.6548)
			(stroke
				(width 0.1524)
				(type default)
			)
			(layer "F.SilkS")
		)
		(fp_line
			(start -3.6068 -0.889)
			(end 3.6068 -0.889)
			(stroke
				(width 0.1524)
				(type default)
			)
			(layer "F.SilkS")
		)
		(fp_line
			(start 3.6068 -0.889)
			(end 3.6068 6.6548)
			(stroke
				(width 0.1524)
				(type default)
			)
			(layer "F.SilkS")
		)
		(fp_circle
			(center -2.54 0)
			(end -2.54 -0.9906)
			(stroke
				(width 0.3048)
				(type default)
			)
			(fill no)
			(layer "F.SilkS")
		)
		(fp_circle
			(center 0 0)
			(end 0 -0.9906)
			(stroke
				(width 0.3048)
				(type default)
			)
			(fill no)
			(layer "F.SilkS")
		)
		(fp_circle
			(center 2.54 0)
			(end 2.54 -0.9906)
			(stroke
				(width 0.3048)
				(type default)
			)
			(fill no)
			(layer "F.SilkS")
		)
		(fp_poly
			(pts
				(xy -1.4986 10.1473) (xy -1.4986 6.4008) (xy -3.3528 6.4008) (xy -3.3528 -0.3937) (xy 3.3528 -0.3937)
				(xy 3.3528 6.4008) (xy 1.4986 6.4008) (xy 1.4986 10.1473)
			)
			(stroke
				(width 0)
				(type default)
			)
			(fill no)
			(layer "F.CrtYd")
		)
		(fp_poly
			(pts
				(xy -2.0066 10.668) (xy 2.0066 10.668) (xy 2.0066 6.9088) (xy 3.8608 6.9088) (xy 3.8608 2.2098)
				(xy 3.3528 2.2098) (xy 3.3528 6.4008) (xy 1.4986 6.4008) (xy 1.4986 10.1473) (xy -1.4986 10.1473)
				(xy -1.4986 6.4008) (xy -3.3528 6.4008) (xy -3.3528 -0.3937) (xy 3.3528 -0.3937) (xy 3.3528 2.1971)
				(xy 3.8608 2.1971) (xy 3.8608 -1.143) (xy -3.8608 -1.143) (xy -3.8608 6.9088) (xy -2.0066 6.9088)
			)
			(stroke
				(width 0)
				(type default)
			)
			(fill no)
			(layer "F.CrtYd")
		)
		(fp_poly
			(pts
				(xy -2.0066 10.668) (xy -2.0066 6.9088) (xy -3.8608 6.9088) (xy -3.8608 -1.143) (xy 3.8608 -1.143)
				(xy 3.8608 6.9088) (xy 2.0066 6.9088) (xy 2.0066 10.668)
			)
			(stroke
				(width 0)
				(type default)
			)
			(fill no)
			(layer "F.Fab")
		)
		(pad "1" thru_hole circle
			(at 2.54 0 270)
			(size 1.27 1.27)
			(drill 0.889)
			(layers "*.Cu" "*.Mask")
			(remove_unused_layers no)
			(net "LED_DR_LED5_BLUE")
			(clearance 0.1651)
			(thermal_gap 0.1651)
		)
		(pad "2" thru_hole circle
			(at 0 0 270)
			(size 1.27 1.27)
			(drill 0.889)
			(layers "*.Cu" "*.Mask")
			(remove_unused_layers no)
			(net "LED_DR_LED5_K")
			(clearance 0.1651)
			(thermal_gap 0.1651)
		)
		(pad "3" thru_hole circle
			(at -2.54 0 270)
			(size 1.27 1.27)
			(drill 0.889)
			(layers "*.Cu" "*.Mask")
			(remove_unused_layers no)
			(net "LED_DR_LED5")
			(clearance 0.1651)
			(thermal_gap 0.1651)
		)
	)
	(footprint ""
		(layer "F.Cu")
		(at 41.4274 -135.1534 -90)
		(property "Reference" "PR100"
			(at 0 0 270)
			(layer "F.SilkS")
			(hide yes)
			(effects
				(font
					(size 1.27 1.27)
				)
			)
		)
		(property "Value" "1MR3J-L-GP"
			(at -0.0254 -2.5146 270)
			(unlocked yes)
			(layer "F.Fab")
			(hide yes)
			(effects
				(font
					(size 1.016 1.016)
					(thickness 0.1524)
				)
			)
		)
		(property "Device Type" "R603H22"
			(at -0.0254 -4.0386 270)
			(unlocked yes)
			(layer "F.Fab")
			(hide yes)
			(effects
				(font
					(size 1.016 1.016)
					(thickness 0.1524)
				)
			)
		)
		(duplicate_pad_numbers_are_jumpers no)
		(fp_line
			(start -0.4826 0)
			(end -0.2032 0)
			(stroke
				(width 0.2032)
				(type default)
			)
			(layer "F.SilkS")
		)
		(fp_line
			(start 0.2032 0)
			(end 0.4826 0)
			(stroke
				(width 0.2032)
				(type default)
			)
			(layer "F.SilkS")
		)
		(fp_rect
			(start -0.5842 1.3335)
			(end 0.5842 -1.3335)
			(stroke
				(width 0)
				(type default)
			)
			(fill no)
			(layer "F.CrtYd")
		)
		(fp_rect
			(start -0.5842 1.3335)
			(end 0.5842 -1.3335)
			(stroke
				(width 0)
				(type default)
			)
			(fill no)
			(layer "F.Fab")
		)
		(pad "1" smd custom
			(at 0 -0.762 270)
			(size 0.2159 0.2159)
			(layers "F.Cu" "F.Mask" "F.Paste")
			(net "P12VL_2490_VCC")
			(options
				(clearance outline)
				(anchor circle)
			)
			(primitives
				(gr_poly
					(pts
						(arc
							(start -0.3302 -0.4318)
							(mid -0.402042 -0.402042)
							(end -0.4318 -0.3302)
						)
						(arc
							(start -0.4318 0.3302)
							(mid -0.402042 0.402042)
							(end -0.3302 0.4318)
						)
						(arc
							(start 0.3302 0.4318)
							(mid 0.402042 0.402042)
							(end 0.4318 0.3302)
						)
						(arc
							(start 0.4318 -0.3302)
							(mid 0.402042 -0.402042)
							(end 0.3302 -0.4318)
						)
					)
					(width 0)
					(fill yes)
				)
			)
		)
		(pad "2" smd custom
			(at 0 0.762 270)
			(size 0.2159 0.2159)
			(layers "F.Cu" "F.Mask" "F.Paste")
			(net "P12VL_2490_SENSE")
			(options
				(clearance outline)
				(anchor circle)
			)
			(primitives
				(gr_poly
					(pts
						(arc
							(start -0.3302 -0.4318)
							(mid -0.402042 -0.402042)
							(end -0.4318 -0.3302)
						)
						(arc
							(start -0.4318 0.3302)
							(mid -0.402042 0.402042)
							(end -0.3302 0.4318)
						)
						(arc
							(start 0.3302 0.4318)
							(mid 0.402042 0.402042)
							(end 0.4318 0.3302)
						)
						(arc
							(start 0.4318 -0.3302)
							(mid 0.402042 -0.402042)
							(end 0.3302 -0.4318)
						)
					)
					(width 0)
					(fill yes)
				)
			)
		)
	)
	(footprint ""
		(layer "F.Cu")
		(at 18.288 -122.555)
		(property "Reference" "PR60"
			(at 0 0 0)
			(layer "F.SilkS")
			(hide yes)
			(effects
				(font
					(size 1.27 1.27)
				)
			)
		)
		(property "Value" "D002R2512F-GP"
			(at -3.228594 -1.194054 0)
			(unlocked yes)
			(layer "F.Fab")
			(hide yes)
			(effects
				(font
					(size 1.016 1.016)
					(thickness 0.1524)
				)
			)
		)
		(property "Device Type" "R2512-2H32"
			(at -3.228594 -2.718054 0)
			(unlocked yes)
			(layer "F.Fab")
			(hide yes)
			(effects
				(font
					(size 1.016 1.016)
					(thickness 0.1524)
				)
			)
		)
		(duplicate_pad_numbers_are_jumpers no)
		(fp_line
			(start -1.9685 -3.81)
			(end 1.9685 -3.81)
			(stroke
				(width 0.1524)
				(type default)
			)
			(layer "F.SilkS")
		)
		(fp_line
			(start -1.9685 3.81)
			(end -1.9685 -3.81)
			(stroke
				(width 0.1524)
				(type default)
			)
			(layer "F.SilkS")
		)
		(fp_line
			(start 1.9685 -3.81)
			(end 1.9685 3.81)
			(stroke
				(width 0.1524)
				(type default)
			)
			(layer "F.SilkS")
		)
		(fp_line
			(start 1.9685 3.81)
			(end -1.9685 3.81)
			(stroke
				(width 0.1524)
				(type default)
			)
			(layer "F.SilkS")
		)
		(fp_rect
			(start -1.5875 3.175)
			(end 1.5875 -3.175)
			(stroke
				(width 0)
				(type default)
			)
			(fill no)
			(layer "F.CrtYd")
		)
		(fp_poly
			(pts
				(xy -2.2225 3.8862) (xy -2.2225 0.00254) (xy -1.5875 0.00254) (xy -1.5875 3.175) (xy 1.5875 3.175)
				(xy 1.5875 -3.175) (xy -1.5875 -3.175) (xy -1.5875 -0.00254) (xy -2.2225 -0.00254) (xy -2.2225 -3.8862)
				(xy 2.2225 -3.8862) (xy 2.2225 3.8862)
			)
			(stroke
				(width 0)
				(type default)
			)
			(fill no)
			(layer "F.CrtYd")
		)
		(fp_rect
			(start -2.2225 3.8862)
			(end 2.2225 -3.8862)
			(stroke
				(width 0)
				(type default)
			)
			(fill no)
			(layer "F.Fab")
		)
		(pad "1" smd rect
			(at 0 -2.273808)
			(size 3.429 2.5654)
			(layers "F.Cu" "F.Mask" "F.Paste")
			(net "P12V")
		)
		(pad "2" smd rect
			(at 0 2.273808)
			(size 3.429 2.5654)
			(layers "F.Cu" "F.Mask" "F.Paste")
			(net "P12VU_NET")
		)
	)
	(footprint ""
		(layer "F.Cu")
		(at 21.6916 -144.7546 -90)
		(property "Reference" "PR110"
			(at 0 0 270)
			(layer "F.SilkS")
			(hide yes)
			(effects
				(font
					(size 1.27 1.27)
				)
			)
		)
		(property "Value" "178KR2F-GP"
			(at 0.064008 -3.993896 270)
			(unlocked yes)
			(layer "F.Fab")
			(hide yes)
			(effects
				(font
					(size 1.016 1.016)
					(thickness 0.1524)
				)
			)
		)
		(property "Device Type" "R402H16"
			(at 0.064008 -5.517896 270)
			(unlocked yes)
			(layer "F.Fab")
			(hide yes)
			(effects
				(font
					(size 1.016 1.016)
					(thickness 0.1524)
				)
			)
		)
		(duplicate_pad_numbers_are_jumpers no)
		(fp_line
			(start -0.508 -0.9398)
			(end -0.508 0.9398)
			(stroke
				(width 0.1524)
				(type default)
			)
			(layer "F.SilkS")
		)
		(fp_line
			(start 0.508 -0.9398)
			(end -0.508 -0.9398)
			(stroke
				(width 0.1524)
				(type default)
			)
			(layer "F.SilkS")
		)
		(fp_rect
			(start -0.508 0.9398)
			(end 0.508 -0.9398)
			(stroke
				(width 0)
				(type default)
			)
			(fill no)
			(layer "F.CrtYd")
		)
		(fp_rect
			(start -0.508 0.9398)
			(end 0.508 -0.9398)
			(stroke
				(width 0)
				(type default)
			)
			(fill no)
			(layer "F.Fab")
		)
		(pad "1" smd custom
			(at 0 -0.4445 270)
			(size 0.1397 0.1397)
			(layers "F.Cu" "F.Mask" "F.Paste")
			(net "P12VU_2490_VREF")
			(options
				(clearance outline)
				(anchor circle)
			)
			(primitives
				(gr_poly
					(pts
						(arc
							(start -0.1778 -0.2794)
							(mid -0.249642 -0.249642)
							(end -0.2794 -0.1778)
						)
						(arc
							(start -0.2794 0.1778)
							(mid -0.249642 0.249642)
							(end -0.1778 0.2794)
						)
						(arc
							(start 0.1778 0.2794)
							(mid 0.249642 0.249642)
							(end 0.2794 0.1778)
						)
						(arc
							(start 0.2794 -0.1778)
							(mid 0.249642 -0.249642)
							(end 0.1778 -0.2794)
						)
					)
					(width 0)
					(fill yes)
				)
			)
		)
		(pad "2" smd custom
			(at 0 0.4445 270)
			(size 0.1397 0.1397)
			(layers "F.Cu" "F.Mask" "F.Paste")
			(net "P12VU_2490_PROG")
			(options
				(clearance outline)
				(anchor circle)
			)
			(primitives
				(gr_poly
					(pts
						(arc
							(start -0.1778 -0.2794)
							(mid -0.249642 -0.249642)
							(end -0.2794 -0.1778)
						)
						(arc
							(start -0.2794 0.1778)
							(mid -0.249642 0.249642)
							(end -0.1778 0.2794)
						)
						(arc
							(start 0.1778 0.2794)
							(mid 0.249642 0.249642)
							(end 0.2794 0.1778)
						)
						(arc
							(start 0.2794 -0.1778)
							(mid 0.249642 -0.249642)
							(end 0.1778 -0.2794)
						)
					)
					(width 0)
					(fill yes)
				)
			)
		)
	)
	(footprint ""
		(layer "F.Cu")
		(at 14.8844 -40.4622 90)
		(property "Reference" "R172"
			(at 0 0 90)
			(layer "F.SilkS")
			(hide yes)
			(effects
				(font
					(size 1.27 1.27)
				)
			)
		)
		(property "Value" "0R2J-2-GP"
			(at 0.064008 -3.993896 90)
			(unlocked yes)
			(layer "F.Fab")
			(hide yes)
			(effects
				(font
					(size 1.016 1.016)
					(thickness 0.1524)
				)
			)
		)
		(property "Device Type" "R402H16"
			(at 0.064008 -5.517896 90)
			(unlocked yes)
			(layer "F.Fab")
			(hide yes)
			(effects
				(font
					(size 1.016 1.016)
					(thickness 0.1524)
				)
			)
		)
		(duplicate_pad_numbers_are_jumpers no)
		(fp_line
			(start 0.508 -0.9398)
			(end -0.508 -0.9398)
			(stroke
				(width 0.1524)
				(type default)
			)
			(layer "F.SilkS")
		)
		(fp_line
			(start -0.508 -0.9398)
			(end -0.508 0.9398)
			(stroke
				(width 0.1524)
				(type default)
			)
			(layer "F.SilkS")
		)
		(fp_rect
			(start -0.508 0.9398)
			(end 0.508 -0.9398)
			(stroke
				(width 0)
				(type default)
			)
			(fill no)
			(layer "F.CrtYd")
		)
		(fp_rect
			(start -0.508 0.9398)
			(end 0.508 -0.9398)
			(stroke
				(width 0)
				(type default)
			)
			(fill no)
			(layer "F.Fab")
		)
		(pad "1" smd custom
			(at 0 -0.4445 90)
			(size 0.1397 0.1397)
			(layers "F.Cu" "F.Mask" "F.Paste")
			(net "SELF_1B_HB")
			(options
				(clearance outline)
				(anchor circle)
			)
			(primitives
				(gr_poly
					(pts
						(arc
							(start -0.1778 -0.2794)
							(mid -0.249642 -0.249642)
							(end -0.2794 -0.1778)
						)
						(arc
							(start -0.2794 0.1778)
							(mid -0.249642 0.249642)
							(end -0.1778 0.2794)
						)
						(arc
							(start 0.1778 0.2794)
							(mid 0.249642 0.249642)
							(end 0.2794 0.1778)
						)
						(arc
							(start 0.2794 -0.1778)
							(mid 0.249642 -0.249642)
							(end 0.1778 -0.2794)
						)
					)
					(width 0)
					(fill yes)
				)
			)
		)
		(pad "2" smd custom
			(at 0 0.4445 90)
			(size 0.1397 0.1397)
			(layers "F.Cu" "F.Mask" "F.Paste")
			(net "SEB_PEER_2B_HB")
			(options
				(clearance outline)
				(anchor circle)
			)
			(primitives
				(gr_poly
					(pts
						(arc
							(start -0.1778 -0.2794)
							(mid -0.249642 -0.249642)
							(end -0.2794 -0.1778)
						)
						(arc
							(start -0.2794 0.1778)
							(mid -0.249642 0.249642)
							(end -0.1778 0.2794)
						)
						(arc
							(start 0.1778 0.2794)
							(mid 0.249642 0.249642)
							(end 0.2794 0.1778)
						)
						(arc
							(start 0.2794 -0.1778)
							(mid 0.249642 -0.249642)
							(end 0.1778 -0.2794)
						)
					)
					(width 0)
					(fill yes)
				)
			)
		)
	)
	(footprint ""
		(layer "F.Cu")
		(at 15.9004 -62.865 180)
		(property "Reference" "R61"
			(at 0 0 180)
			(layer "F.SilkS")
			(hide yes)
			(effects
				(font
					(size 1.27 1.27)
				)
			)
		)
		(property "Value" "4K7R2F-GP"
			(at 0.064008 -3.993896 180)
			(unlocked yes)
			(layer "F.Fab")
			(hide yes)
			(effects
				(font
					(size 1.016 1.016)
					(thickness 0.1524)
				)
			)
		)
		(property "Device Type" "R402H16"
			(at 0.064008 -5.517896 180)
			(unlocked yes)
			(layer "F.Fab")
			(hide yes)
			(effects
				(font
					(size 1.016 1.016)
					(thickness 0.1524)
				)
			)
		)
		(duplicate_pad_numbers_are_jumpers no)
		(fp_line
			(start 0.508 -0.9398)
			(end -0.508 -0.9398)
			(stroke
				(width 0.1524)
				(type default)
			)
			(layer "F.SilkS")
		)
		(fp_line
			(start -0.508 -0.9398)
			(end -0.508 0.9398)
			(stroke
				(width 0.1524)
				(type default)
			)
			(layer "F.SilkS")
		)
		(fp_rect
			(start -0.508 0.9398)
			(end 0.508 -0.9398)
			(stroke
				(width 0)
				(type default)
			)
			(fill no)
			(layer "F.CrtYd")
		)
		(fp_rect
			(start -0.508 0.9398)
			(end 0.508 -0.9398)
			(stroke
				(width 0)
				(type default)
			)
			(fill no)
			(layer "F.Fab")
		)
		(pad "1" smd custom
			(at 0 -0.4445 180)
			(size 0.1397 0.1397)
			(layers "F.Cu" "F.Mask" "F.Paste")
			(net "P3V3")
			(options
				(clearance outline)
				(anchor circle)
			)
			(primitives
				(gr_poly
					(pts
						(arc
							(start -0.1778 -0.2794)
							(mid -0.249642 -0.249642)
							(end -0.2794 -0.1778)
						)
						(arc
							(start -0.2794 0.1778)
							(mid -0.249642 0.249642)
							(end -0.1778 0.2794)
						)
						(arc
							(start 0.1778 0.2794)
							(mid 0.249642 0.249642)
							(end 0.2794 0.1778)
						)
						(arc
							(start 0.2794 -0.1778)
							(mid 0.249642 -0.249642)
							(end 0.1778 -0.2794)
						)
					)
					(width 0)
					(fill yes)
				)
			)
		)
		(pad "2" smd custom
			(at 0 0.4445 180)
			(size 0.1397 0.1397)
			(layers "F.Cu" "F.Mask" "F.Paste")
			(net "I2C_C_SCL_CONN_R")
			(options
				(clearance outline)
				(anchor circle)
			)
			(primitives
				(gr_poly
					(pts
						(arc
							(start -0.1778 -0.2794)
							(mid -0.249642 -0.249642)
							(end -0.2794 -0.1778)
						)
						(arc
							(start -0.2794 0.1778)
							(mid -0.249642 0.249642)
							(end -0.1778 0.2794)
						)
						(arc
							(start 0.1778 0.2794)
							(mid 0.249642 0.249642)
							(end 0.2794 0.1778)
						)
						(arc
							(start 0.2794 -0.1778)
							(mid 0.249642 -0.249642)
							(end 0.1778 -0.2794)
						)
					)
					(width 0)
					(fill yes)
				)
			)
		)
	)
	(footprint ""
		(layer "F.Cu")
		(at 36.0426 -369.1382 -90)
		(property "Reference" "PR4"
			(at 0 0 270)
			(layer "F.SilkS")
			(hide yes)
			(effects
				(font
					(size 1.27 1.27)
				)
			)
		)
		(property "Value" "49K9R2F-L-GP"
			(at 0.064008 -3.993896 270)
			(unlocked yes)
			(layer "F.Fab")
			(hide yes)
			(effects
				(font
					(size 1.016 1.016)
					(thickness 0.1524)
				)
			)
		)
		(property "Device Type" "R402H16"
			(at 0.064008 -5.517896 270)
			(unlocked yes)
			(layer "F.Fab")
			(hide yes)
			(effects
				(font
					(size 1.016 1.016)
					(thickness 0.1524)
				)
			)
		)
		(duplicate_pad_numbers_are_jumpers no)
		(fp_line
			(start -0.508 -0.9398)
			(end -0.508 0.9398)
			(stroke
				(width 0.1524)
				(type default)
			)
			(layer "F.SilkS")
		)
		(fp_line
			(start 0.508 -0.9398)
			(end -0.508 -0.9398)
			(stroke
				(width 0.1524)
				(type default)
			)
			(layer "F.SilkS")
		)
		(fp_rect
			(start -0.508 0.9398)
			(end 0.508 -0.9398)
			(stroke
				(width 0)
				(type default)
			)
			(fill no)
			(layer "F.CrtYd")
		)
		(fp_rect
			(start -0.508 0.9398)
			(end 0.508 -0.9398)
			(stroke
				(width 0)
				(type default)
			)
			(fill no)
			(layer "F.Fab")
		)
		(pad "1" smd custom
			(at 0 -0.4445 270)
			(size 0.1397 0.1397)
			(layers "F.Cu" "F.Mask" "F.Paste")
			(net "P12V_AUX")
			(options
				(clearance outline)
				(anchor circle)
			)
			(primitives
				(gr_poly
					(pts
						(arc
							(start -0.1778 -0.2794)
							(mid -0.249642 -0.249642)
							(end -0.2794 -0.1778)
						)
						(arc
							(start -0.2794 0.1778)
							(mid -0.249642 0.249642)
							(end -0.1778 0.2794)
						)
						(arc
							(start 0.1778 0.2794)
							(mid 0.249642 0.249642)
							(end 0.2794 0.1778)
						)
						(arc
							(start 0.2794 -0.1778)
							(mid 0.249642 -0.249642)
							(end 0.1778 -0.2794)
						)
					)
					(width 0)
					(fill yes)
				)
			)
		)
		(pad "2" smd custom
			(at 0 0.4445 270)
			(size 0.1397 0.1397)
			(layers "F.Cu" "F.Mask" "F.Paste")
			(net "ADM1276_PWRGD")
			(options
				(clearance outline)
				(anchor circle)
			)
			(primitives
				(gr_poly
					(pts
						(arc
							(start -0.1778 -0.2794)
							(mid -0.249642 -0.249642)
							(end -0.2794 -0.1778)
						)
						(arc
							(start -0.2794 0.1778)
							(mid -0.249642 0.249642)
							(end -0.1778 0.2794)
						)
						(arc
							(start 0.1778 0.2794)
							(mid 0.249642 0.249642)
							(end 0.2794 0.1778)
						)
						(arc
							(start 0.2794 -0.1778)
							(mid 0.249642 -0.249642)
							(end 0.1778 -0.2794)
						)
					)
					(width 0)
					(fill yes)
				)
			)
		)
	)
	(footprint ""
		(layer "F.Cu")
		(at 14.5034 -248.1834)
		(property "Reference" "PR57"
			(at 0 0 0)
			(layer "F.SilkS")
			(hide yes)
			(effects
				(font
					(size 1.27 1.27)
				)
			)
		)
		(property "Value" "0R0603-PAD-2-GP"
			(at -0.0254 -2.3622 0)
			(unlocked yes)
			(layer "F.Fab")
			(hide yes)
			(effects
				(font
					(size 1.016 1.016)
					(thickness 0.1524)
				)
			)
		)
		(property "Device Type" "0R0603-PAD-1"
			(at -0.0254 -3.8862 0)
			(unlocked yes)
			(layer "F.Fab")
			(hide yes)
			(effects
				(font
					(size 1.016 1.016)
					(thickness 0.1524)
				)
			)
		)
		(duplicate_pad_numbers_are_jumpers no)
		(fp_line
			(start -0.6604 -1.3716)
			(end -0.6604 1.3716)
			(stroke
				(width 0.1524)
				(type default)
			)
			(layer "F.SilkS")
		)
		(fp_line
			(start 0.6604 -1.3716)
			(end -0.6604 -1.3716)
			(stroke
				(width 0.1524)
				(type default)
			)
			(layer "F.SilkS")
		)
		(fp_rect
			(start -0.6604 1.3716)
			(end 0.6604 -1.3716)
			(stroke
				(width 0)
				(type default)
			)
			(fill no)
			(layer "F.CrtYd")
		)
		(fp_rect
			(start -0.6604 1.3716)
			(end 0.6604 -1.3716)
			(stroke
				(width 0)
				(type default)
			)
			(fill no)
			(layer "F.Fab")
		)
		(pad "1" smd custom
			(at 0 -0.8509)
			(size 0.2159 0.2159)
			(layers "F.Cu" "F.Mask" "F.Paste")
			(net "P12V")
			(options
				(clearance outline)
				(anchor circle)
			)
			(primitives
				(gr_poly
					(pts
						(arc
							(start 0.4318 0.4826)
							(mid 0.402042 0.554442)
							(end 0.3302 0.5842)
						)
						(arc
							(start -0.3302 0.5842)
							(mid -0.402042 0.554442)
							(end -0.4318 0.4826)
						)
						(arc
							(start -0.4318 -0.4826)
							(mid -0.402042 -0.554442)
							(end -0.3302 -0.5842)
						)
						(arc
							(start 0.3302 -0.5842)
							(mid 0.402042 -0.554442)
							(end 0.4318 -0.4826)
						)
					)
					(width 0)
					(fill yes)
				)
			)
		)
		(pad "2" smd custom
			(at 0 0.6731)
			(size 0.2159 0.2159)
			(layers "F.Cu" "F.Mask" "F.Paste")
			(net "P3V3_IN")
			(options
				(clearance outline)
				(anchor circle)
			)
			(primitives
				(gr_poly
					(pts
						(arc
							(start -0.3302 0.5842)
							(mid -0.402042 0.554442)
							(end -0.4318 0.4826)
						)
						(arc
							(start -0.4318 -0.4826)
							(mid -0.402042 -0.554442)
							(end -0.3302 -0.5842)
						)
						(arc
							(start 0.3302 -0.5842)
							(mid 0.402042 -0.554442)
							(end 0.4318 -0.4826)
						)
						(arc
							(start 0.4318 0.4826)
							(mid 0.402042 0.554442)
							(end 0.3302 0.5842)
						)
					)
					(width 0)
					(fill yes)
				)
			)
		)
	)
	(footprint ""
		(layer "F.Cu")
		(at 40.8178 -156.4386 180)
		(property "Reference" "TP17"
			(at 0 0 180)
			(layer "F.SilkS")
			(hide yes)
			(effects
				(font
					(size 1.27 1.27)
				)
			)
		)
		(property "Value" "TPAD32-GP"
			(at 0 -3.166364 180)
			(unlocked yes)
			(layer "F.Fab")
			(hide yes)
			(effects
				(font
					(size 1.016 1.016)
					(thickness 0.1524)
				)
			)
		)
		(property "Device Type" "TPAD32"
			(at 0 -4.690618 180)
			(unlocked yes)
			(layer "F.Fab")
			(hide yes)
			(effects
				(font
					(size 1.016 1.016)
					(thickness 0.1524)
				)
			)
		)
		(duplicate_pad_numbers_are_jumpers no)
		(fp_poly
			(pts
				(arc
					(start -0.7112 0)
					(mid 0.7112 0)
					(end -0.7112 0)
				)
			)
			(stroke
				(width 0)
				(type default)
			)
			(fill no)
			(layer "F.CrtYd")
		)
		(fp_poly
			(pts
				(arc
					(start -0.7112 0)
					(mid 0.7112 0)
					(end -0.7112 0)
				)
			)
			(stroke
				(width 0)
				(type default)
			)
			(fill no)
			(layer "F.Fab")
		)
		(pad "1" smd circle
			(at 0 0 180)
			(size 0.8128 0.8128)
			(layers "F.Cu" "F.Mask" "F.Paste")
			(net "NCT7904_PROCHOT")
		)
	)
	(footprint ""
		(layer "F.Cu")
		(at 6.999986 -459.999842)
		(property "Reference" "H5"
			(at 0 0 0)
			(layer "F.SilkS")
			(hide yes)
			(effects
				(font
					(size 1.27 1.27)
				)
			)
		)
		(property "Value" "HOLE315R138"
			(at 0 -7.0612 0)
			(unlocked yes)
			(layer "F.Fab")
			(hide yes)
			(effects
				(font
					(size 1.016 1.016)
					(thickness 0.1524)
				)
			)
		)
		(property "Device Type" "HOLE315R138"
			(at 0 -8.5852 0)
			(unlocked yes)
			(layer "F.Fab")
			(hide yes)
			(effects
				(font
					(size 1.016 1.016)
					(thickness 0.1524)
				)
			)
		)
		(duplicate_pad_numbers_are_jumpers no)
		(fp_poly
			(pts
				(xy 0 4.3053) (xy -0.13462 4.30276) (xy -0.27051 4.29641) (xy -0.40513 4.28625) (xy -0.53975 4.27101)
				(xy -0.6731 4.25196) (xy -0.80645 4.2291) (xy -0.9398 4.20116) (xy -1.07061 4.17068) (xy -1.20142 4.13385)
				(xy -1.33096 4.09448) (xy -1.45796 4.0513) (xy -1.58496 4.00304) (xy -1.70942 3.95097) (xy -1.83261 3.89509)
				(xy -1.95453 3.83667) (xy -2.07391 3.77317) (xy -2.19202 3.70586) (xy -2.30632 3.63474) (xy -2.41935 3.56108)
				(xy -2.53111 3.48361) (xy -2.63906 3.40233) (xy -2.74447 3.31724) (xy -2.84734 3.22961) (xy -2.94767 3.13817)
				(xy -3.04419 3.04419) (xy -3.13817 2.94767) (xy -3.22961 2.84734) (xy -3.31724 2.74447) (xy -3.40233 2.63906)
				(xy -3.48361 2.53111) (xy -3.56108 2.41935) (xy -3.63474 2.30632) (xy -3.70586 2.19202) (xy -3.77317 2.07391)
				(xy -3.83667 1.95453) (xy -3.89509 1.83261) (xy -3.95097 1.70942) (xy -4.00304 1.58496) (xy -4.0513 1.45796)
				(xy -4.09448 1.33096) (xy -4.13385 1.20142) (xy -4.17068 1.07061) (xy -4.20116 0.9398) (xy -4.2291 0.80645)
				(xy -4.25196 0.6731) (xy -4.27101 0.53975) (xy -4.28625 0.40513) (xy -4.29641 0.27051) (xy -4.30276 0.13462)
				(xy -4.3053 0) (xy -4.30276 -0.13462) (xy -4.29641 -0.27051) (xy -4.28625 -0.40513) (xy -4.27101 -0.53975)
				(xy -4.25196 -0.6731) (xy -4.2291 -0.80645) (xy -4.20116 -0.9398) (xy -4.17068 -1.07061) (xy -4.13385 -1.20142)
				(xy -4.09448 -1.33096) (xy -4.0513 -1.45796) (xy -4.00304 -1.58496) (xy -3.95097 -1.70942) (xy -3.89509 -1.83261)
				(xy -3.83667 -1.95453) (xy -3.77317 -2.07391) (xy -3.70586 -2.19202) (xy -3.63474 -2.30632) (xy -3.56108 -2.41935)
				(xy -3.48361 -2.53111) (xy -3.40233 -2.63906) (xy -3.31724 -2.74447) (xy -3.22961 -2.84734) (xy -3.13817 -2.94767)
				(xy -3.04419 -3.04419) (xy -2.94767 -3.13817) (xy -2.84734 -3.22961) (xy -2.74447 -3.31724) (xy -2.63906 -3.40233)
				(xy -2.53111 -3.48361) (xy -2.41935 -3.56108) (xy -2.30632 -3.63474) (xy -2.19202 -3.70586) (xy -2.07391 -3.77317)
				(xy -1.95453 -3.83667) (xy -1.83261 -3.89509) (xy -1.70942 -3.95097) (xy -1.58496 -4.00304) (xy -1.45796 -4.0513)
				(xy -1.33096 -4.09448) (xy -1.20142 -4.13385) (xy -1.07061 -4.17068) (xy -0.9398 -4.20116) (xy -0.80645 -4.2291)
				(xy -0.6731 -4.25196) (xy -0.53975 -4.27101) (xy -0.40513 -4.28625) (xy -0.27051 -4.29641) (xy -0.13462 -4.30276)
				(xy 0 -4.3053) (xy 0.13462 -4.30276) (xy 0.27051 -4.29641) (xy 0.40513 -4.28625) (xy 0.53975 -4.27101)
				(xy 0.6731 -4.25196) (xy 0.80645 -4.2291) (xy 0.9398 -4.20116) (xy 1.07061 -4.17068) (xy 1.20142 -4.13385)
				(xy 1.33096 -4.09448) (xy 1.45796 -4.0513) (xy 1.58496 -4.00304) (xy 1.70942 -3.95097) (xy 1.83261 -3.89509)
				(xy 1.95453 -3.83667) (xy 2.07391 -3.77317) (xy 2.19202 -3.70586) (xy 2.30632 -3.63474) (xy 2.41935 -3.56108)
				(xy 2.53111 -3.48361) (xy 2.63906 -3.40233) (xy 2.74447 -3.31724) (xy 2.84734 -3.22961) (xy 2.94767 -3.13817)
				(xy 3.04419 -3.04419) (xy 3.13817 -2.94767) (xy 3.22961 -2.84734) (xy 3.31724 -2.74447) (xy 3.40233 -2.63906)
				(xy 3.48361 -2.53111) (xy 3.56108 -2.41935) (xy 3.63474 -2.30632) (xy 3.70586 -2.19202) (xy 3.77317 -2.07391)
				(xy 3.83667 -1.95453) (xy 3.89509 -1.83261) (xy 3.95097 -1.70942) (xy 4.00304 -1.58496) (xy 4.0513 -1.45796)
				(xy 4.09448 -1.33096) (xy 4.13385 -1.20142) (xy 4.17068 -1.07061) (xy 4.20116 -0.9398) (xy 4.2291 -0.80645)
				(xy 4.25196 -0.6731) (xy 4.27101 -0.53975) (xy 4.28625 -0.40513) (xy 4.29641 -0.27051) (xy 4.30276 -0.13462)
				(xy 4.3053 0) (xy 4.30276 0.13462) (xy 4.29641 0.27051) (xy 4.28625 0.40513) (xy 4.27101 0.53975)
				(xy 4.25196 0.6731) (xy 4.2291 0.80645) (xy 4.20116 0.9398) (xy 4.17068 1.07061) (xy 4.13385 1.20142)
				(xy 4.09448 1.33096) (xy 4.0513 1.45796) (xy 4.00304 1.58496) (xy 3.95097 1.70942) (xy 3.89509 1.83261)
				(xy 3.83667 1.95453) (xy 3.77317 2.07391) (xy 3.70586 2.19202) (xy 3.63474 2.30632) (xy 3.56108 2.41935)
				(xy 3.48361 2.53111) (xy 3.40233 2.63906) (xy 3.31724 2.74447) (xy 3.22961 2.84734) (xy 3.13817 2.94767)
				(xy 3.04419 3.04419) (xy 2.94767 3.13817) (xy 2.84734 3.22961) (xy 2.74447 3.31724) (xy 2.63906 3.40233)
				(xy 2.53111 3.48361) (xy 2.41935 3.56108) (xy 2.30632 3.63474) (xy 2.19202 3.70586) (xy 2.07391 3.77317)
				(xy 1.95453 3.83667) (xy 1.83261 3.89509) (xy 1.70942 3.95097) (xy 1.58496 4.00304) (xy 1.45796 4.0513)
				(xy 1.33096 4.09448) (xy 1.20142 4.13385) (xy 1.07061 4.17068) (xy 0.9398 4.20116) (xy 0.80645 4.2291)
				(xy 0.6731 4.25196) (xy 0.53975 4.27101) (xy 0.40513 4.28625) (xy 0.27051 4.29641) (xy 0.13462 4.30276)
			)
			(stroke
				(width 0)
				(type default)
			)
			(fill no)
			(layer "F.CrtYd")
		)
		(fp_poly
			(pts
				(xy 0 4.3053) (xy -0.13462 4.30276) (xy -0.27051 4.29641) (xy -0.40513 4.28625) (xy -0.53975 4.27101)
				(xy -0.6731 4.25196) (xy -0.80645 4.2291) (xy -0.9398 4.20116) (xy -1.07061 4.17068) (xy -1.20142 4.13385)
				(xy -1.33096 4.09448) (xy -1.45796 4.0513) (xy -1.58496 4.00304) (xy -1.70942 3.95097) (xy -1.83261 3.89509)
				(xy -1.95453 3.83667) (xy -2.07391 3.77317) (xy -2.19202 3.70586) (xy -2.30632 3.63474) (xy -2.41935 3.56108)
				(xy -2.53111 3.48361) (xy -2.63906 3.40233) (xy -2.74447 3.31724) (xy -2.84734 3.22961) (xy -2.94767 3.13817)
				(xy -3.04419 3.04419) (xy -3.13817 2.94767) (xy -3.22961 2.84734) (xy -3.31724 2.74447) (xy -3.40233 2.63906)
				(xy -3.48361 2.53111) (xy -3.56108 2.41935) (xy -3.63474 2.30632) (xy -3.70586 2.19202) (xy -3.77317 2.07391)
				(xy -3.83667 1.95453) (xy -3.89509 1.83261) (xy -3.95097 1.70942) (xy -4.00304 1.58496) (xy -4.0513 1.45796)
				(xy -4.09448 1.33096) (xy -4.13385 1.20142) (xy -4.17068 1.07061) (xy -4.20116 0.9398) (xy -4.2291 0.80645)
				(xy -4.25196 0.6731) (xy -4.27101 0.53975) (xy -4.28625 0.40513) (xy -4.29641 0.27051) (xy -4.30276 0.13462)
				(xy -4.3053 0) (xy -4.30276 -0.13462) (xy -4.29641 -0.27051) (xy -4.28625 -0.40513) (xy -4.27101 -0.53975)
				(xy -4.25196 -0.6731) (xy -4.2291 -0.80645) (xy -4.20116 -0.9398) (xy -4.17068 -1.07061) (xy -4.13385 -1.20142)
				(xy -4.09448 -1.33096) (xy -4.0513 -1.45796) (xy -4.00304 -1.58496) (xy -3.95097 -1.70942) (xy -3.89509 -1.83261)
				(xy -3.83667 -1.95453) (xy -3.77317 -2.07391) (xy -3.70586 -2.19202) (xy -3.63474 -2.30632) (xy -3.56108 -2.41935)
				(xy -3.48361 -2.53111) (xy -3.40233 -2.63906) (xy -3.31724 -2.74447) (xy -3.22961 -2.84734) (xy -3.13817 -2.94767)
				(xy -3.04419 -3.04419) (xy -2.94767 -3.13817) (xy -2.84734 -3.22961) (xy -2.74447 -3.31724) (xy -2.63906 -3.40233)
				(xy -2.53111 -3.48361) (xy -2.41935 -3.56108) (xy -2.30632 -3.63474) (xy -2.19202 -3.70586) (xy -2.07391 -3.77317)
				(xy -1.95453 -3.83667) (xy -1.83261 -3.89509) (xy -1.70942 -3.95097) (xy -1.58496 -4.00304) (xy -1.45796 -4.0513)
				(xy -1.33096 -4.09448) (xy -1.20142 -4.13385) (xy -1.07061 -4.17068) (xy -0.9398 -4.20116) (xy -0.80645 -4.2291)
				(xy -0.6731 -4.25196) (xy -0.53975 -4.27101) (xy -0.40513 -4.28625) (xy -0.27051 -4.29641) (xy -0.13462 -4.30276)
				(xy 0 -4.3053) (xy 0.13462 -4.30276) (xy 0.27051 -4.29641) (xy 0.40513 -4.28625) (xy 0.53975 -4.27101)
				(xy 0.6731 -4.25196) (xy 0.80645 -4.2291) (xy 0.9398 -4.20116) (xy 1.07061 -4.17068) (xy 1.20142 -4.13385)
				(xy 1.33096 -4.09448) (xy 1.45796 -4.0513) (xy 1.58496 -4.00304) (xy 1.70942 -3.95097) (xy 1.83261 -3.89509)
				(xy 1.95453 -3.83667) (xy 2.07391 -3.77317) (xy 2.19202 -3.70586) (xy 2.30632 -3.63474) (xy 2.41935 -3.56108)
				(xy 2.53111 -3.48361) (xy 2.63906 -3.40233) (xy 2.74447 -3.31724) (xy 2.84734 -3.22961) (xy 2.94767 -3.13817)
				(xy 3.04419 -3.04419) (xy 3.13817 -2.94767) (xy 3.22961 -2.84734) (xy 3.31724 -2.74447) (xy 3.40233 -2.63906)
				(xy 3.48361 -2.53111) (xy 3.56108 -2.41935) (xy 3.63474 -2.30632) (xy 3.70586 -2.19202) (xy 3.77317 -2.07391)
				(xy 3.83667 -1.95453) (xy 3.89509 -1.83261) (xy 3.95097 -1.70942) (xy 4.00304 -1.58496) (xy 4.0513 -1.45796)
				(xy 4.09448 -1.33096) (xy 4.13385 -1.20142) (xy 4.17068 -1.07061) (xy 4.20116 -0.9398) (xy 4.2291 -0.80645)
				(xy 4.25196 -0.6731) (xy 4.27101 -0.53975) (xy 4.28625 -0.40513) (xy 4.29641 -0.27051) (xy 4.30276 -0.13462)
				(xy 4.3053 0) (xy 4.30276 0.13462) (xy 4.29641 0.27051) (xy 4.28625 0.40513) (xy 4.27101 0.53975)
				(xy 4.25196 0.6731) (xy 4.2291 0.80645) (xy 4.20116 0.9398) (xy 4.17068 1.07061) (xy 4.13385 1.20142)
				(xy 4.09448 1.33096) (xy 4.0513 1.45796) (xy 4.00304 1.58496) (xy 3.95097 1.70942) (xy 3.89509 1.83261)
				(xy 3.83667 1.95453) (xy 3.77317 2.07391) (xy 3.70586 2.19202) (xy 3.63474 2.30632) (xy 3.56108 2.41935)
				(xy 3.48361 2.53111) (xy 3.40233 2.63906) (xy 3.31724 2.74447) (xy 3.22961 2.84734) (xy 3.13817 2.94767)
				(xy 3.04419 3.04419) (xy 2.94767 3.13817) (xy 2.84734 3.22961) (xy 2.74447 3.31724) (xy 2.63906 3.40233)
				(xy 2.53111 3.48361) (xy 2.41935 3.56108) (xy 2.30632 3.63474) (xy 2.19202 3.70586) (xy 2.07391 3.77317)
				(xy 1.95453 3.83667) (xy 1.83261 3.89509) (xy 1.70942 3.95097) (xy 1.58496 4.00304) (xy 1.45796 4.0513)
				(xy 1.33096 4.09448) (xy 1.20142 4.13385) (xy 1.07061 4.17068) (xy 0.9398 4.20116) (xy 0.80645 4.2291)
				(xy 0.6731 4.25196) (xy 0.53975 4.27101) (xy 0.40513 4.28625) (xy 0.27051 4.29641) (xy 0.13462 4.30276)
			)
			(stroke
				(width 0)
				(type default)
			)
			(fill no)
			(layer "F.Fab")
		)
		(pad "1" thru_hole circle
			(at 0 0)
			(size 8.001 8.001)
			(drill 3.5052)
			(layers "*.Cu" "*.Mask")
			(remove_unused_layers no)
			(net "GND")
			(clearance -1.7399)
			(thermal_gap 0.3048)
			(padstack
				(mode front_inner_back)
				(layer "Inner"
					(shape circle)
					(size 3.9116 3.9116)
					(clearance 0.3048)
				)
				(layer "B.Cu"
					(shape circle)
					(size 8.001 8.001)
					(clearance -1.7399)
				)
			)
		)
	)
	(footprint ""
		(layer "F.Cu")
		(at 37.211 -378.333 180)
		(property "Reference" "PR27"
			(at 0 0 180)
			(layer "F.SilkS")
			(hide yes)
			(effects
				(font
					(size 1.27 1.27)
				)
			)
		)
		(property "Value" "10R2F-L-GP"
			(at 0.064008 -3.993896 180)
			(unlocked yes)
			(layer "F.Fab")
			(hide yes)
			(effects
				(font
					(size 1.016 1.016)
					(thickness 0.1524)
				)
			)
		)
		(property "Device Type" "R402H14"
			(at 0.064008 -5.517896 180)
			(unlocked yes)
			(layer "F.Fab")
			(hide yes)
			(effects
				(font
					(size 1.016 1.016)
					(thickness 0.1524)
				)
			)
		)
		(duplicate_pad_numbers_are_jumpers no)
		(fp_line
			(start 0.508 -0.9398)
			(end -0.508 -0.9398)
			(stroke
				(width 0.1524)
				(type default)
			)
			(layer "F.SilkS")
		)
		(fp_line
			(start -0.508 -0.9398)
			(end -0.508 0.9398)
			(stroke
				(width 0.1524)
				(type default)
			)
			(layer "F.SilkS")
		)
		(fp_rect
			(start -0.508 0.9398)
			(end 0.508 -0.9398)
			(stroke
				(width 0)
				(type default)
			)
			(fill no)
			(layer "F.CrtYd")
		)
		(fp_rect
			(start -0.508 0.9398)
			(end 0.508 -0.9398)
			(stroke
				(width 0)
				(type default)
			)
			(fill no)
			(layer "F.Fab")
		)
		(pad "1" smd custom
			(at 0 -0.4445 180)
			(size 0.1397 0.1397)
			(layers "F.Cu" "F.Mask" "F.Paste")
			(net "ADM1276_GATE")
			(options
				(clearance outline)
				(anchor circle)
			)
			(primitives
				(gr_poly
					(pts
						(arc
							(start -0.1778 -0.2794)
							(mid -0.249642 -0.249642)
							(end -0.2794 -0.1778)
						)
						(arc
							(start -0.2794 0.1778)
							(mid -0.249642 0.249642)
							(end -0.1778 0.2794)
						)
						(arc
							(start 0.1778 0.2794)
							(mid 0.249642 0.249642)
							(end 0.2794 0.1778)
						)
						(arc
							(start 0.2794 -0.1778)
							(mid 0.249642 -0.249642)
							(end 0.1778 -0.2794)
						)
					)
					(width 0)
					(fill yes)
				)
			)
		)
		(pad "2" smd custom
			(at 0 0.4445 180)
			(size 0.1397 0.1397)
			(layers "F.Cu" "F.Mask" "F.Paste")
			(net "ADM1276_GATE_DRV2")
			(options
				(clearance outline)
				(anchor circle)
			)
			(primitives
				(gr_poly
					(pts
						(arc
							(start -0.1778 -0.2794)
							(mid -0.249642 -0.249642)
							(end -0.2794 -0.1778)
						)
						(arc
							(start -0.2794 0.1778)
							(mid -0.249642 0.249642)
							(end -0.1778 0.2794)
						)
						(arc
							(start 0.1778 0.2794)
							(mid 0.249642 0.249642)
							(end 0.2794 0.1778)
						)
						(arc
							(start 0.2794 -0.1778)
							(mid 0.249642 -0.249642)
							(end 0.1778 -0.2794)
						)
					)
					(width 0)
					(fill yes)
				)
			)
		)
	)
	(footprint ""
		(layer "F.Cu")
		(at 22.733 -372.237 180)
		(property "Reference" "PC9"
			(at 0 0 180)
			(layer "F.SilkS")
			(hide yes)
			(effects
				(font
					(size 1.27 1.27)
				)
			)
		)
		(property "Value" "SC1U25V5KX-1GP"
			(at -0.0762 -6.1214 180)
			(unlocked yes)
			(layer "F.Fab")
			(hide yes)
			(effects
				(font
					(size 1.016 1.016)
					(thickness 0.1524)
				)
			)
		)
		(property "Device Type" "C805H58"
			(at -0.0762 -8.1534 180)
			(unlocked yes)
			(layer "F.Fab")
			(hide yes)
			(effects
				(font
					(size 1.016 1.016)
					(thickness 0.1524)
				)
			)
		)
		(duplicate_pad_numbers_are_jumpers no)
		(fp_line
			(start 0.635 0)
			(end -0.635 0)
			(stroke
				(width 0.508)
				(type default)
			)
			(layer "F.SilkS")
		)
		(fp_rect
			(start -0.9652 1.778)
			(end 0.9652 -1.778)
			(stroke
				(width 0)
				(type default)
			)
			(fill no)
			(layer "F.CrtYd")
		)
		(fp_poly
			(pts
				(xy -0.9652 -1.778) (xy 0.9652 -1.778) (xy 0.9652 1.778) (xy -0.9652 1.778)
			)
			(stroke
				(width 0)
				(type default)
			)
			(fill no)
			(layer "F.Fab")
		)
		(pad "1" smd rect
			(at 0 -0.9652 180)
			(size 1.397 1.143)
			(layers "F.Cu" "F.Mask" "F.Paste")
			(net "ADM1276_OV")
		)
		(pad "2" smd rect
			(at 0 0.9652 180)
			(size 1.397 1.143)
			(layers "F.Cu" "F.Mask" "F.Paste")
			(net "GND")
		)
	)
	(footprint ""
		(layer "F.Cu")
		(at 21.8948 -197.2818 90)
		(property "Reference" "R180"
			(at 0 0 90)
			(layer "F.SilkS")
			(hide yes)
			(effects
				(font
					(size 1.27 1.27)
				)
			)
		)
		(property "Value" "0R1206-PAD-1-GP"
			(at 0 -5.0292 90)
			(unlocked yes)
			(layer "F.Fab")
			(hide yes)
			(effects
				(font
					(size 1.016 1.016)
					(thickness 0.1524)
				)
			)
		)
		(property "Device Type" "0R1206-PAD-1"
			(at 0 -6.5532 90)
			(unlocked yes)
			(layer "F.Fab")
			(hide yes)
			(effects
				(font
					(size 1.016 1.016)
					(thickness 0.1524)
				)
			)
		)
		(duplicate_pad_numbers_are_jumpers no)
		(fp_line
			(start 1.016 -2.2352)
			(end -1.016 -2.2352)
			(stroke
				(width 0.1524)
				(type default)
			)
			(layer "F.SilkS")
		)
		(fp_line
			(start -1.016 -2.2352)
			(end -1.016 2.2352)
			(stroke
				(width 0.1524)
				(type default)
			)
			(layer "F.SilkS")
		)
		(fp_line
			(start 1.016 2.2352)
			(end 1.016 -2.2352)
			(stroke
				(width 0.1524)
				(type default)
			)
			(layer "F.SilkS")
		)
		(fp_line
			(start -1.016 2.2352)
			(end 1.016 2.2352)
			(stroke
				(width 0.1524)
				(type default)
			)
			(layer "F.SilkS")
		)
		(fp_rect
			(start -1.0922 2.3114)
			(end 1.0922 -2.3114)
			(stroke
				(width 0)
				(type default)
			)
			(fill no)
			(layer "F.CrtYd")
		)
		(fp_poly
			(pts
				(xy -1.0922 -2.3114) (xy 1.0922 -2.3114) (xy 1.0922 2.3114) (xy -1.0922 2.3114)
			)
			(stroke
				(width 0)
				(type default)
			)
			(fill no)
			(layer "F.Fab")
		)
		(pad "1" smd rect
			(at 0 -1.397 90)
			(size 1.651 2.0574)
			(drill
				(offset 0 0.3937)
			)
			(layers "F.Cu" "F.Mask" "F.Paste")
			(net "P12V_FAN4")
		)
		(pad "2" smd rect
			(at 0 1.397 90)
			(size 1.651 2.0574)
			(drill
				(offset 0 -0.3937)
			)
			(layers "F.Cu" "F.Mask" "F.Paste")
			(net "P12V")
		)
	)
	(footprint ""
		(layer "F.Cu")
		(at 34.544 -400.177)
		(property "Reference" "PQ2"
			(at 0 0 0)
			(layer "F.SilkS")
			(hide yes)
			(effects
				(font
					(size 1.27 1.27)
				)
			)
		)
		(property "Value" "PH0925CL-GP"
			(at -4.2799 -0.4572 0)
			(unlocked yes)
			(layer "F.Fab")
			(hide yes)
			(effects
				(font
					(size 1.016 1.016)
					(thickness 0.1524)
				)
			)
		)
		(property "Device Type" "LFPAK-5PH48-U"
			(at -4.2799 -1.9812 0)
			(unlocked yes)
			(layer "F.Fab")
			(hide yes)
			(effects
				(font
					(size 1.016 1.016)
					(thickness 0.1524)
				)
			)
		)
		(duplicate_pad_numbers_are_jumpers no)
		(fp_line
			(start -2.7559 -6.5532)
			(end -2.7559 1.0668)
			(stroke
				(width 0.1524)
				(type default)
			)
			(layer "F.SilkS")
		)
		(fp_line
			(start -2.7559 1.0668)
			(end 2.7559 1.0668)
			(stroke
				(width 0.1524)
				(type default)
			)
			(layer "F.SilkS")
		)
		(fp_line
			(start -1.7272 1.1684)
			(end -2.1082 1.1684)
			(stroke
				(width 0.3302)
				(type default)
			)
			(layer "F.SilkS")
		)
		(fp_line
			(start 2.7559 -6.5532)
			(end -2.7559 -6.5532)
			(stroke
				(width 0.1524)
				(type default)
			)
			(layer "F.SilkS")
		)
		(fp_line
			(start 2.7559 1.0668)
			(end 2.7559 -6.5532)
			(stroke
				(width 0.1524)
				(type default)
			)
			(layer "F.SilkS")
		)
		(fp_poly
			(pts
				(xy -2.3368 1.5748) (xy -1.905 1.143) (xy -1.4732 1.5748)
			)
			(stroke
				(width 0)
				(type default)
			)
			(fill yes)
			(layer "F.SilkS")
		)
		(fp_poly
			(pts
				(xy -2.5019 -4.02971) (xy -0.3302 -4.02971) (xy -0.3302 -6.30301) (xy -2.5019 -6.30301)
			)
			(stroke
				(width 0)
				(type default)
			)
			(fill yes)
			(layer "F.Paste")
		)
		(fp_poly
			(pts
				(xy -2.5019 -1.09601) (xy -0.3302 -1.09601) (xy -0.3302 -3.36931) (xy -2.5019 -3.36931)
			)
			(stroke
				(width 0)
				(type default)
			)
			(fill yes)
			(layer "F.Paste")
		)
		(fp_poly
			(pts
				(xy 0.3302 -4.02971) (xy 2.5019 -4.02971) (xy 2.5019 -6.30301) (xy 0.3302 -6.30301)
			)
			(stroke
				(width 0)
				(type default)
			)
			(fill yes)
			(layer "F.Paste")
		)
		(fp_poly
			(pts
				(xy 0.3302 -1.09601) (xy 2.5019 -1.09601) (xy 2.5019 -3.36931) (xy 0.3302 -3.36931)
			)
			(stroke
				(width 0)
				(type default)
			)
			(fill yes)
			(layer "F.Paste")
		)
		(fp_rect
			(start -2.4511 0.3048)
			(end 2.4511 -5.6896)
			(stroke
				(width 0)
				(type default)
			)
			(fill no)
			(layer "F.CrtYd")
		)
		(fp_poly
			(pts
				(xy -3.0099 1.3208) (xy -3.0099 -6.8072) (xy 3.0099 -6.8072) (xy 3.0099 -1.016) (xy 2.4511 -1.016)
				(xy 2.4511 -5.6896) (xy -2.4511 -5.6896) (xy -2.4511 0.3048) (xy 2.4511 0.3048) (xy 2.4511 -1.0033)
				(xy 3.0099 -1.0033) (xy 3.0099 1.3208)
			)
			(stroke
				(width 0)
				(type default)
			)
			(fill no)
			(layer "F.CrtYd")
		)
		(fp_rect
			(start -3.0099 1.3208)
			(end 3.0099 -6.8072)
			(stroke
				(width 0)
				(type default)
			)
			(fill no)
			(layer "F.Fab")
		)
		(pad "1" smd rect
			(at -1.905 0)
			(size 0.762 1.6256)
			(layers "F.Cu" "F.Mask" "F.Paste")
			(net "P12V")
		)
		(pad "2" smd rect
			(at -0.635 0)
			(size 0.762 1.6256)
			(layers "F.Cu" "F.Mask" "F.Paste")
			(net "P12V")
		)
		(pad "3" smd rect
			(at 0.635 0)
			(size 0.762 1.6256)
			(layers "F.Cu" "F.Mask" "F.Paste")
			(net "P12V")
		)
		(pad "4" smd rect
			(at 1.905 0)
			(size 0.762 1.6256)
			(layers "F.Cu" "F.Mask" "F.Paste")
			(net "ADM1276_GATE_DRV2")
		)
		(pad "5" smd rect
			(at 0 -3.69951)
			(size 5.0038 5.207)
			(layers "F.Cu" "F.Mask" "F.Paste")
			(net "P12V_SENSE_TRACE")
		)
	)
	(footprint ""
		(layer "F.Cu")
		(at 45.499782 -144.999964)
		(property "Reference" "H8"
			(at 0 0 0)
			(layer "F.SilkS")
			(hide yes)
			(effects
				(font
					(size 1.27 1.27)
				)
			)
		)
		(property "Value" "HOLE315R138"
			(at 0 -7.0612 0)
			(unlocked yes)
			(layer "F.Fab")
			(hide yes)
			(effects
				(font
					(size 1.016 1.016)
					(thickness 0.1524)
				)
			)
		)
		(property "Device Type" "HOLE315R138"
			(at 0 -8.5852 0)
			(unlocked yes)
			(layer "F.Fab")
			(hide yes)
			(effects
				(font
					(size 1.016 1.016)
					(thickness 0.1524)
				)
			)
		)
		(duplicate_pad_numbers_are_jumpers no)
		(fp_poly
			(pts
				(xy 0 4.3053) (xy -0.13462 4.30276) (xy -0.27051 4.29641) (xy -0.40513 4.28625) (xy -0.53975 4.27101)
				(xy -0.6731 4.25196) (xy -0.80645 4.2291) (xy -0.9398 4.20116) (xy -1.07061 4.17068) (xy -1.20142 4.13385)
				(xy -1.33096 4.09448) (xy -1.45796 4.0513) (xy -1.58496 4.00304) (xy -1.70942 3.95097) (xy -1.83261 3.89509)
				(xy -1.95453 3.83667) (xy -2.07391 3.77317) (xy -2.19202 3.70586) (xy -2.30632 3.63474) (xy -2.41935 3.56108)
				(xy -2.53111 3.48361) (xy -2.63906 3.40233) (xy -2.74447 3.31724) (xy -2.84734 3.22961) (xy -2.94767 3.13817)
				(xy -3.04419 3.04419) (xy -3.13817 2.94767) (xy -3.22961 2.84734) (xy -3.31724 2.74447) (xy -3.40233 2.63906)
				(xy -3.48361 2.53111) (xy -3.56108 2.41935) (xy -3.63474 2.30632) (xy -3.70586 2.19202) (xy -3.77317 2.07391)
				(xy -3.83667 1.95453) (xy -3.89509 1.83261) (xy -3.95097 1.70942) (xy -4.00304 1.58496) (xy -4.0513 1.45796)
				(xy -4.09448 1.33096) (xy -4.13385 1.20142) (xy -4.17068 1.07061) (xy -4.20116 0.9398) (xy -4.2291 0.80645)
				(xy -4.25196 0.6731) (xy -4.27101 0.53975) (xy -4.28625 0.40513) (xy -4.29641 0.27051) (xy -4.30276 0.13462)
				(xy -4.3053 0) (xy -4.30276 -0.13462) (xy -4.29641 -0.27051) (xy -4.28625 -0.40513) (xy -4.27101 -0.53975)
				(xy -4.25196 -0.6731) (xy -4.2291 -0.80645) (xy -4.20116 -0.9398) (xy -4.17068 -1.07061) (xy -4.13385 -1.20142)
				(xy -4.09448 -1.33096) (xy -4.0513 -1.45796) (xy -4.00304 -1.58496) (xy -3.95097 -1.70942) (xy -3.89509 -1.83261)
				(xy -3.83667 -1.95453) (xy -3.77317 -2.07391) (xy -3.70586 -2.19202) (xy -3.63474 -2.30632) (xy -3.56108 -2.41935)
				(xy -3.48361 -2.53111) (xy -3.40233 -2.63906) (xy -3.31724 -2.74447) (xy -3.22961 -2.84734) (xy -3.13817 -2.94767)
				(xy -3.04419 -3.04419) (xy -2.94767 -3.13817) (xy -2.84734 -3.22961) (xy -2.74447 -3.31724) (xy -2.63906 -3.40233)
				(xy -2.53111 -3.48361) (xy -2.41935 -3.56108) (xy -2.30632 -3.63474) (xy -2.19202 -3.70586) (xy -2.07391 -3.77317)
				(xy -1.95453 -3.83667) (xy -1.83261 -3.89509) (xy -1.70942 -3.95097) (xy -1.58496 -4.00304) (xy -1.45796 -4.0513)
				(xy -1.33096 -4.09448) (xy -1.20142 -4.13385) (xy -1.07061 -4.17068) (xy -0.9398 -4.20116) (xy -0.80645 -4.2291)
				(xy -0.6731 -4.25196) (xy -0.53975 -4.27101) (xy -0.40513 -4.28625) (xy -0.27051 -4.29641) (xy -0.13462 -4.30276)
				(xy 0 -4.3053) (xy 0.13462 -4.30276) (xy 0.27051 -4.29641) (xy 0.40513 -4.28625) (xy 0.53975 -4.27101)
				(xy 0.6731 -4.25196) (xy 0.80645 -4.2291) (xy 0.9398 -4.20116) (xy 1.07061 -4.17068) (xy 1.20142 -4.13385)
				(xy 1.33096 -4.09448) (xy 1.45796 -4.0513) (xy 1.58496 -4.00304) (xy 1.70942 -3.95097) (xy 1.83261 -3.89509)
				(xy 1.95453 -3.83667) (xy 2.07391 -3.77317) (xy 2.19202 -3.70586) (xy 2.30632 -3.63474) (xy 2.41935 -3.56108)
				(xy 2.53111 -3.48361) (xy 2.63906 -3.40233) (xy 2.74447 -3.31724) (xy 2.84734 -3.22961) (xy 2.94767 -3.13817)
				(xy 3.04419 -3.04419) (xy 3.13817 -2.94767) (xy 3.22961 -2.84734) (xy 3.31724 -2.74447) (xy 3.40233 -2.63906)
				(xy 3.48361 -2.53111) (xy 3.56108 -2.41935) (xy 3.63474 -2.30632) (xy 3.70586 -2.19202) (xy 3.77317 -2.07391)
				(xy 3.83667 -1.95453) (xy 3.89509 -1.83261) (xy 3.95097 -1.70942) (xy 4.00304 -1.58496) (xy 4.0513 -1.45796)
				(xy 4.09448 -1.33096) (xy 4.13385 -1.20142) (xy 4.17068 -1.07061) (xy 4.20116 -0.9398) (xy 4.2291 -0.80645)
				(xy 4.25196 -0.6731) (xy 4.27101 -0.53975) (xy 4.28625 -0.40513) (xy 4.29641 -0.27051) (xy 4.30276 -0.13462)
				(xy 4.3053 0) (xy 4.30276 0.13462) (xy 4.29641 0.27051) (xy 4.28625 0.40513) (xy 4.27101 0.53975)
				(xy 4.25196 0.6731) (xy 4.2291 0.80645) (xy 4.20116 0.9398) (xy 4.17068 1.07061) (xy 4.13385 1.20142)
				(xy 4.09448 1.33096) (xy 4.0513 1.45796) (xy 4.00304 1.58496) (xy 3.95097 1.70942) (xy 3.89509 1.83261)
				(xy 3.83667 1.95453) (xy 3.77317 2.07391) (xy 3.70586 2.19202) (xy 3.63474 2.30632) (xy 3.56108 2.41935)
				(xy 3.48361 2.53111) (xy 3.40233 2.63906) (xy 3.31724 2.74447) (xy 3.22961 2.84734) (xy 3.13817 2.94767)
				(xy 3.04419 3.04419) (xy 2.94767 3.13817) (xy 2.84734 3.22961) (xy 2.74447 3.31724) (xy 2.63906 3.40233)
				(xy 2.53111 3.48361) (xy 2.41935 3.56108) (xy 2.30632 3.63474) (xy 2.19202 3.70586) (xy 2.07391 3.77317)
				(xy 1.95453 3.83667) (xy 1.83261 3.89509) (xy 1.70942 3.95097) (xy 1.58496 4.00304) (xy 1.45796 4.0513)
				(xy 1.33096 4.09448) (xy 1.20142 4.13385) (xy 1.07061 4.17068) (xy 0.9398 4.20116) (xy 0.80645 4.2291)
				(xy 0.6731 4.25196) (xy 0.53975 4.27101) (xy 0.40513 4.28625) (xy 0.27051 4.29641) (xy 0.13462 4.30276)
			)
			(stroke
				(width 0)
				(type default)
			)
			(fill no)
			(layer "F.CrtYd")
		)
		(fp_poly
			(pts
				(xy 0 4.3053) (xy -0.13462 4.30276) (xy -0.27051 4.29641) (xy -0.40513 4.28625) (xy -0.53975 4.27101)
				(xy -0.6731 4.25196) (xy -0.80645 4.2291) (xy -0.9398 4.20116) (xy -1.07061 4.17068) (xy -1.20142 4.13385)
				(xy -1.33096 4.09448) (xy -1.45796 4.0513) (xy -1.58496 4.00304) (xy -1.70942 3.95097) (xy -1.83261 3.89509)
				(xy -1.95453 3.83667) (xy -2.07391 3.77317) (xy -2.19202 3.70586) (xy -2.30632 3.63474) (xy -2.41935 3.56108)
				(xy -2.53111 3.48361) (xy -2.63906 3.40233) (xy -2.74447 3.31724) (xy -2.84734 3.22961) (xy -2.94767 3.13817)
				(xy -3.04419 3.04419) (xy -3.13817 2.94767) (xy -3.22961 2.84734) (xy -3.31724 2.74447) (xy -3.40233 2.63906)
				(xy -3.48361 2.53111) (xy -3.56108 2.41935) (xy -3.63474 2.30632) (xy -3.70586 2.19202) (xy -3.77317 2.07391)
				(xy -3.83667 1.95453) (xy -3.89509 1.83261) (xy -3.95097 1.70942) (xy -4.00304 1.58496) (xy -4.0513 1.45796)
				(xy -4.09448 1.33096) (xy -4.13385 1.20142) (xy -4.17068 1.07061) (xy -4.20116 0.9398) (xy -4.2291 0.80645)
				(xy -4.25196 0.6731) (xy -4.27101 0.53975) (xy -4.28625 0.40513) (xy -4.29641 0.27051) (xy -4.30276 0.13462)
				(xy -4.3053 0) (xy -4.30276 -0.13462) (xy -4.29641 -0.27051) (xy -4.28625 -0.40513) (xy -4.27101 -0.53975)
				(xy -4.25196 -0.6731) (xy -4.2291 -0.80645) (xy -4.20116 -0.9398) (xy -4.17068 -1.07061) (xy -4.13385 -1.20142)
				(xy -4.09448 -1.33096) (xy -4.0513 -1.45796) (xy -4.00304 -1.58496) (xy -3.95097 -1.70942) (xy -3.89509 -1.83261)
				(xy -3.83667 -1.95453) (xy -3.77317 -2.07391) (xy -3.70586 -2.19202) (xy -3.63474 -2.30632) (xy -3.56108 -2.41935)
				(xy -3.48361 -2.53111) (xy -3.40233 -2.63906) (xy -3.31724 -2.74447) (xy -3.22961 -2.84734) (xy -3.13817 -2.94767)
				(xy -3.04419 -3.04419) (xy -2.94767 -3.13817) (xy -2.84734 -3.22961) (xy -2.74447 -3.31724) (xy -2.63906 -3.40233)
				(xy -2.53111 -3.48361) (xy -2.41935 -3.56108) (xy -2.30632 -3.63474) (xy -2.19202 -3.70586) (xy -2.07391 -3.77317)
				(xy -1.95453 -3.83667) (xy -1.83261 -3.89509) (xy -1.70942 -3.95097) (xy -1.58496 -4.00304) (xy -1.45796 -4.0513)
				(xy -1.33096 -4.09448) (xy -1.20142 -4.13385) (xy -1.07061 -4.17068) (xy -0.9398 -4.20116) (xy -0.80645 -4.2291)
				(xy -0.6731 -4.25196) (xy -0.53975 -4.27101) (xy -0.40513 -4.28625) (xy -0.27051 -4.29641) (xy -0.13462 -4.30276)
				(xy 0 -4.3053) (xy 0.13462 -4.30276) (xy 0.27051 -4.29641) (xy 0.40513 -4.28625) (xy 0.53975 -4.27101)
				(xy 0.6731 -4.25196) (xy 0.80645 -4.2291) (xy 0.9398 -4.20116) (xy 1.07061 -4.17068) (xy 1.20142 -4.13385)
				(xy 1.33096 -4.09448) (xy 1.45796 -4.0513) (xy 1.58496 -4.00304) (xy 1.70942 -3.95097) (xy 1.83261 -3.89509)
				(xy 1.95453 -3.83667) (xy 2.07391 -3.77317) (xy 2.19202 -3.70586) (xy 2.30632 -3.63474) (xy 2.41935 -3.56108)
				(xy 2.53111 -3.48361) (xy 2.63906 -3.40233) (xy 2.74447 -3.31724) (xy 2.84734 -3.22961) (xy 2.94767 -3.13817)
				(xy 3.04419 -3.04419) (xy 3.13817 -2.94767) (xy 3.22961 -2.84734) (xy 3.31724 -2.74447) (xy 3.40233 -2.63906)
				(xy 3.48361 -2.53111) (xy 3.56108 -2.41935) (xy 3.63474 -2.30632) (xy 3.70586 -2.19202) (xy 3.77317 -2.07391)
				(xy 3.83667 -1.95453) (xy 3.89509 -1.83261) (xy 3.95097 -1.70942) (xy 4.00304 -1.58496) (xy 4.0513 -1.45796)
				(xy 4.09448 -1.33096) (xy 4.13385 -1.20142) (xy 4.17068 -1.07061) (xy 4.20116 -0.9398) (xy 4.2291 -0.80645)
				(xy 4.25196 -0.6731) (xy 4.27101 -0.53975) (xy 4.28625 -0.40513) (xy 4.29641 -0.27051) (xy 4.30276 -0.13462)
				(xy 4.3053 0) (xy 4.30276 0.13462) (xy 4.29641 0.27051) (xy 4.28625 0.40513) (xy 4.27101 0.53975)
				(xy 4.25196 0.6731) (xy 4.2291 0.80645) (xy 4.20116 0.9398) (xy 4.17068 1.07061) (xy 4.13385 1.20142)
				(xy 4.09448 1.33096) (xy 4.0513 1.45796) (xy 4.00304 1.58496) (xy 3.95097 1.70942) (xy 3.89509 1.83261)
				(xy 3.83667 1.95453) (xy 3.77317 2.07391) (xy 3.70586 2.19202) (xy 3.63474 2.30632) (xy 3.56108 2.41935)
				(xy 3.48361 2.53111) (xy 3.40233 2.63906) (xy 3.31724 2.74447) (xy 3.22961 2.84734) (xy 3.13817 2.94767)
				(xy 3.04419 3.04419) (xy 2.94767 3.13817) (xy 2.84734 3.22961) (xy 2.74447 3.31724) (xy 2.63906 3.40233)
				(xy 2.53111 3.48361) (xy 2.41935 3.56108) (xy 2.30632 3.63474) (xy 2.19202 3.70586) (xy 2.07391 3.77317)
				(xy 1.95453 3.83667) (xy 1.83261 3.89509) (xy 1.70942 3.95097) (xy 1.58496 4.00304) (xy 1.45796 4.0513)
				(xy 1.33096 4.09448) (xy 1.20142 4.13385) (xy 1.07061 4.17068) (xy 0.9398 4.20116) (xy 0.80645 4.2291)
				(xy 0.6731 4.25196) (xy 0.53975 4.27101) (xy 0.40513 4.28625) (xy 0.27051 4.29641) (xy 0.13462 4.30276)
			)
			(stroke
				(width 0)
				(type default)
			)
			(fill no)
			(layer "F.Fab")
		)
		(pad "1" thru_hole circle
			(at 0 0)
			(size 8.001 8.001)
			(drill 3.5052)
			(layers "*.Cu" "*.Mask")
			(remove_unused_layers no)
			(net "GND")
			(clearance -1.7399)
			(thermal_gap 0.3048)
			(padstack
				(mode front_inner_back)
				(layer "Inner"
					(shape circle)
					(size 3.9116 3.9116)
					(clearance 0.3048)
				)
				(layer "B.Cu"
					(shape circle)
					(size 8.001 8.001)
					(clearance -1.7399)
				)
			)
		)
	)
	(footprint ""
		(layer "F.Cu")
		(at 21.6408 -290.322 -90)
		(property "Reference" "C44"
			(at 0 0 270)
			(layer "F.SilkS")
			(hide yes)
			(effects
				(font
					(size 1.27 1.27)
				)
			)
		)
		(property "Value" "SCD1U16V2KX-3GP"
			(at 1.1811 -2.7051 270)
			(unlocked yes)
			(layer "F.Fab")
			(hide yes)
			(effects
				(font
					(size 1.016 1.016)
					(thickness 0.1524)
				)
			)
		)
		(property "Device Type" "C402H22"
			(at 1.1811 -4.2291 270)
			(unlocked yes)
			(layer "F.Fab")
			(hide yes)
			(effects
				(font
					(size 1.016 1.016)
					(thickness 0.1524)
				)
			)
		)
		(duplicate_pad_numbers_are_jumpers no)
		(fp_rect
			(start -0.4318 0.9525)
			(end 0.4318 -0.9525)
			(stroke
				(width 0)
				(type default)
			)
			(fill no)
			(layer "F.CrtYd")
		)
		(fp_rect
			(start -0.4318 0.9525)
			(end 0.4318 -0.9525)
			(stroke
				(width 0)
				(type default)
			)
			(fill no)
			(layer "F.Fab")
		)
		(pad "1" smd custom
			(at 0 -0.4445 270)
			(size 0.1524 0.1524)
			(layers "F.Cu" "F.Mask" "F.Paste")
			(net "FAN_TACH4")
			(options
				(clearance outline)
				(anchor circle)
			)
			(primitives
				(gr_poly
					(pts
						(arc
							(start 0.3048 -0.2032)
							(mid 0.275042 -0.275042)
							(end 0.2032 -0.3048)
						)
						(arc
							(start -0.2032 -0.3048)
							(mid -0.275042 -0.275042)
							(end -0.3048 -0.2032)
						)
						(arc
							(start -0.3048 0.2032)
							(mid -0.275042 0.275042)
							(end -0.2032 0.3048)
						)
						(arc
							(start 0.2032 0.3048)
							(mid 0.275042 0.275042)
							(end 0.3048 0.2032)
						)
					)
					(width 0)
					(fill yes)
				)
			)
		)
		(pad "2" smd custom
			(at 0 0.4445 270)
			(size 0.1524 0.1524)
			(layers "F.Cu" "F.Mask" "F.Paste")
			(net "GND")
			(options
				(clearance outline)
				(anchor circle)
			)
			(primitives
				(gr_poly
					(pts
						(arc
							(start 0.3048 -0.2032)
							(mid 0.275042 -0.275042)
							(end 0.2032 -0.3048)
						)
						(arc
							(start -0.2032 -0.3048)
							(mid -0.275042 -0.275042)
							(end -0.3048 -0.2032)
						)
						(arc
							(start -0.3048 0.2032)
							(mid -0.275042 0.275042)
							(end -0.2032 0.3048)
						)
						(arc
							(start 0.2032 0.3048)
							(mid 0.275042 0.275042)
							(end 0.3048 0.2032)
						)
					)
					(width 0)
					(fill yes)
				)
			)
		)
	)
	(footprint ""
		(layer "F.Cu")
		(at 24.4094 -135.1788)
		(property "Reference" "PR94"
			(at 0 0 0)
			(layer "F.SilkS")
			(hide yes)
			(effects
				(font
					(size 1.27 1.27)
				)
			)
		)
		(property "Value" "0R2J-2-GP"
			(at 0.064008 -3.993896 0)
			(unlocked yes)
			(layer "F.Fab")
			(hide yes)
			(effects
				(font
					(size 1.016 1.016)
					(thickness 0.1524)
				)
			)
		)
		(property "Device Type" "R402H16"
			(at 0.064008 -5.517896 0)
			(unlocked yes)
			(layer "F.Fab")
			(hide yes)
			(effects
				(font
					(size 1.016 1.016)
					(thickness 0.1524)
				)
			)
		)
		(duplicate_pad_numbers_are_jumpers no)
		(fp_line
			(start -0.508 -0.9398)
			(end -0.508 0.9398)
			(stroke
				(width 0.1524)
				(type default)
			)
			(layer "F.SilkS")
		)
		(fp_line
			(start 0.508 -0.9398)
			(end -0.508 -0.9398)
			(stroke
				(width 0.1524)
				(type default)
			)
			(layer "F.SilkS")
		)
		(fp_rect
			(start -0.508 0.9398)
			(end 0.508 -0.9398)
			(stroke
				(width 0)
				(type default)
			)
			(fill no)
			(layer "F.CrtYd")
		)
		(fp_rect
			(start -0.508 0.9398)
			(end 0.508 -0.9398)
			(stroke
				(width 0)
				(type default)
			)
			(fill no)
			(layer "F.Fab")
		)
		(pad "1" smd custom
			(at 0 -0.4445)
			(size 0.1397 0.1397)
			(layers "F.Cu" "F.Mask" "F.Paste")
			(net "P12VU_2490_VCC")
			(options
				(clearance outline)
				(anchor circle)
			)
			(primitives
				(gr_poly
					(pts
						(arc
							(start -0.1778 -0.2794)
							(mid -0.249642 -0.249642)
							(end -0.2794 -0.1778)
						)
						(arc
							(start -0.2794 0.1778)
							(mid -0.249642 0.249642)
							(end -0.1778 0.2794)
						)
						(arc
							(start 0.1778 0.2794)
							(mid 0.249642 0.249642)
							(end 0.2794 0.1778)
						)
						(arc
							(start 0.2794 -0.1778)
							(mid 0.249642 -0.249642)
							(end 0.1778 -0.2794)
						)
					)
					(width 0)
					(fill yes)
				)
			)
		)
		(pad "2" smd custom
			(at 0 0.4445)
			(size 0.1397 0.1397)
			(layers "F.Cu" "F.Mask" "F.Paste")
			(net "P12V")
			(options
				(clearance outline)
				(anchor circle)
			)
			(primitives
				(gr_poly
					(pts
						(arc
							(start -0.1778 -0.2794)
							(mid -0.249642 -0.249642)
							(end -0.2794 -0.1778)
						)
						(arc
							(start -0.2794 0.1778)
							(mid -0.249642 0.249642)
							(end -0.1778 0.2794)
						)
						(arc
							(start 0.1778 0.2794)
							(mid 0.249642 0.249642)
							(end 0.2794 0.1778)
						)
						(arc
							(start 0.2794 -0.1778)
							(mid 0.249642 -0.249642)
							(end 0.1778 -0.2794)
						)
					)
					(width 0)
					(fill yes)
				)
			)
		)
	)
	(footprint ""
		(layer "F.Cu")
		(at 36.83 -240.665 180)
		(property "Reference" "R148"
			(at 0 0 180)
			(layer "F.SilkS")
			(hide yes)
			(effects
				(font
					(size 1.27 1.27)
				)
			)
		)
		(property "Value" "330R2J-3-GP"
			(at 0.064008 -3.993896 180)
			(unlocked yes)
			(layer "F.Fab")
			(hide yes)
			(effects
				(font
					(size 1.016 1.016)
					(thickness 0.1524)
				)
			)
		)
		(property "Device Type" "R402H16"
			(at 0.064008 -5.517896 180)
			(unlocked yes)
			(layer "F.Fab")
			(hide yes)
			(effects
				(font
					(size 1.016 1.016)
					(thickness 0.1524)
				)
			)
		)
		(duplicate_pad_numbers_are_jumpers no)
		(fp_line
			(start 0.508 -0.9398)
			(end -0.508 -0.9398)
			(stroke
				(width 0.1524)
				(type default)
			)
			(layer "F.SilkS")
		)
		(fp_line
			(start -0.508 -0.9398)
			(end -0.508 0.9398)
			(stroke
				(width 0.1524)
				(type default)
			)
			(layer "F.SilkS")
		)
		(fp_rect
			(start -0.508 0.9398)
			(end 0.508 -0.9398)
			(stroke
				(width 0)
				(type default)
			)
			(fill no)
			(layer "F.CrtYd")
		)
		(fp_rect
			(start -0.508 0.9398)
			(end 0.508 -0.9398)
			(stroke
				(width 0)
				(type default)
			)
			(fill no)
			(layer "F.Fab")
		)
		(pad "1" smd custom
			(at 0 -0.4445 180)
			(size 0.1397 0.1397)
			(layers "F.Cu" "F.Mask" "F.Paste")
			(net "P3V3")
			(options
				(clearance outline)
				(anchor circle)
			)
			(primitives
				(gr_poly
					(pts
						(arc
							(start -0.1778 -0.2794)
							(mid -0.249642 -0.249642)
							(end -0.2794 -0.1778)
						)
						(arc
							(start -0.2794 0.1778)
							(mid -0.249642 0.249642)
							(end -0.1778 0.2794)
						)
						(arc
							(start 0.1778 0.2794)
							(mid 0.249642 0.249642)
							(end 0.2794 0.1778)
						)
						(arc
							(start 0.2794 -0.1778)
							(mid 0.249642 -0.249642)
							(end 0.1778 -0.2794)
						)
					)
					(width 0)
					(fill yes)
				)
			)
		)
		(pad "2" smd custom
			(at 0 0.4445 180)
			(size 0.1397 0.1397)
			(layers "F.Cu" "F.Mask" "F.Paste")
			(net "LED_DR_LED0")
			(options
				(clearance outline)
				(anchor circle)
			)
			(primitives
				(gr_poly
					(pts
						(arc
							(start -0.1778 -0.2794)
							(mid -0.249642 -0.249642)
							(end -0.2794 -0.1778)
						)
						(arc
							(start -0.2794 0.1778)
							(mid -0.249642 0.249642)
							(end -0.1778 0.2794)
						)
						(arc
							(start 0.1778 0.2794)
							(mid 0.249642 0.249642)
							(end 0.2794 0.1778)
						)
						(arc
							(start 0.2794 -0.1778)
							(mid 0.249642 -0.249642)
							(end 0.1778 -0.2794)
						)
					)
					(width 0)
					(fill yes)
				)
			)
		)
	)
	(footprint ""
		(layer "F.Cu")
		(at 41.529 -252.984)
		(property "Reference" "R149"
			(at 0 0 0)
			(layer "F.SilkS")
			(hide yes)
			(effects
				(font
					(size 1.27 1.27)
				)
			)
		)
		(property "Value" "330R2J-3-GP"
			(at 0.064008 -3.993896 0)
			(unlocked yes)
			(layer "F.Fab")
			(hide yes)
			(effects
				(font
					(size 1.016 1.016)
					(thickness 0.1524)
				)
			)
		)
		(property "Device Type" "R402H16"
			(at 0.064008 -5.517896 0)
			(unlocked yes)
			(layer "F.Fab")
			(hide yes)
			(effects
				(font
					(size 1.016 1.016)
					(thickness 0.1524)
				)
			)
		)
		(duplicate_pad_numbers_are_jumpers no)
		(fp_line
			(start -0.508 -0.9398)
			(end -0.508 0.9398)
			(stroke
				(width 0.1524)
				(type default)
			)
			(layer "F.SilkS")
		)
		(fp_line
			(start 0.508 -0.9398)
			(end -0.508 -0.9398)
			(stroke
				(width 0.1524)
				(type default)
			)
			(layer "F.SilkS")
		)
		(fp_rect
			(start -0.508 0.9398)
			(end 0.508 -0.9398)
			(stroke
				(width 0)
				(type default)
			)
			(fill no)
			(layer "F.CrtYd")
		)
		(fp_rect
			(start -0.508 0.9398)
			(end 0.508 -0.9398)
			(stroke
				(width 0)
				(type default)
			)
			(fill no)
			(layer "F.Fab")
		)
		(pad "1" smd custom
			(at 0 -0.4445)
			(size 0.1397 0.1397)
			(layers "F.Cu" "F.Mask" "F.Paste")
			(net "P3V3")
			(options
				(clearance outline)
				(anchor circle)
			)
			(primitives
				(gr_poly
					(pts
						(arc
							(start -0.1778 -0.2794)
							(mid -0.249642 -0.249642)
							(end -0.2794 -0.1778)
						)
						(arc
							(start -0.2794 0.1778)
							(mid -0.249642 0.249642)
							(end -0.1778 0.2794)
						)
						(arc
							(start 0.1778 0.2794)
							(mid 0.249642 0.249642)
							(end 0.2794 0.1778)
						)
						(arc
							(start 0.2794 -0.1778)
							(mid 0.249642 -0.249642)
							(end 0.1778 -0.2794)
						)
					)
					(width 0)
					(fill yes)
				)
			)
		)
		(pad "2" smd custom
			(at 0 0.4445)
			(size 0.1397 0.1397)
			(layers "F.Cu" "F.Mask" "F.Paste")
			(net "LED_DR_LED4")
			(options
				(clearance outline)
				(anchor circle)
			)
			(primitives
				(gr_poly
					(pts
						(arc
							(start -0.1778 -0.2794)
							(mid -0.249642 -0.249642)
							(end -0.2794 -0.1778)
						)
						(arc
							(start -0.2794 0.1778)
							(mid -0.249642 0.249642)
							(end -0.1778 0.2794)
						)
						(arc
							(start 0.1778 0.2794)
							(mid 0.249642 0.249642)
							(end 0.2794 0.1778)
						)
						(arc
							(start 0.2794 -0.1778)
							(mid 0.249642 -0.249642)
							(end 0.1778 -0.2794)
						)
					)
					(width 0)
					(fill yes)
				)
			)
		)
	)
	(footprint ""
		(layer "F.Cu")
		(at 7.239 -454.1012 -90)
		(property "Reference" "C45"
			(at 0 0 270)
			(layer "F.SilkS")
			(hide yes)
			(effects
				(font
					(size 1.27 1.27)
				)
			)
		)
		(property "Value" "SCD1U16V2KX-3GP"
			(at 1.1811 -2.7051 270)
			(unlocked yes)
			(layer "F.Fab")
			(hide yes)
			(effects
				(font
					(size 1.016 1.016)
					(thickness 0.1524)
				)
			)
		)
		(property "Device Type" "C402H22"
			(at 1.1811 -4.2291 270)
			(unlocked yes)
			(layer "F.Fab")
			(hide yes)
			(effects
				(font
					(size 1.016 1.016)
					(thickness 0.1524)
				)
			)
		)
		(duplicate_pad_numbers_are_jumpers no)
		(fp_rect
			(start -0.4318 0.9525)
			(end 0.4318 -0.9525)
			(stroke
				(width 0)
				(type default)
			)
			(fill no)
			(layer "F.CrtYd")
		)
		(fp_rect
			(start -0.4318 0.9525)
			(end 0.4318 -0.9525)
			(stroke
				(width 0)
				(type default)
			)
			(fill no)
			(layer "F.Fab")
		)
		(pad "1" smd custom
			(at 0 -0.4445 270)
			(size 0.1524 0.1524)
			(layers "F.Cu" "F.Mask" "F.Paste")
			(net "FAN_TACH1")
			(options
				(clearance outline)
				(anchor circle)
			)
			(primitives
				(gr_poly
					(pts
						(arc
							(start 0.3048 -0.2032)
							(mid 0.275042 -0.275042)
							(end 0.2032 -0.3048)
						)
						(arc
							(start -0.2032 -0.3048)
							(mid -0.275042 -0.275042)
							(end -0.3048 -0.2032)
						)
						(arc
							(start -0.3048 0.2032)
							(mid -0.275042 0.275042)
							(end -0.2032 0.3048)
						)
						(arc
							(start 0.2032 0.3048)
							(mid 0.275042 0.275042)
							(end 0.3048 0.2032)
						)
					)
					(width 0)
					(fill yes)
				)
			)
		)
		(pad "2" smd custom
			(at 0 0.4445 270)
			(size 0.1524 0.1524)
			(layers "F.Cu" "F.Mask" "F.Paste")
			(net "GND")
			(options
				(clearance outline)
				(anchor circle)
			)
			(primitives
				(gr_poly
					(pts
						(arc
							(start 0.3048 -0.2032)
							(mid 0.275042 -0.275042)
							(end 0.2032 -0.3048)
						)
						(arc
							(start -0.2032 -0.3048)
							(mid -0.275042 -0.275042)
							(end -0.3048 -0.2032)
						)
						(arc
							(start -0.3048 0.2032)
							(mid -0.275042 0.275042)
							(end -0.2032 0.3048)
						)
						(arc
							(start 0.2032 0.3048)
							(mid 0.275042 0.275042)
							(end 0.3048 0.2032)
						)
					)
					(width 0)
					(fill yes)
				)
			)
		)
	)
	(footprint ""
		(layer "F.Cu")
		(at 26.67 -361.188)
		(property "Reference" "PR116"
			(at 0 0 0)
			(layer "F.SilkS")
			(hide yes)
			(effects
				(font
					(size 1.27 1.27)
				)
			)
		)
		(property "Value" "0R2J-2-GP"
			(at 0.064008 -3.993896 0)
			(unlocked yes)
			(layer "F.Fab")
			(hide yes)
			(effects
				(font
					(size 1.016 1.016)
					(thickness 0.1524)
				)
			)
		)
		(property "Device Type" "R402H16"
			(at 0.064008 -5.517896 0)
			(unlocked yes)
			(layer "F.Fab")
			(hide yes)
			(effects
				(font
					(size 1.016 1.016)
					(thickness 0.1524)
				)
			)
		)
		(duplicate_pad_numbers_are_jumpers no)
		(fp_line
			(start -0.508 -0.9398)
			(end -0.508 0.9398)
			(stroke
				(width 0.1524)
				(type default)
			)
			(layer "F.SilkS")
		)
		(fp_line
			(start 0.508 -0.9398)
			(end -0.508 -0.9398)
			(stroke
				(width 0.1524)
				(type default)
			)
			(layer "F.SilkS")
		)
		(fp_rect
			(start -0.508 0.9398)
			(end 0.508 -0.9398)
			(stroke
				(width 0)
				(type default)
			)
			(fill no)
			(layer "F.CrtYd")
		)
		(fp_rect
			(start -0.508 0.9398)
			(end 0.508 -0.9398)
			(stroke
				(width 0)
				(type default)
			)
			(fill no)
			(layer "F.Fab")
		)
		(pad "1" smd custom
			(at 0 -0.4445)
			(size 0.1397 0.1397)
			(layers "F.Cu" "F.Mask" "F.Paste")
			(net "ADM1276_LATCH#")
			(options
				(clearance outline)
				(anchor circle)
			)
			(primitives
				(gr_poly
					(pts
						(arc
							(start -0.1778 -0.2794)
							(mid -0.249642 -0.249642)
							(end -0.2794 -0.1778)
						)
						(arc
							(start -0.2794 0.1778)
							(mid -0.249642 0.249642)
							(end -0.1778 0.2794)
						)
						(arc
							(start 0.1778 0.2794)
							(mid 0.249642 0.249642)
							(end 0.2794 0.1778)
						)
						(arc
							(start 0.2794 -0.1778)
							(mid 0.249642 -0.249642)
							(end 0.1778 -0.2794)
						)
					)
					(width 0)
					(fill yes)
				)
			)
		)
		(pad "2" smd custom
			(at 0 0.4445)
			(size 0.1397 0.1397)
			(layers "F.Cu" "F.Mask" "F.Paste")
			(net "P3V3")
			(options
				(clearance outline)
				(anchor circle)
			)
			(primitives
				(gr_poly
					(pts
						(arc
							(start -0.1778 -0.2794)
							(mid -0.249642 -0.249642)
							(end -0.2794 -0.1778)
						)
						(arc
							(start -0.2794 0.1778)
							(mid -0.249642 0.249642)
							(end -0.1778 0.2794)
						)
						(arc
							(start 0.1778 0.2794)
							(mid 0.249642 0.249642)
							(end 0.2794 0.1778)
						)
						(arc
							(start 0.2794 -0.1778)
							(mid 0.249642 -0.249642)
							(end 0.1778 -0.2794)
						)
					)
					(width 0)
					(fill yes)
				)
			)
		)
	)
	(footprint ""
		(layer "F.Cu")
		(at 26.0604 -224.3074)
		(property "Reference" "R141"
			(at 0 0 0)
			(layer "F.SilkS")
			(hide yes)
			(effects
				(font
					(size 1.27 1.27)
				)
			)
		)
		(property "Value" "0R2J-2-GP"
			(at 0.064008 -3.993896 0)
			(unlocked yes)
			(layer "F.Fab")
			(hide yes)
			(effects
				(font
					(size 1.016 1.016)
					(thickness 0.1524)
				)
			)
		)
		(property "Device Type" "R402H16"
			(at 0.064008 -5.517896 0)
			(unlocked yes)
			(layer "F.Fab")
			(hide yes)
			(effects
				(font
					(size 1.016 1.016)
					(thickness 0.1524)
				)
			)
		)
		(duplicate_pad_numbers_are_jumpers no)
		(fp_line
			(start -0.508 -0.9398)
			(end -0.508 0.9398)
			(stroke
				(width 0.1524)
				(type default)
			)
			(layer "F.SilkS")
		)
		(fp_line
			(start 0.508 -0.9398)
			(end -0.508 -0.9398)
			(stroke
				(width 0.1524)
				(type default)
			)
			(layer "F.SilkS")
		)
		(fp_rect
			(start -0.508 0.9398)
			(end 0.508 -0.9398)
			(stroke
				(width 0)
				(type default)
			)
			(fill no)
			(layer "F.CrtYd")
		)
		(fp_rect
			(start -0.508 0.9398)
			(end 0.508 -0.9398)
			(stroke
				(width 0)
				(type default)
			)
			(fill no)
			(layer "F.Fab")
		)
		(pad "1" smd custom
			(at 0 -0.4445)
			(size 0.1397 0.1397)
			(layers "F.Cu" "F.Mask" "F.Paste")
			(net "PWM_OUT_FAN1_NET")
			(options
				(clearance outline)
				(anchor circle)
			)
			(primitives
				(gr_poly
					(pts
						(arc
							(start -0.1778 -0.2794)
							(mid -0.249642 -0.249642)
							(end -0.2794 -0.1778)
						)
						(arc
							(start -0.2794 0.1778)
							(mid -0.249642 0.249642)
							(end -0.1778 0.2794)
						)
						(arc
							(start 0.1778 0.2794)
							(mid 0.249642 0.249642)
							(end 0.2794 0.1778)
						)
						(arc
							(start 0.2794 -0.1778)
							(mid 0.249642 -0.249642)
							(end 0.1778 -0.2794)
						)
					)
					(width 0)
					(fill yes)
				)
			)
		)
		(pad "2" smd custom
			(at 0 0.4445)
			(size 0.1397 0.1397)
			(layers "F.Cu" "F.Mask" "F.Paste")
			(net "PWM_OUT_FAN1")
			(options
				(clearance outline)
				(anchor circle)
			)
			(primitives
				(gr_poly
					(pts
						(arc
							(start -0.1778 -0.2794)
							(mid -0.249642 -0.249642)
							(end -0.2794 -0.1778)
						)
						(arc
							(start -0.2794 0.1778)
							(mid -0.249642 0.249642)
							(end -0.1778 0.2794)
						)
						(arc
							(start 0.1778 0.2794)
							(mid 0.249642 0.249642)
							(end 0.2794 0.1778)
						)
						(arc
							(start 0.2794 -0.1778)
							(mid 0.249642 -0.249642)
							(end 0.1778 -0.2794)
						)
					)
					(width 0)
					(fill yes)
				)
			)
		)
	)
	(footprint ""
		(layer "F.Cu")
		(at 22.733 -179.8066 -90)
		(property "Reference" "R83"
			(at 0 0 270)
			(layer "F.SilkS")
			(hide yes)
			(effects
				(font
					(size 1.27 1.27)
				)
			)
		)
		(property "Value" "4K7R2F-GP"
			(at 0.064008 -3.993896 270)
			(unlocked yes)
			(layer "F.Fab")
			(hide yes)
			(effects
				(font
					(size 1.016 1.016)
					(thickness 0.1524)
				)
			)
		)
		(property "Device Type" "R402H16"
			(at 0.064008 -5.517896 270)
			(unlocked yes)
			(layer "F.Fab")
			(hide yes)
			(effects
				(font
					(size 1.016 1.016)
					(thickness 0.1524)
				)
			)
		)
		(duplicate_pad_numbers_are_jumpers no)
		(fp_line
			(start -0.508 -0.9398)
			(end -0.508 0.9398)
			(stroke
				(width 0.1524)
				(type default)
			)
			(layer "F.SilkS")
		)
		(fp_line
			(start 0.508 -0.9398)
			(end -0.508 -0.9398)
			(stroke
				(width 0.1524)
				(type default)
			)
			(layer "F.SilkS")
		)
		(fp_rect
			(start -0.508 0.9398)
			(end 0.508 -0.9398)
			(stroke
				(width 0)
				(type default)
			)
			(fill no)
			(layer "F.CrtYd")
		)
		(fp_rect
			(start -0.508 0.9398)
			(end 0.508 -0.9398)
			(stroke
				(width 0)
				(type default)
			)
			(fill no)
			(layer "F.Fab")
		)
		(pad "1" smd custom
			(at 0 -0.4445 270)
			(size 0.1397 0.1397)
			(layers "F.Cu" "F.Mask" "F.Paste")
			(net "P12V")
			(options
				(clearance outline)
				(anchor circle)
			)
			(primitives
				(gr_poly
					(pts
						(arc
							(start -0.1778 -0.2794)
							(mid -0.249642 -0.249642)
							(end -0.2794 -0.1778)
						)
						(arc
							(start -0.2794 0.1778)
							(mid -0.249642 0.249642)
							(end -0.1778 0.2794)
						)
						(arc
							(start 0.1778 0.2794)
							(mid 0.249642 0.249642)
							(end 0.2794 0.1778)
						)
						(arc
							(start 0.2794 -0.1778)
							(mid 0.249642 -0.249642)
							(end 0.1778 -0.2794)
						)
					)
					(width 0)
					(fill yes)
				)
			)
		)
		(pad "2" smd custom
			(at 0 0.4445 270)
			(size 0.1397 0.1397)
			(layers "F.Cu" "F.Mask" "F.Paste")
			(net "FAN_TACH7")
			(options
				(clearance outline)
				(anchor circle)
			)
			(primitives
				(gr_poly
					(pts
						(arc
							(start -0.1778 -0.2794)
							(mid -0.249642 -0.249642)
							(end -0.2794 -0.1778)
						)
						(arc
							(start -0.2794 0.1778)
							(mid -0.249642 0.249642)
							(end -0.1778 0.2794)
						)
						(arc
							(start 0.1778 0.2794)
							(mid 0.249642 0.249642)
							(end 0.2794 0.1778)
						)
						(arc
							(start 0.2794 -0.1778)
							(mid 0.249642 -0.249642)
							(end 0.1778 -0.2794)
						)
					)
					(width 0)
					(fill yes)
				)
			)
		)
	)
	(footprint ""
		(layer "F.Cu")
		(at 22.71649 -162.262566 180)
		(property "Reference" "R8"
			(at 0 0 180)
			(layer "F.SilkS")
			(hide yes)
			(effects
				(font
					(size 1.27 1.27)
				)
			)
		)
		(property "Value" "0R5J-5-GP"
			(at 0 -8.9535 180)
			(unlocked yes)
			(layer "F.Fab")
			(hide yes)
			(effects
				(font
					(size 1.27 1.016)
					(thickness 0.1524)
				)
			)
		)
		(property "Device Type" "R805H24"
			(at 0 -10.6299 180)
			(unlocked yes)
			(layer "F.Fab")
			(hide yes)
			(effects
				(font
					(size 1.27 1.016)
					(thickness 0.1524)
				)
			)
		)
		(duplicate_pad_numbers_are_jumpers no)
		(fp_line
			(start 0.889 1.7018)
			(end 0.889 -0.508)
			(stroke
				(width 0.1524)
				(type default)
			)
			(layer "F.SilkS")
		)
		(fp_line
			(start 0.889 -1.7018)
			(end 0.889 -0.381)
			(stroke
				(width 0.1524)
				(type default)
			)
			(layer "F.SilkS")
		)
		(fp_line
			(start 0.889 -1.7018)
			(end -0.889 -1.7018)
			(stroke
				(width 0.1524)
				(type default)
			)
			(layer "F.SilkS")
		)
		(fp_line
			(start -0.889 1.7018)
			(end 0.889 1.7018)
			(stroke
				(width 0.1524)
				(type default)
			)
			(layer "F.SilkS")
		)
		(fp_line
			(start -0.889 0.0762)
			(end -0.889 1.7018)
			(stroke
				(width 0.1524)
				(type default)
			)
			(layer "F.SilkS")
		)
		(fp_line
			(start -0.889 -1.7018)
			(end -0.889 0.2794)
			(stroke
				(width 0.1524)
				(type default)
			)
			(layer "F.SilkS")
		)
		(fp_poly
			(pts
				(xy 0.9652 -1.778) (xy 0.9652 1.778) (xy -0.9652 1.778) (xy -0.9652 -1.778)
			)
			(stroke
				(width 0)
				(type default)
			)
			(fill no)
			(layer "F.CrtYd")
		)
		(fp_rect
			(start -0.9652 1.778)
			(end 0.9652 -1.778)
			(stroke
				(width 0)
				(type default)
			)
			(fill no)
			(layer "F.Fab")
		)
		(pad "1" smd rect
			(at 0 -0.9652 180)
			(size 1.397 1.143)
			(layers "F.Cu" "F.Mask" "F.Paste")
			(net "NCT7904_GND")
		)
		(pad "2" smd rect
			(at 0 0.9652 180)
			(size 1.397 1.143)
			(layers "F.Cu" "F.Mask" "F.Paste")
			(net "GND")
		)
	)
	(footprint ""
		(layer "F.Cu")
		(at 23.622 -170.434 -90)
		(property "Reference" "R21"
			(at 0 0 270)
			(layer "F.SilkS")
			(hide yes)
			(effects
				(font
					(size 1.27 1.27)
				)
			)
		)
		(property "Value" "100KR2F-L1-GP"
			(at 0.064008 -3.993896 270)
			(unlocked yes)
			(layer "F.Fab")
			(hide yes)
			(effects
				(font
					(size 1.016 1.016)
					(thickness 0.1524)
				)
			)
		)
		(property "Device Type" "R402H16"
			(at 0.064008 -5.517896 270)
			(unlocked yes)
			(layer "F.Fab")
			(hide yes)
			(effects
				(font
					(size 1.016 1.016)
					(thickness 0.1524)
				)
			)
		)
		(duplicate_pad_numbers_are_jumpers no)
		(fp_line
			(start -0.508 -0.9398)
			(end -0.508 0.9398)
			(stroke
				(width 0.1524)
				(type default)
			)
			(layer "F.SilkS")
		)
		(fp_line
			(start 0.508 -0.9398)
			(end -0.508 -0.9398)
			(stroke
				(width 0.1524)
				(type default)
			)
			(layer "F.SilkS")
		)
		(fp_rect
			(start -0.508 0.9398)
			(end 0.508 -0.9398)
			(stroke
				(width 0)
				(type default)
			)
			(fill no)
			(layer "F.CrtYd")
		)
		(fp_rect
			(start -0.508 0.9398)
			(end 0.508 -0.9398)
			(stroke
				(width 0)
				(type default)
			)
			(fill no)
			(layer "F.Fab")
		)
		(pad "1" smd custom
			(at 0 -0.4445 270)
			(size 0.1397 0.1397)
			(layers "F.Cu" "F.Mask" "F.Paste")
			(net "PWM_EXP_2B")
			(options
				(clearance outline)
				(anchor circle)
			)
			(primitives
				(gr_poly
					(pts
						(arc
							(start -0.1778 -0.2794)
							(mid -0.249642 -0.249642)
							(end -0.2794 -0.1778)
						)
						(arc
							(start -0.2794 0.1778)
							(mid -0.249642 0.249642)
							(end -0.1778 0.2794)
						)
						(arc
							(start 0.1778 0.2794)
							(mid 0.249642 0.249642)
							(end 0.2794 0.1778)
						)
						(arc
							(start 0.2794 -0.1778)
							(mid 0.249642 -0.249642)
							(end 0.1778 -0.2794)
						)
					)
					(width 0)
					(fill yes)
				)
			)
		)
		(pad "2" smd custom
			(at 0 0.4445 270)
			(size 0.1397 0.1397)
			(layers "F.Cu" "F.Mask" "F.Paste")
			(net "GND")
			(options
				(clearance outline)
				(anchor circle)
			)
			(primitives
				(gr_poly
					(pts
						(arc
							(start -0.1778 -0.2794)
							(mid -0.249642 -0.249642)
							(end -0.2794 -0.1778)
						)
						(arc
							(start -0.2794 0.1778)
							(mid -0.249642 0.249642)
							(end -0.1778 0.2794)
						)
						(arc
							(start 0.1778 0.2794)
							(mid 0.249642 0.249642)
							(end 0.2794 0.1778)
						)
						(arc
							(start 0.2794 -0.1778)
							(mid 0.249642 -0.249642)
							(end 0.1778 -0.2794)
						)
					)
					(width 0)
					(fill yes)
				)
			)
		)
	)
	(footprint ""
		(layer "F.Cu")
		(at 6.604 -280.924 -90)
		(property "Reference" "R37"
			(at 0 0 270)
			(layer "F.SilkS")
			(hide yes)
			(effects
				(font
					(size 1.27 1.27)
				)
			)
		)
		(property "Value" "33R2F-3-GP"
			(at 0.064008 -3.993896 270)
			(unlocked yes)
			(layer "F.Fab")
			(hide yes)
			(effects
				(font
					(size 1.016 1.016)
					(thickness 0.1524)
				)
			)
		)
		(property "Device Type" "R402H16"
			(at 0.064008 -5.517896 270)
			(unlocked yes)
			(layer "F.Fab")
			(hide yes)
			(effects
				(font
					(size 1.016 1.016)
					(thickness 0.1524)
				)
			)
		)
		(duplicate_pad_numbers_are_jumpers no)
		(fp_line
			(start -0.508 -0.9398)
			(end -0.508 0.9398)
			(stroke
				(width 0.1524)
				(type default)
			)
			(layer "F.SilkS")
		)
		(fp_line
			(start 0.508 -0.9398)
			(end -0.508 -0.9398)
			(stroke
				(width 0.1524)
				(type default)
			)
			(layer "F.SilkS")
		)
		(fp_rect
			(start -0.508 0.9398)
			(end 0.508 -0.9398)
			(stroke
				(width 0)
				(type default)
			)
			(fill no)
			(layer "F.CrtYd")
		)
		(fp_rect
			(start -0.508 0.9398)
			(end 0.508 -0.9398)
			(stroke
				(width 0)
				(type default)
			)
			(fill no)
			(layer "F.Fab")
		)
		(pad "1" smd custom
			(at 0 -0.4445 270)
			(size 0.1397 0.1397)
			(layers "F.Cu" "F.Mask" "F.Paste")
			(net "P3V3")
			(options
				(clearance outline)
				(anchor circle)
			)
			(primitives
				(gr_poly
					(pts
						(arc
							(start -0.1778 -0.2794)
							(mid -0.249642 -0.249642)
							(end -0.2794 -0.1778)
						)
						(arc
							(start -0.2794 0.1778)
							(mid -0.249642 0.249642)
							(end -0.1778 0.2794)
						)
						(arc
							(start 0.1778 0.2794)
							(mid 0.249642 0.249642)
							(end 0.2794 0.1778)
						)
						(arc
							(start 0.2794 -0.1778)
							(mid 0.249642 -0.249642)
							(end 0.1778 -0.2794)
						)
					)
					(width 0)
					(fill yes)
				)
			)
		)
		(pad "2" smd custom
			(at 0 0.4445 270)
			(size 0.1397 0.1397)
			(layers "F.Cu" "F.Mask" "F.Paste")
			(net "LED_DR_LED2_BLUE")
			(options
				(clearance outline)
				(anchor circle)
			)
			(primitives
				(gr_poly
					(pts
						(arc
							(start -0.1778 -0.2794)
							(mid -0.249642 -0.249642)
							(end -0.2794 -0.1778)
						)
						(arc
							(start -0.2794 0.1778)
							(mid -0.249642 0.249642)
							(end -0.1778 0.2794)
						)
						(arc
							(start 0.1778 0.2794)
							(mid 0.249642 0.249642)
							(end 0.2794 0.1778)
						)
						(arc
							(start 0.2794 -0.1778)
							(mid 0.249642 -0.249642)
							(end 0.1778 -0.2794)
						)
					)
					(width 0)
					(fill yes)
				)
			)
		)
	)
	(footprint ""
		(layer "F.Cu")
		(at 7.949946 -88.535002 -90)
		(property "Reference" "LED5"
			(at 0 0 270)
			(layer "F.SilkS")
			(hide yes)
			(effects
				(font
					(size 1.27 1.27)
				)
			)
		)
		(property "Value" "LED-RB-6-GP"
			(at -4.6736 3.8354 270)
			(unlocked yes)
			(layer "F.Fab")
			(hide yes)
			(effects
				(font
					(size 1.016 1.016)
					(thickness 0.1524)
				)
			)
		)
		(property "Device Type" "LED-100-3P-067106H325"
			(at -4.6736 2.3114 270)
			(unlocked yes)
			(layer "F.Fab")
			(hide yes)
			(effects
				(font
					(size 1.016 1.016)
					(thickness 0.1524)
				)
			)
		)
		(duplicate_pad_numbers_are_jumpers no)
		(fp_line
			(start -1.7526 10.414)
			(end -1.7526 6.6548)
			(stroke
				(width 0.1524)
				(type default)
			)
			(layer "F.SilkS")
		)
		(fp_line
			(start 1.7526 10.414)
			(end -1.7526 10.414)
			(stroke
				(width 0.1524)
				(type default)
			)
			(layer "F.SilkS")
		)
		(fp_line
			(start -3.6068 6.6548)
			(end -3.6068 -0.889)
			(stroke
				(width 0.1524)
				(type default)
			)
			(layer "F.SilkS")
		)
		(fp_line
			(start -1.7526 6.6548)
			(end -3.6068 6.6548)
			(stroke
				(width 0.1524)
				(type default)
			)
			(layer "F.SilkS")
		)
		(fp_line
			(start 1.7526 6.6548)
			(end 1.7526 10.414)
			(stroke
				(width 0.1524)
				(type default)
			)
			(layer "F.SilkS")
		)
		(fp_line
			(start 3.6068 6.6548)
			(end 1.7526 6.6548)
			(stroke
				(width 0.1524)
				(type default)
			)
			(layer "F.SilkS")
		)
		(fp_line
			(start -3.6068 -0.889)
			(end 3.6068 -0.889)
			(stroke
				(width 0.1524)
				(type default)
			)
			(layer "F.SilkS")
		)
		(fp_line
			(start 3.6068 -0.889)
			(end 3.6068 6.6548)
			(stroke
				(width 0.1524)
				(type default)
			)
			(layer "F.SilkS")
		)
		(fp_circle
			(center -2.54 0)
			(end -2.54 -0.9906)
			(stroke
				(width 0.3048)
				(type default)
			)
			(fill no)
			(layer "F.SilkS")
		)
		(fp_circle
			(center 0 0)
			(end 0 -0.9906)
			(stroke
				(width 0.3048)
				(type default)
			)
			(fill no)
			(layer "F.SilkS")
		)
		(fp_circle
			(center 2.54 0)
			(end 2.54 -0.9906)
			(stroke
				(width 0.3048)
				(type default)
			)
			(fill no)
			(layer "F.SilkS")
		)
		(fp_poly
			(pts
				(xy -1.4986 10.1473) (xy -1.4986 6.4008) (xy -3.3528 6.4008) (xy -3.3528 -0.3937) (xy 3.3528 -0.3937)
				(xy 3.3528 6.4008) (xy 1.4986 6.4008) (xy 1.4986 10.1473)
			)
			(stroke
				(width 0)
				(type default)
			)
			(fill no)
			(layer "F.CrtYd")
		)
		(fp_poly
			(pts
				(xy -2.0066 10.668) (xy 2.0066 10.668) (xy 2.0066 6.9088) (xy 3.8608 6.9088) (xy 3.8608 2.2098)
				(xy 3.3528 2.2098) (xy 3.3528 6.4008) (xy 1.4986 6.4008) (xy 1.4986 10.1473) (xy -1.4986 10.1473)
				(xy -1.4986 6.4008) (xy -3.3528 6.4008) (xy -3.3528 -0.3937) (xy 3.3528 -0.3937) (xy 3.3528 2.1971)
				(xy 3.8608 2.1971) (xy 3.8608 -1.143) (xy -3.8608 -1.143) (xy -3.8608 6.9088) (xy -2.0066 6.9088)
			)
			(stroke
				(width 0)
				(type default)
			)
			(fill no)
			(layer "F.CrtYd")
		)
		(fp_poly
			(pts
				(xy -2.0066 10.668) (xy -2.0066 6.9088) (xy -3.8608 6.9088) (xy -3.8608 -1.143) (xy 3.8608 -1.143)
				(xy 3.8608 6.9088) (xy 2.0066 6.9088) (xy 2.0066 10.668)
			)
			(stroke
				(width 0)
				(type default)
			)
			(fill no)
			(layer "F.Fab")
		)
		(pad "1" thru_hole circle
			(at 2.54 0 270)
			(size 1.27 1.27)
			(drill 0.889)
			(layers "*.Cu" "*.Mask")
			(remove_unused_layers no)
			(net "LED_DR_LED4_BLUE")
			(clearance 0.1651)
			(thermal_gap 0.1651)
		)
		(pad "2" thru_hole circle
			(at 0 0 270)
			(size 1.27 1.27)
			(drill 0.889)
			(layers "*.Cu" "*.Mask")
			(remove_unused_layers no)
			(net "LED_DR_LED4_K")
			(clearance 0.1651)
			(thermal_gap 0.1651)
		)
		(pad "3" thru_hole circle
			(at -2.54 0 270)
			(size 1.27 1.27)
			(drill 0.889)
			(layers "*.Cu" "*.Mask")
			(remove_unused_layers no)
			(net "LED_DR_LED4")
			(clearance 0.1651)
			(thermal_gap 0.1651)
		)
	)
	(footprint ""
		(layer "F.Cu")
		(at 11.4554 -147.3454)
		(property "Reference" "R70"
			(at 0 0 0)
			(layer "F.SilkS")
			(hide yes)
			(effects
				(font
					(size 1.27 1.27)
				)
			)
		)
		(property "Value" "27KR3F-GP"
			(at -0.0254 -2.5146 0)
			(unlocked yes)
			(layer "F.Fab")
			(hide yes)
			(effects
				(font
					(size 1.016 1.016)
					(thickness 0.1524)
				)
			)
		)
		(property "Device Type" "R603H22"
			(at -0.0254 -4.0386 0)
			(unlocked yes)
			(layer "F.Fab")
			(hide yes)
			(effects
				(font
					(size 1.016 1.016)
					(thickness 0.1524)
				)
			)
		)
		(duplicate_pad_numbers_are_jumpers no)
		(fp_line
			(start -0.4826 0)
			(end -0.2032 0)
			(stroke
				(width 0.2032)
				(type default)
			)
			(layer "F.SilkS")
		)
		(fp_line
			(start 0.2032 0)
			(end 0.4826 0)
			(stroke
				(width 0.2032)
				(type default)
			)
			(layer "F.SilkS")
		)
		(fp_rect
			(start -0.5842 1.3335)
			(end 0.5842 -1.3335)
			(stroke
				(width 0)
				(type default)
			)
			(fill no)
			(layer "F.CrtYd")
		)
		(fp_rect
			(start -0.5842 1.3335)
			(end 0.5842 -1.3335)
			(stroke
				(width 0)
				(type default)
			)
			(fill no)
			(layer "F.Fab")
		)
		(pad "1" smd custom
			(at 0 -0.762)
			(size 0.2159 0.2159)
			(layers "F.Cu" "F.Mask" "F.Paste")
			(net "FAN_TACH10")
			(options
				(clearance outline)
				(anchor circle)
			)
			(primitives
				(gr_poly
					(pts
						(arc
							(start -0.3302 -0.4318)
							(mid -0.402042 -0.402042)
							(end -0.4318 -0.3302)
						)
						(arc
							(start -0.4318 0.3302)
							(mid -0.402042 0.402042)
							(end -0.3302 0.4318)
						)
						(arc
							(start 0.3302 0.4318)
							(mid 0.402042 0.402042)
							(end 0.4318 0.3302)
						)
						(arc
							(start 0.4318 -0.3302)
							(mid 0.402042 -0.402042)
							(end 0.3302 -0.4318)
						)
					)
					(width 0)
					(fill yes)
				)
			)
		)
		(pad "2" smd custom
			(at 0 0.762)
			(size 0.2159 0.2159)
			(layers "F.Cu" "F.Mask" "F.Paste")
			(net "FANIN_10")
			(options
				(clearance outline)
				(anchor circle)
			)
			(primitives
				(gr_poly
					(pts
						(arc
							(start -0.3302 -0.4318)
							(mid -0.402042 -0.402042)
							(end -0.4318 -0.3302)
						)
						(arc
							(start -0.4318 0.3302)
							(mid -0.402042 0.402042)
							(end -0.3302 0.4318)
						)
						(arc
							(start 0.3302 0.4318)
							(mid 0.402042 0.402042)
							(end 0.4318 0.3302)
						)
						(arc
							(start 0.4318 -0.3302)
							(mid 0.402042 -0.402042)
							(end 0.3302 -0.4318)
						)
					)
					(width 0)
					(fill yes)
				)
			)
		)
	)
	(footprint ""
		(layer "F.Cu")
		(at 33.782 -381 180)
		(property "Reference" "PR23"
			(at 0 0 180)
			(layer "F.SilkS")
			(hide yes)
			(effects
				(font
					(size 1.27 1.27)
				)
			)
		)
		(property "Value" "10R2F-L-GP"
			(at 0.064008 -3.993896 180)
			(unlocked yes)
			(layer "F.Fab")
			(hide yes)
			(effects
				(font
					(size 1.016 1.016)
					(thickness 0.1524)
				)
			)
		)
		(property "Device Type" "R402H14"
			(at 0.064008 -5.517896 180)
			(unlocked yes)
			(layer "F.Fab")
			(hide yes)
			(effects
				(font
					(size 1.016 1.016)
					(thickness 0.1524)
				)
			)
		)
		(duplicate_pad_numbers_are_jumpers no)
		(fp_line
			(start 0.508 -0.9398)
			(end -0.508 -0.9398)
			(stroke
				(width 0.1524)
				(type default)
			)
			(layer "F.SilkS")
		)
		(fp_line
			(start -0.508 -0.9398)
			(end -0.508 0.9398)
			(stroke
				(width 0.1524)
				(type default)
			)
			(layer "F.SilkS")
		)
		(fp_rect
			(start -0.508 0.9398)
			(end 0.508 -0.9398)
			(stroke
				(width 0)
				(type default)
			)
			(fill no)
			(layer "F.CrtYd")
		)
		(fp_rect
			(start -0.508 0.9398)
			(end 0.508 -0.9398)
			(stroke
				(width 0)
				(type default)
			)
			(fill no)
			(layer "F.Fab")
		)
		(pad "1" smd custom
			(at 0 -0.4445 180)
			(size 0.1397 0.1397)
			(layers "F.Cu" "F.Mask" "F.Paste")
			(net "ADM1276_SENSE-")
			(options
				(clearance outline)
				(anchor circle)
			)
			(primitives
				(gr_poly
					(pts
						(arc
							(start -0.1778 -0.2794)
							(mid -0.249642 -0.249642)
							(end -0.2794 -0.1778)
						)
						(arc
							(start -0.2794 0.1778)
							(mid -0.249642 0.249642)
							(end -0.1778 0.2794)
						)
						(arc
							(start 0.1778 0.2794)
							(mid 0.249642 0.249642)
							(end 0.2794 0.1778)
						)
						(arc
							(start 0.2794 -0.1778)
							(mid 0.249642 -0.249642)
							(end 0.1778 -0.2794)
						)
					)
					(width 0)
					(fill yes)
				)
			)
		)
		(pad "2" smd custom
			(at 0 0.4445 180)
			(size 0.1397 0.1397)
			(layers "F.Cu" "F.Mask" "F.Paste")
			(net "SENSE-_R3")
			(options
				(clearance outline)
				(anchor circle)
			)
			(primitives
				(gr_poly
					(pts
						(arc
							(start -0.1778 -0.2794)
							(mid -0.249642 -0.249642)
							(end -0.2794 -0.1778)
						)
						(arc
							(start -0.2794 0.1778)
							(mid -0.249642 0.249642)
							(end -0.1778 0.2794)
						)
						(arc
							(start 0.1778 0.2794)
							(mid 0.249642 0.249642)
							(end 0.2794 0.1778)
						)
						(arc
							(start 0.2794 -0.1778)
							(mid 0.249642 -0.249642)
							(end 0.1778 -0.2794)
						)
					)
					(width 0)
					(fill yes)
				)
			)
		)
	)
	(footprint ""
		(layer "F.Cu")
		(at 22.479 -181.7116 90)
		(property "Reference" "D8"
			(at 0 0 90)
			(layer "F.SilkS")
			(hide yes)
			(effects
				(font
					(size 1.27 1.27)
				)
			)
		)
		(property "Value" "BAS16H-GP"
			(at 0 -5.5372 90)
			(unlocked yes)
			(layer "F.Fab")
			(hide yes)
			(effects
				(font
					(size 1.016 1.016)
					(thickness 0.1524)
				)
			)
		)
		(property "Device Type" "SOD123AKH48"
			(at 0 -7.0612 90)
			(unlocked yes)
			(layer "F.Fab")
			(hide yes)
			(effects
				(font
					(size 1.016 1.016)
					(thickness 0.1524)
				)
			)
		)
		(duplicate_pad_numbers_are_jumpers no)
		(fp_line
			(start 1.016 -2.667)
			(end -1.016 -2.667)
			(stroke
				(width 0.1524)
				(type default)
			)
			(layer "F.SilkS")
		)
		(fp_line
			(start -1.016 -2.667)
			(end -1.016 2.667)
			(stroke
				(width 0.1524)
				(type default)
			)
			(layer "F.SilkS")
		)
		(fp_line
			(start 1.016 2.667)
			(end 1.016 -2.667)
			(stroke
				(width 0.1524)
				(type default)
			)
			(layer "F.SilkS")
		)
		(fp_line
			(start -1.016 2.667)
			(end 1.016 2.667)
			(stroke
				(width 0.1524)
				(type default)
			)
			(layer "F.SilkS")
		)
		(fp_line
			(start 0.889 2.921)
			(end -0.889 2.921)
			(stroke
				(width 0.508)
				(type default)
			)
			(layer "F.SilkS")
		)
		(fp_rect
			(start -1.143 3.175)
			(end 1.143 -2.794)
			(stroke
				(width 0)
				(type default)
			)
			(fill no)
			(layer "F.CrtYd")
		)
		(fp_poly
			(pts
				(xy -1.143 -2.794) (xy 1.143 -2.794) (xy 1.143 3.175) (xy -1.143 3.175)
			)
			(stroke
				(width 0)
				(type default)
			)
			(fill no)
			(layer "F.Fab")
		)
		(pad "A" smd rect
			(at 0 -1.6891 90)
			(size 0.889 1.397)
			(layers "F.Cu" "F.Mask" "F.Paste")
			(net "FAN_TACH7")
		)
		(pad "K" smd rect
			(at 0 1.6891 90)
			(size 0.889 1.397)
			(layers "F.Cu" "F.Mask" "F.Paste")
			(net "P12V")
		)
	)
	(footprint ""
		(layer "F.Cu")
		(at 43.7134 -138.5062)
		(property "Reference" "PC95"
			(at 0 0 0)
			(layer "F.SilkS")
			(hide yes)
			(effects
				(font
					(size 1.27 1.27)
				)
			)
		)
		(property "Value" "SC10U25V5KX-GP"
			(at -0.0762 -6.1214 0)
			(unlocked yes)
			(layer "F.Fab")
			(hide yes)
			(effects
				(font
					(size 1.016 1.016)
					(thickness 0.1524)
				)
			)
		)
		(property "Device Type" "C805H56"
			(at -0.0762 -8.1534 0)
			(unlocked yes)
			(layer "F.Fab")
			(hide yes)
			(effects
				(font
					(size 1.016 1.016)
					(thickness 0.1524)
				)
			)
		)
		(duplicate_pad_numbers_are_jumpers no)
		(fp_line
			(start 0.635 0)
			(end -0.635 0)
			(stroke
				(width 0.508)
				(type default)
			)
			(layer "F.SilkS")
		)
		(fp_rect
			(start -0.9652 1.778)
			(end 0.9652 -1.778)
			(stroke
				(width 0)
				(type default)
			)
			(fill no)
			(layer "F.CrtYd")
		)
		(fp_poly
			(pts
				(xy -0.9652 -1.778) (xy 0.9652 -1.778) (xy 0.9652 1.778) (xy -0.9652 1.778)
			)
			(stroke
				(width 0)
				(type default)
			)
			(fill no)
			(layer "F.Fab")
		)
		(pad "1" smd rect
			(at 0 -0.9652)
			(size 1.397 1.143)
			(layers "F.Cu" "F.Mask" "F.Paste")
			(net "P12VL_2490_EN_2")
		)
		(pad "2" smd rect
			(at 0 0.9652)
			(size 1.397 1.143)
			(layers "F.Cu" "F.Mask" "F.Paste")
			(net "GND")
		)
	)
	(footprint ""
		(layer "F.Cu")
		(at 37.999924 -56.999886 -90)
		(property "Reference" "CN10"
			(at 0 0 270)
			(layer "F.SilkS")
			(hide yes)
			(effects
				(font
					(size 1.27 1.27)
				)
			)
		)
		(property "Value" "FCI-CONN52-4R-1-GP"
			(at -30.89656 -6.096 270)
			(unlocked yes)
			(layer "F.Fab")
			(hide yes)
			(effects
				(font
					(size 1.016 1.016)
					(thickness 0.1524)
				)
			)
		)
		(property "Device Type" "51952-220LF"
			(at -30.89656 -7.62 270)
			(unlocked yes)
			(layer "F.Fab")
			(hide yes)
			(effects
				(font
					(size 1.016 1.016)
					(thickness 0.1524)
				)
			)
		)
		(duplicate_pad_numbers_are_jumpers no)
		(fp_line
			(start -29.464 3.7338)
			(end -29.464 -3.7338)
			(stroke
				(width 0.1524)
				(type default)
			)
			(layer "F.SilkS")
		)
		(fp_line
			(start 29.464 3.7338)
			(end -29.464 3.7338)
			(stroke
				(width 0.1524)
				(type default)
			)
			(layer "F.SilkS")
		)
		(fp_line
			(start -29.464 -3.7338)
			(end -22.225 -3.7338)
			(stroke
				(width 0.1524)
				(type default)
			)
			(layer "F.SilkS")
		)
		(fp_line
			(start -22.225 -3.7338)
			(end -22.225 -11.3538)
			(stroke
				(width 0.1524)
				(type default)
			)
			(layer "F.SilkS")
		)
		(fp_line
			(start 22.225 -3.7338)
			(end 29.464 -3.7338)
			(stroke
				(width 0.1524)
				(type default)
			)
			(layer "F.SilkS")
		)
		(fp_line
			(start 29.464 -3.7338)
			(end 29.464 3.7338)
			(stroke
				(width 0.1524)
				(type default)
			)
			(layer "F.SilkS")
		)
		(fp_line
			(start -22.225 -11.3538)
			(end 22.225 -11.3538)
			(stroke
				(width 0.1524)
				(type default)
			)
			(layer "F.SilkS")
		)
		(fp_line
			(start 22.225 -11.3538)
			(end 22.225 -3.7338)
			(stroke
				(width 0.1524)
				(type default)
			)
			(layer "F.SilkS")
		)
		(fp_circle
			(center -15.88008 0)
			(end -15.88008 -1.0795)
			(stroke
				(width 0.3048)
				(type default)
			)
			(fill no)
			(layer "F.SilkS")
		)
		(fp_circle
			(center -13.34008 0)
			(end -13.34008 -1.0795)
			(stroke
				(width 0.3048)
				(type default)
			)
			(fill no)
			(layer "F.SilkS")
		)
		(fp_circle
			(center -10.80008 0)
			(end -10.80008 -1.0795)
			(stroke
				(width 0.3048)
				(type default)
			)
			(fill no)
			(layer "F.SilkS")
		)
		(fp_circle
			(center -8.26008 0)
			(end -8.26008 -1.0795)
			(stroke
				(width 0.3048)
				(type default)
			)
			(fill no)
			(layer "F.SilkS")
		)
		(fp_circle
			(center -5.08 0)
			(end -5.08 -1.0795)
			(stroke
				(width 0.3048)
				(type default)
			)
			(fill no)
			(layer "F.SilkS")
		)
		(fp_circle
			(center -2.54 0)
			(end -2.54 -1.0795)
			(stroke
				(width 0.3048)
				(type default)
			)
			(fill no)
			(layer "F.SilkS")
		)
		(fp_circle
			(center 0 0)
			(end 0 -1.0795)
			(stroke
				(width 0.3048)
				(type default)
			)
			(fill no)
			(layer "F.SilkS")
		)
		(fp_circle
			(center 2.54 0)
			(end 2.54 -1.0795)
			(stroke
				(width 0.3048)
				(type default)
			)
			(fill no)
			(layer "F.SilkS")
		)
		(fp_circle
			(center 5.08 0)
			(end 5.08 -1.0795)
			(stroke
				(width 0.3048)
				(type default)
			)
			(fill no)
			(layer "F.SilkS")
		)
		(fp_circle
			(center 8.26008 0)
			(end 8.26008 -1.0795)
			(stroke
				(width 0.3048)
				(type default)
			)
			(fill no)
			(layer "F.SilkS")
		)
		(fp_circle
			(center 10.80008 0)
			(end 10.80008 -1.0795)
			(stroke
				(width 0.3048)
				(type default)
			)
			(fill no)
			(layer "F.SilkS")
		)
		(fp_circle
			(center 13.34008 0)
			(end 13.34008 -1.0795)
			(stroke
				(width 0.3048)
				(type default)
			)
			(fill no)
			(layer "F.SilkS")
		)
		(fp_circle
			(center 15.88008 0)
			(end 15.88008 -1.0795)
			(stroke
				(width 0.3048)
				(type default)
			)
			(fill no)
			(layer "F.SilkS")
		)
		(fp_circle
			(center -15.88008 -2.54)
			(end -15.88008 -3.6195)
			(stroke
				(width 0.3048)
				(type default)
			)
			(fill no)
			(layer "F.SilkS")
		)
		(fp_circle
			(center -13.34008 -2.54)
			(end -13.34008 -3.6195)
			(stroke
				(width 0.3048)
				(type default)
			)
			(fill no)
			(layer "F.SilkS")
		)
		(fp_circle
			(center -10.80008 -2.54)
			(end -10.80008 -3.6195)
			(stroke
				(width 0.3048)
				(type default)
			)
			(fill no)
			(layer "F.SilkS")
		)
		(fp_circle
			(center -8.26008 -2.54)
			(end -8.26008 -3.6195)
			(stroke
				(width 0.3048)
				(type default)
			)
			(fill no)
			(layer "F.SilkS")
		)
		(fp_circle
			(center -5.08 -2.54)
			(end -5.08 -3.6195)
			(stroke
				(width 0.3048)
				(type default)
			)
			(fill no)
			(layer "F.SilkS")
		)
		(fp_circle
			(center -2.54 -2.54)
			(end -2.54 -3.6195)
			(stroke
				(width 0.3048)
				(type default)
			)
			(fill no)
			(layer "F.SilkS")
		)
		(fp_circle
			(center 0 -2.54)
			(end 0 -3.6195)
			(stroke
				(width 0.3048)
				(type default)
			)
			(fill no)
			(layer "F.SilkS")
		)
		(fp_circle
			(center 2.54 -2.54)
			(end 2.54 -3.6195)
			(stroke
				(width 0.3048)
				(type default)
			)
			(fill no)
			(layer "F.SilkS")
		)
		(fp_circle
			(center 5.08 -2.54)
			(end 5.08 -3.6195)
			(stroke
				(width 0.3048)
				(type default)
			)
			(fill no)
			(layer "F.SilkS")
		)
		(fp_circle
			(center 8.26008 -2.54)
			(end 8.26008 -3.6195)
			(stroke
				(width 0.3048)
				(type default)
			)
			(fill no)
			(layer "F.SilkS")
		)
		(fp_circle
			(center 10.80008 -2.54)
			(end 10.80008 -3.6195)
			(stroke
				(width 0.3048)
				(type default)
			)
			(fill no)
			(layer "F.SilkS")
		)
		(fp_circle
			(center 13.34008 -2.54)
			(end 13.34008 -3.6195)
			(stroke
				(width 0.3048)
				(type default)
			)
			(fill no)
			(layer "F.SilkS")
		)
		(fp_circle
			(center 15.88008 -2.54)
			(end 15.88008 -3.6195)
			(stroke
				(width 0.3048)
				(type default)
			)
			(fill no)
			(layer "F.SilkS")
		)
		(fp_circle
			(center -15.88008 -5.08)
			(end -15.88008 -6.1595)
			(stroke
				(width 0.3048)
				(type default)
			)
			(fill no)
			(layer "F.SilkS")
		)
		(fp_circle
			(center -13.34008 -5.08)
			(end -13.34008 -6.1595)
			(stroke
				(width 0.3048)
				(type default)
			)
			(fill no)
			(layer "F.SilkS")
		)
		(fp_circle
			(center -10.80008 -5.08)
			(end -10.80008 -6.1595)
			(stroke
				(width 0.3048)
				(type default)
			)
			(fill no)
			(layer "F.SilkS")
		)
		(fp_circle
			(center -8.26008 -5.08)
			(end -8.26008 -6.1595)
			(stroke
				(width 0.3048)
				(type default)
			)
			(fill no)
			(layer "F.SilkS")
		)
		(fp_circle
			(center -5.08 -5.08)
			(end -5.08 -6.1595)
			(stroke
				(width 0.3048)
				(type default)
			)
			(fill no)
			(layer "F.SilkS")
		)
		(fp_circle
			(center -2.54 -5.08)
			(end -2.54 -6.1595)
			(stroke
				(width 0.3048)
				(type default)
			)
			(fill no)
			(layer "F.SilkS")
		)
		(fp_circle
			(center 0 -5.08)
			(end 0 -6.1595)
			(stroke
				(width 0.3048)
				(type default)
			)
			(fill no)
			(layer "F.SilkS")
		)
		(fp_circle
			(center 2.54 -5.08)
			(end 2.54 -6.1595)
			(stroke
				(width 0.3048)
				(type default)
			)
			(fill no)
			(layer "F.SilkS")
		)
		(fp_circle
			(center 5.08 -5.08)
			(end 5.08 -6.1595)
			(stroke
				(width 0.3048)
				(type default)
			)
			(fill no)
			(layer "F.SilkS")
		)
		(fp_circle
			(center 8.26008 -5.08)
			(end 8.26008 -6.1595)
			(stroke
				(width 0.3048)
				(type default)
			)
			(fill no)
			(layer "F.SilkS")
		)
		(fp_circle
			(center 10.80008 -5.08)
			(end 10.80008 -6.1595)
			(stroke
				(width 0.3048)
				(type default)
			)
			(fill no)
			(layer "F.SilkS")
		)
		(fp_circle
			(center 13.34008 -5.08)
			(end 13.34008 -6.1595)
			(stroke
				(width 0.3048)
				(type default)
			)
			(fill no)
			(layer "F.SilkS")
		)
		(fp_circle
			(center 15.88008 -5.08)
			(end 15.88008 -6.1595)
			(stroke
				(width 0.3048)
				(type default)
			)
			(fill no)
			(layer "F.SilkS")
		)
		(fp_circle
			(center -15.88008 -7.62)
			(end -15.88008 -8.6995)
			(stroke
				(width 0.3048)
				(type default)
			)
			(fill no)
			(layer "F.SilkS")
		)
		(fp_circle
			(center -13.34008 -7.62)
			(end -13.34008 -8.6995)
			(stroke
				(width 0.3048)
				(type default)
			)
			(fill no)
			(layer "F.SilkS")
		)
		(fp_circle
			(center -10.80008 -7.62)
			(end -10.80008 -8.6995)
			(stroke
				(width 0.3048)
				(type default)
			)
			(fill no)
			(layer "F.SilkS")
		)
		(fp_circle
			(center -8.26008 -7.62)
			(end -8.26008 -8.6995)
			(stroke
				(width 0.3048)
				(type default)
			)
			(fill no)
			(layer "F.SilkS")
		)
		(fp_circle
			(center -5.08 -7.62)
			(end -5.08 -8.6995)
			(stroke
				(width 0.3048)
				(type default)
			)
			(fill no)
			(layer "F.SilkS")
		)
		(fp_circle
			(center -2.54 -7.62)
			(end -2.54 -8.6995)
			(stroke
				(width 0.3048)
				(type default)
			)
			(fill no)
			(layer "F.SilkS")
		)
		(fp_circle
			(center 0 -7.62)
			(end 0 -8.6995)
			(stroke
				(width 0.3048)
				(type default)
			)
			(fill no)
			(layer "F.SilkS")
		)
		(fp_circle
			(center 2.54 -7.62)
			(end 2.54 -8.6995)
			(stroke
				(width 0.3048)
				(type default)
			)
			(fill no)
			(layer "F.SilkS")
		)
		(fp_circle
			(center 5.08 -7.62)
			(end 5.08 -8.6995)
			(stroke
				(width 0.3048)
				(type default)
			)
			(fill no)
			(layer "F.SilkS")
		)
		(fp_circle
			(center 8.26008 -7.62)
			(end 8.26008 -8.6995)
			(stroke
				(width 0.3048)
				(type default)
			)
			(fill no)
			(layer "F.SilkS")
		)
		(fp_circle
			(center 10.80008 -7.62)
			(end 10.80008 -8.6995)
			(stroke
				(width 0.3048)
				(type default)
			)
			(fill no)
			(layer "F.SilkS")
		)
		(fp_circle
			(center 13.34008 -7.62)
			(end 13.34008 -8.6995)
			(stroke
				(width 0.3048)
				(type default)
			)
			(fill no)
			(layer "F.SilkS")
		)
		(fp_circle
			(center 15.88008 -7.62)
			(end 15.88008 -8.6995)
			(stroke
				(width 0.3048)
				(type default)
			)
			(fill no)
			(layer "F.SilkS")
		)
		(fp_poly
			(pts
				(xy -29.21 3.4798) (xy -29.21 -3.4798) (xy -21.971 -3.4798) (xy -21.971 -11.0998) (xy 21.971 -11.0998)
				(xy 21.971 -3.4798) (xy 29.21 -3.4798) (xy 29.21 3.4798)
			)
			(stroke
				(width 0)
				(type default)
			)
			(fill no)
			(layer "F.CrtYd")
		)
		(fp_poly
			(pts
				(xy -29.718 3.9878) (xy -29.718 -11.6078) (xy 29.718 -11.6078) (xy 29.718 -0.00635) (xy 29.21 -0.00635)
				(xy 29.21 -3.4798) (xy 21.971 -3.4798) (xy 21.971 -11.0998) (xy -21.971 -11.0998) (xy -21.971 -3.4798)
				(xy -29.21 -3.4798) (xy -29.21 3.4798) (xy 29.21 3.4798) (xy 29.21 0.00635) (xy 29.718 0.00635)
				(xy 29.718 3.9878)
			)
			(stroke
				(width 0)
				(type default)
			)
			(fill no)
			(layer "F.CrtYd")
		)
		(fp_poly
			(pts
				(xy -29.718 3.9878) (xy -29.718 -11.6078) (xy 29.718 -11.6078) (xy 29.718 3.9878)
			)
			(stroke
				(width 0)
				(type default)
			)
			(fill no)
			(layer "F.Fab")
		)
		(pad "" np_thru_hole circle
			(at -26.67 0 270)
			(size 0.254 0.254)
			(drill 3.2004)
			(layers "*.Cu" "*.Mask")
			(clearance 1.8288)
			(thermal_gap 1.8288)
		)
		(pad "" np_thru_hole circle
			(at -21.59 0 270)
			(size 0.254 0.254)
			(drill 2.5146)
			(layers "*.Cu" "*.Mask")
			(clearance 1.4859)
			(thermal_gap 1.4859)
		)
		(pad "" np_thru_hole circle
			(at 21.59 0 270)
			(size 0.254 0.254)
			(drill 2.5146)
			(layers "*.Cu" "*.Mask")
			(clearance 1.4859)
			(thermal_gap 1.4859)
		)
		(pad "" np_thru_hole circle
			(at 26.67 0 270)
			(size 0.254 0.254)
			(drill 3.2004)
			(layers "*.Cu" "*.Mask")
			(clearance 1.8288)
			(thermal_gap 1.8288)
		)
		(pad "A1" thru_hole circle
			(at -5.08 0 270)
			(size 1.4478 1.4478)
			(drill 1.0414)
			(layers "*.Cu" "*.Mask")
			(remove_unused_layers no)
			(net "I2C_C_SDA_CONN_R")
			(clearance 0.1524)
			(thermal_gap 0.1524)
		)
		(pad "A2" thru_hole circle
			(at -2.54 0 270)
			(size 1.4478 1.4478)
			(drill 1.0414)
			(layers "*.Cu" "*.Mask")
			(remove_unused_layers no)
			(net "GND")
			(clearance 0.1524)
			(thermal_gap 0.1524)
		)
		(pad "A3" thru_hole circle
			(at 0 0 270)
			(size 1.4478 1.4478)
			(drill 1.0414)
			(layers "*.Cu" "*.Mask")
			(remove_unused_layers no)
			(net "I2C_C_SCL_CONN_R")
			(clearance 0.1524)
			(thermal_gap 0.1524)
		)
		(pad "A4" thru_hole circle
			(at 2.54 0 270)
			(size 1.4478 1.4478)
			(drill 1.0414)
			(layers "*.Cu" "*.Mask")
			(remove_unused_layers no)
			(net "GND")
			(clearance 0.1524)
			(thermal_gap 0.1524)
		)
		(pad "A5" thru_hole circle
			(at 5.08 0 270)
			(size 1.4478 1.4478)
			(drill 1.0414)
			(layers "*.Cu" "*.Mask")
			(remove_unused_layers no)
			(net "PWM_EXP_2B")
			(clearance 0.1524)
			(thermal_gap 0.1524)
		)
		(pad "B1" thru_hole circle
			(at -5.08 -2.54 270)
			(size 1.4478 1.4478)
			(drill 1.0414)
			(layers "*.Cu" "*.Mask")
			(remove_unused_layers no)
			(net "GND")
			(clearance 0.1524)
			(thermal_gap 0.1524)
		)
		(pad "B2" thru_hole circle
			(at -2.54 -2.54 270)
			(size 1.4478 1.4478)
			(drill 1.0414)
			(layers "*.Cu" "*.Mask")
			(remove_unused_layers no)
			(net "PWM_EXP_2A")
			(clearance 0.1524)
			(thermal_gap 0.1524)
		)
		(pad "B3" thru_hole circle
			(at 0 -2.54 270)
			(size 1.4478 1.4478)
			(drill 1.0414)
			(layers "*.Cu" "*.Mask")
			(remove_unused_layers no)
			(net "GND")
			(clearance 0.1524)
			(thermal_gap 0.1524)
		)
		(pad "B4" thru_hole circle
			(at 2.54 -2.54 270)
			(size 1.4478 1.4478)
			(drill 1.0414)
			(layers "*.Cu" "*.Mask")
			(remove_unused_layers no)
			(net "SELF_2B_HB")
			(clearance 0.1524)
			(thermal_gap 0.1524)
		)
		(pad "B5" thru_hole circle
			(at 5.08 -2.54 270)
			(size 1.4478 1.4478)
			(drill 1.0414)
			(layers "*.Cu" "*.Mask")
			(remove_unused_layers no)
			(net "GND")
			(clearance 0.1524)
			(thermal_gap 0.1524)
		)
		(pad "C1" thru_hole circle
			(at -5.08 -5.08 270)
			(size 1.4478 1.4478)
			(drill 1.0414)
			(layers "*.Cu" "*.Mask")
			(remove_unused_layers no)
			(net "P12VL_2490_EN_1")
			(clearance 0.1524)
			(thermal_gap 0.1524)
		)
		(pad "C2" thru_hole circle
			(at -2.54 -5.08 270)
			(size 1.4478 1.4478)
			(drill 1.0414)
			(layers "*.Cu" "*.Mask")
			(remove_unused_layers no)
			(net "P12VL_2490_EN_2")
			(clearance 0.1524)
			(thermal_gap 0.1524)
		)
		(pad "C3" thru_hole circle
			(at 0 -5.08 270)
			(size 1.4478 1.4478)
			(drill 1.0414)
			(layers "*.Cu" "*.Mask")
			(remove_unused_layers no)
			(net "SELF_2A_HB")
			(clearance 0.1524)
			(thermal_gap 0.1524)
		)
		(pad "C4" thru_hole circle
			(at 2.54 -5.08 270)
			(size 1.4478 1.4478)
			(drill 1.0414)
			(layers "*.Cu" "*.Mask")
			(remove_unused_layers no)
			(net "SEB_PEER_2A_HB")
			(clearance 0.1524)
			(thermal_gap 0.1524)
		)
		(pad "C5" thru_hole circle
			(at 5.08 -5.08 270)
			(size 1.4478 1.4478)
			(drill 1.0414)
			(layers "*.Cu" "*.Mask")
			(remove_unused_layers no)
			(net "SEB_PEER_2B_HB")
			(clearance 0.1524)
			(thermal_gap 0.1524)
		)
		(pad "D1" thru_hole circle
			(at -5.08 -7.62 270)
			(size 1.4478 1.4478)
			(drill 1.0414)
			(layers "*.Cu" "*.Mask")
			(remove_unused_layers no)
			(net "PEER_TRAY PRESENT_LOWER")
			(clearance 0.1524)
			(thermal_gap 0.1524)
		)
		(pad "D2" thru_hole circle
			(at -2.54 -7.62 270)
			(size 1.4478 1.4478)
			(drill 1.0414)
			(layers "*.Cu" "*.Mask")
			(remove_unused_layers no)
			(net "LOWER_TRAY_ID")
			(clearance 0.1524)
			(thermal_gap 0.1524)
		)
		(pad "D3" thru_hole circle
			(at 0 -7.62 270)
			(size 1.4478 1.4478)
			(drill 1.0414)
			(layers "*.Cu" "*.Mask")
			(remove_unused_layers no)
			(net "FCB_HW_REVISION")
			(clearance 0.1524)
			(thermal_gap 0.1524)
		)
		(pad "D4" thru_hole circle
			(at 2.54 -7.62 270)
			(size 1.4478 1.4478)
			(drill 1.0414)
			(layers "*.Cu" "*.Mask")
			(remove_unused_layers no)
			(net "SD_LATCH_RELEASE_L")
			(clearance 0.1524)
			(thermal_gap 0.1524)
		)
		(pad "D5" thru_hole circle
			(at 5.08 -7.62 270)
			(size 1.4478 1.4478)
			(drill 1.0414)
			(layers "*.Cu" "*.Mask")
			(remove_unused_layers no)
			(net "SELF_TRAY_PRESENT_LOWER")
			(clearance 0.1524)
			(thermal_gap 0.1524)
		)
		(pad "P1_1" thru_hole circle
			(at -15.88008 0 270)
			(size 1.4478 1.4478)
			(drill 1.0414)
			(layers "*.Cu" "*.Mask")
			(remove_unused_layers no)
			(net "P12VL")
			(clearance 0.1524)
			(thermal_gap 0.1524)
		)
		(pad "P1_2" thru_hole circle
			(at -15.88008 -2.54 270)
			(size 1.4478 1.4478)
			(drill 1.0414)
			(layers "*.Cu" "*.Mask")
			(remove_unused_layers no)
			(net "P12VL")
			(clearance 0.1524)
			(thermal_gap 0.1524)
		)
		(pad "P1_3" thru_hole circle
			(at -15.88008 -5.08 270)
			(size 1.4478 1.4478)
			(drill 1.0414)
			(layers "*.Cu" "*.Mask")
			(remove_unused_layers no)
			(net "P12VL")
			(clearance 0.1524)
			(thermal_gap 0.1524)
		)
		(pad "P1_4" thru_hole circle
			(at -15.88008 -7.62 270)
			(size 1.4478 1.4478)
			(drill 1.0414)
			(layers "*.Cu" "*.Mask")
			(remove_unused_layers no)
			(net "P12VL")
			(clearance 0.1524)
			(thermal_gap 0.1524)
		)
		(pad "P1_5" thru_hole circle
			(at -13.34008 0 270)
			(size 1.4478 1.4478)
			(drill 1.0414)
			(layers "*.Cu" "*.Mask")
			(remove_unused_layers no)
			(net "P12VL")
			(clearance 0.1524)
			(thermal_gap 0.1524)
		)
		(pad "P1_6" thru_hole circle
			(at -13.34008 -2.54 270)
			(size 1.4478 1.4478)
			(drill 1.0414)
			(layers "*.Cu" "*.Mask")
			(remove_unused_layers no)
			(net "P12VL")
			(clearance 0.1524)
			(thermal_gap 0.1524)
		)
		(pad "P1_7" thru_hole circle
			(at -13.34008 -5.08 270)
			(size 1.4478 1.4478)
			(drill 1.0414)
			(layers "*.Cu" "*.Mask")
			(remove_unused_layers no)
			(net "P12VL")
			(clearance 0.1524)
			(thermal_gap 0.1524)
		)
		(pad "P1_8" thru_hole circle
			(at -13.34008 -7.62 270)
			(size 1.4478 1.4478)
			(drill 1.0414)
			(layers "*.Cu" "*.Mask")
			(remove_unused_layers no)
			(net "P12VL")
			(clearance 0.1524)
			(thermal_gap 0.1524)
		)
		(pad "P2_1" thru_hole circle
			(at -10.80008 0 270)
			(size 1.4478 1.4478)
			(drill 1.0414)
			(layers "*.Cu" "*.Mask")
			(remove_unused_layers no)
			(net "P12VL")
			(clearance 0.1524)
			(thermal_gap 0.1524)
		)
		(pad "P2_2" thru_hole circle
			(at -10.80008 -2.54 270)
			(size 1.4478 1.4478)
			(drill 1.0414)
			(layers "*.Cu" "*.Mask")
			(remove_unused_layers no)
			(net "P12VL")
			(clearance 0.1524)
			(thermal_gap 0.1524)
		)
		(pad "P2_3" thru_hole circle
			(at -10.80008 -5.08 270)
			(size 1.4478 1.4478)
			(drill 1.0414)
			(layers "*.Cu" "*.Mask")
			(remove_unused_layers no)
			(net "P12VL")
			(clearance 0.1524)
			(thermal_gap 0.1524)
		)
		(pad "P2_4" thru_hole circle
			(at -10.80008 -7.62 270)
			(size 1.4478 1.4478)
			(drill 1.0414)
			(layers "*.Cu" "*.Mask")
			(remove_unused_layers no)
			(net "P12VL")
			(clearance 0.1524)
			(thermal_gap 0.1524)
		)
		(pad "P2_5" thru_hole circle
			(at -8.26008 0 270)
			(size 1.4478 1.4478)
			(drill 1.0414)
			(layers "*.Cu" "*.Mask")
			(remove_unused_layers no)
			(net "P12VL")
			(clearance 0.1524)
			(thermal_gap 0.1524)
		)
		(pad "P2_6" thru_hole circle
			(at -8.26008 -2.54 270)
			(size 1.4478 1.4478)
			(drill 1.0414)
			(layers "*.Cu" "*.Mask")
			(remove_unused_layers no)
			(net "P12VL")
			(clearance 0.1524)
			(thermal_gap 0.1524)
		)
		(pad "P2_7" thru_hole circle
			(at -8.26008 -5.08 270)
			(size 1.4478 1.4478)
			(drill 1.0414)
			(layers "*.Cu" "*.Mask")
			(remove_unused_layers no)
			(net "P12VL")
			(clearance 0.1524)
			(thermal_gap 0.1524)
		)
		(pad "P2_8" thru_hole circle
			(at -8.26008 -7.62 270)
			(size 1.4478 1.4478)
			(drill 1.0414)
			(layers "*.Cu" "*.Mask")
			(remove_unused_layers no)
			(net "P12VL")
			(clearance 0.1524)
			(thermal_gap 0.1524)
		)
		(pad "P3_1" thru_hole circle
			(at 8.26008 0 270)
			(size 1.4478 1.4478)
			(drill 1.0414)
			(layers "*.Cu" "*.Mask")
			(remove_unused_layers no)
			(net "GND")
			(clearance 0.1524)
			(thermal_gap 0.1524)
		)
		(pad "P3_2" thru_hole circle
			(at 8.26008 -2.54 270)
			(size 1.4478 1.4478)
			(drill 1.0414)
			(layers "*.Cu" "*.Mask")
			(remove_unused_layers no)
			(net "GND")
			(clearance 0.1524)
			(thermal_gap 0.1524)
		)
		(pad "P3_3" thru_hole circle
			(at 8.26008 -5.08 270)
			(size 1.4478 1.4478)
			(drill 1.0414)
			(layers "*.Cu" "*.Mask")
			(remove_unused_layers no)
			(net "GND")
			(clearance 0.1524)
			(thermal_gap 0.1524)
		)
		(pad "P3_4" thru_hole circle
			(at 8.26008 -7.62 270)
			(size 1.4478 1.4478)
			(drill 1.0414)
			(layers "*.Cu" "*.Mask")
			(remove_unused_layers no)
			(net "GND")
			(clearance 0.1524)
			(thermal_gap 0.1524)
		)
		(pad "P3_5" thru_hole circle
			(at 10.80008 0 270)
			(size 1.4478 1.4478)
			(drill 1.0414)
			(layers "*.Cu" "*.Mask")
			(remove_unused_layers no)
			(net "GND")
			(clearance 0.1524)
			(thermal_gap 0.1524)
		)
		(pad "P3_6" thru_hole circle
			(at 10.80008 -2.54 270)
			(size 1.4478 1.4478)
			(drill 1.0414)
			(layers "*.Cu" "*.Mask")
			(remove_unused_layers no)
			(net "GND")
			(clearance 0.1524)
			(thermal_gap 0.1524)
		)
		(pad "P3_7" thru_hole circle
			(at 10.80008 -5.08 270)
			(size 1.4478 1.4478)
			(drill 1.0414)
			(layers "*.Cu" "*.Mask")
			(remove_unused_layers no)
			(net "GND")
			(clearance 0.1524)
			(thermal_gap 0.1524)
		)
		(pad "P3_8" thru_hole circle
			(at 10.80008 -7.62 270)
			(size 1.4478 1.4478)
			(drill 1.0414)
			(layers "*.Cu" "*.Mask")
			(remove_unused_layers no)
			(net "GND")
			(clearance 0.1524)
			(thermal_gap 0.1524)
		)
		(pad "P4_1" thru_hole circle
			(at 13.34008 0 270)
			(size 1.4478 1.4478)
			(drill 1.0414)
			(layers "*.Cu" "*.Mask")
			(remove_unused_layers no)
			(net "GND")
			(clearance 0.1524)
			(thermal_gap 0.1524)
		)
		(pad "P4_2" thru_hole circle
			(at 13.34008 -2.54 270)
			(size 1.4478 1.4478)
			(drill 1.0414)
			(layers "*.Cu" "*.Mask")
			(remove_unused_layers no)
			(net "GND")
			(clearance 0.1524)
			(thermal_gap 0.1524)
		)
		(pad "P4_3" thru_hole circle
			(at 13.34008 -5.08 270)
			(size 1.4478 1.4478)
			(drill 1.0414)
			(layers "*.Cu" "*.Mask")
			(remove_unused_layers no)
			(net "GND")
			(clearance 0.1524)
			(thermal_gap 0.1524)
		)
		(pad "P4_4" thru_hole circle
			(at 13.34008 -7.62 270)
			(size 1.4478 1.4478)
			(drill 1.0414)
			(layers "*.Cu" "*.Mask")
			(remove_unused_layers no)
			(net "GND")
			(clearance 0.1524)
			(thermal_gap 0.1524)
		)
		(pad "P4_5" thru_hole circle
			(at 15.88008 0 270)
			(size 1.4478 1.4478)
			(drill 1.0414)
			(layers "*.Cu" "*.Mask")
			(remove_unused_layers no)
			(net "GND")
			(clearance 0.1524)
			(thermal_gap 0.1524)
		)
		(pad "P4_6" thru_hole circle
			(at 15.88008 -2.54 270)
			(size 1.4478 1.4478)
			(drill 1.0414)
			(layers "*.Cu" "*.Mask")
			(remove_unused_layers no)
			(net "GND")
			(clearance 0.1524)
			(thermal_gap 0.1524)
		)
		(pad "P4_7" thru_hole circle
			(at 15.88008 -5.08 270)
			(size 1.4478 1.4478)
			(drill 1.0414)
			(layers "*.Cu" "*.Mask")
			(remove_unused_layers no)
			(net "GND")
			(clearance 0.1524)
			(thermal_gap 0.1524)
		)
		(pad "P4_8" thru_hole circle
			(at 15.88008 -7.62 270)
			(size 1.4478 1.4478)
			(drill 1.0414)
			(layers "*.Cu" "*.Mask")
			(remove_unused_layers no)
			(net "GND")
			(clearance 0.1524)
			(thermal_gap 0.1524)
		)
		(zone
			(layers "F.Cu" "B.Cu" "In1.Cu" "In2.Cu")
			(hatch none 0.5)
			(connect_pads
				(clearance 0)
			)
			(min_thickness 0.25)
			(keepout
				(tracks not_allowed)
				(vias allowed)
				(pads allowed)
				(copperpour not_allowed)
				(footprints allowed)
			)
			(placement
				(enabled no)
				(sheetname "")
			)
			(fill
				(thermal_gap 0.5)
				(thermal_bridge_width 0.5)
				(island_removal_mode 0)
			)
			(polygon
				(pts
					(arc
						(start 39.562024 -78.589886)
						(mid 36.437824 -78.589886)
						(end 39.562024 -78.589886)
					)
				)
			)
		)
		(zone
			(layers "F.Cu" "B.Cu" "In1.Cu" "In2.Cu")
			(hatch none 0.5)
			(connect_pads
				(clearance 0)
			)
			(min_thickness 0.25)
			(keepout
				(tracks not_allowed)
				(vias allowed)
				(pads allowed)
				(copperpour not_allowed)
				(footprints allowed)
			)
			(placement
				(enabled no)
				(sheetname "")
			)
			(fill
				(thermal_gap 0.5)
				(thermal_bridge_width 0.5)
				(island_removal_mode 0)
			)
			(polygon
				(pts
					(arc
						(start 39.562024 -35.409886)
						(mid 36.437824 -35.409886)
						(end 39.562024 -35.409886)
					)
				)
			)
		)
		(zone
			(layers "F.Cu" "B.Cu" "In1.Cu" "In2.Cu")
			(hatch none 0.5)
			(connect_pads
				(clearance 0)
			)
			(min_thickness 0.25)
			(keepout
				(tracks not_allowed)
				(vias allowed)
				(pads allowed)
				(copperpour not_allowed)
				(footprints allowed)
			)
			(placement
				(enabled no)
				(sheetname "")
			)
			(fill
				(thermal_gap 0.5)
				(thermal_bridge_width 0.5)
				(island_removal_mode 0)
			)
			(polygon
				(pts
					(arc
						(start 39.904924 -83.669886)
						(mid 36.094924 -83.669886)
						(end 39.904924 -83.669886)
					)
				)
			)
		)
		(zone
			(layers "F.Cu" "B.Cu" "In1.Cu" "In2.Cu")
			(hatch none 0.5)
			(connect_pads
				(clearance 0)
			)
			(min_thickness 0.25)
			(keepout
				(tracks not_allowed)
				(vias allowed)
				(pads allowed)
				(copperpour not_allowed)
				(footprints allowed)
			)
			(placement
				(enabled no)
				(sheetname "")
			)
			(fill
				(thermal_gap 0.5)
				(thermal_bridge_width 0.5)
				(island_removal_mode 0)
			)
			(polygon
				(pts
					(arc
						(start 39.904924 -30.329886)
						(mid 36.094924 -30.329886)
						(end 39.904924 -30.329886)
					)
				)
			)
		)
	)
	(footprint ""
		(layer "F.Cu")
		(at 41.0464 -139.5222 -90)
		(property "Reference" "PC86"
			(at 0 0 270)
			(layer "F.SilkS")
			(hide yes)
			(effects
				(font
					(size 1.27 1.27)
				)
			)
		)
		(property "Value" "SCD01U25V2KX-3GP"
			(at 1.1811 -2.7051 270)
			(unlocked yes)
			(layer "F.Fab")
			(hide yes)
			(effects
				(font
					(size 1.016 1.016)
					(thickness 0.1524)
				)
			)
		)
		(property "Device Type" "C402H22"
			(at 1.1811 -4.2291 270)
			(unlocked yes)
			(layer "F.Fab")
			(hide yes)
			(effects
				(font
					(size 1.016 1.016)
					(thickness 0.1524)
				)
			)
		)
		(duplicate_pad_numbers_are_jumpers no)
		(fp_rect
			(start -0.4318 0.9525)
			(end 0.4318 -0.9525)
			(stroke
				(width 0)
				(type default)
			)
			(fill no)
			(layer "F.CrtYd")
		)
		(fp_rect
			(start -0.4318 0.9525)
			(end 0.4318 -0.9525)
			(stroke
				(width 0)
				(type default)
			)
			(fill no)
			(layer "F.Fab")
		)
		(pad "1" smd custom
			(at 0 -0.4445 270)
			(size 0.1524 0.1524)
			(layers "F.Cu" "F.Mask" "F.Paste")
			(net "P12VL_2490_RC")
			(options
				(clearance outline)
				(anchor circle)
			)
			(primitives
				(gr_poly
					(pts
						(arc
							(start 0.3048 -0.2032)
							(mid 0.275042 -0.275042)
							(end 0.2032 -0.3048)
						)
						(arc
							(start -0.2032 -0.3048)
							(mid -0.275042 -0.275042)
							(end -0.3048 -0.2032)
						)
						(arc
							(start -0.3048 0.2032)
							(mid -0.275042 0.275042)
							(end -0.2032 0.3048)
						)
						(arc
							(start 0.2032 0.3048)
							(mid 0.275042 0.275042)
							(end 0.3048 0.2032)
						)
					)
					(width 0)
					(fill yes)
				)
			)
		)
		(pad "2" smd custom
			(at 0 0.4445 270)
			(size 0.1524 0.1524)
			(layers "F.Cu" "F.Mask" "F.Paste")
			(net "GND")
			(options
				(clearance outline)
				(anchor circle)
			)
			(primitives
				(gr_poly
					(pts
						(arc
							(start 0.3048 -0.2032)
							(mid 0.275042 -0.275042)
							(end 0.2032 -0.3048)
						)
						(arc
							(start -0.2032 -0.3048)
							(mid -0.275042 -0.275042)
							(end -0.3048 -0.2032)
						)
						(arc
							(start -0.3048 0.2032)
							(mid -0.275042 0.275042)
							(end -0.2032 0.3048)
						)
						(arc
							(start 0.2032 0.3048)
							(mid 0.275042 0.275042)
							(end 0.3048 0.2032)
						)
					)
					(width 0)
					(fill yes)
				)
			)
		)
	)
	(footprint ""
		(layer "F.Cu")
		(at 24.8666 -136.6012 90)
		(property "Reference" "PC89"
			(at 0 0 90)
			(layer "F.SilkS")
			(hide yes)
			(effects
				(font
					(size 1.27 1.27)
				)
			)
		)
		(property "Value" "SCD1U25V2KX-GP"
			(at 1.1811 -2.7051 90)
			(unlocked yes)
			(layer "F.Fab")
			(hide yes)
			(effects
				(font
					(size 1.016 1.016)
					(thickness 0.1524)
				)
			)
		)
		(property "Device Type" "C402H22"
			(at 1.1811 -4.2291 90)
			(unlocked yes)
			(layer "F.Fab")
			(hide yes)
			(effects
				(font
					(size 1.016 1.016)
					(thickness 0.1524)
				)
			)
		)
		(duplicate_pad_numbers_are_jumpers no)
		(fp_rect
			(start -0.4318 0.9525)
			(end 0.4318 -0.9525)
			(stroke
				(width 0)
				(type default)
			)
			(fill no)
			(layer "F.CrtYd")
		)
		(fp_rect
			(start -0.4318 0.9525)
			(end 0.4318 -0.9525)
			(stroke
				(width 0)
				(type default)
			)
			(fill no)
			(layer "F.Fab")
		)
		(pad "1" smd custom
			(at 0 -0.4445 90)
			(size 0.1524 0.1524)
			(layers "F.Cu" "F.Mask" "F.Paste")
			(net "P12VU_2490_VCC")
			(options
				(clearance outline)
				(anchor circle)
			)
			(primitives
				(gr_poly
					(pts
						(arc
							(start 0.3048 -0.2032)
							(mid 0.275042 -0.275042)
							(end 0.2032 -0.3048)
						)
						(arc
							(start -0.2032 -0.3048)
							(mid -0.275042 -0.275042)
							(end -0.3048 -0.2032)
						)
						(arc
							(start -0.3048 0.2032)
							(mid -0.275042 0.275042)
							(end -0.2032 0.3048)
						)
						(arc
							(start 0.2032 0.3048)
							(mid 0.275042 0.275042)
							(end 0.3048 0.2032)
						)
					)
					(width 0)
					(fill yes)
				)
			)
		)
		(pad "2" smd custom
			(at 0 0.4445 90)
			(size 0.1524 0.1524)
			(layers "F.Cu" "F.Mask" "F.Paste")
			(net "GND")
			(options
				(clearance outline)
				(anchor circle)
			)
			(primitives
				(gr_poly
					(pts
						(arc
							(start 0.3048 -0.2032)
							(mid 0.275042 -0.275042)
							(end 0.2032 -0.3048)
						)
						(arc
							(start -0.2032 -0.3048)
							(mid -0.275042 -0.275042)
							(end -0.3048 -0.2032)
						)
						(arc
							(start -0.3048 0.2032)
							(mid -0.275042 0.275042)
							(end -0.2032 0.3048)
						)
						(arc
							(start 0.2032 0.3048)
							(mid 0.275042 0.275042)
							(end 0.3048 0.2032)
						)
					)
					(width 0)
					(fill yes)
				)
			)
		)
	)
	(footprint ""
		(layer "F.Cu")
		(at 19.9136 -149.6822)
		(property "Reference" "R76"
			(at 0 0 0)
			(layer "F.SilkS")
			(hide yes)
			(effects
				(font
					(size 1.27 1.27)
				)
			)
		)
		(property "Value" "10KR2F-2-GP"
			(at 0.064008 -3.993896 0)
			(unlocked yes)
			(layer "F.Fab")
			(hide yes)
			(effects
				(font
					(size 1.016 1.016)
					(thickness 0.1524)
				)
			)
		)
		(property "Device Type" "R402H16"
			(at 0.064008 -5.517896 0)
			(unlocked yes)
			(layer "F.Fab")
			(hide yes)
			(effects
				(font
					(size 1.016 1.016)
					(thickness 0.1524)
				)
			)
		)
		(duplicate_pad_numbers_are_jumpers no)
		(fp_line
			(start -0.508 -0.9398)
			(end -0.508 0.9398)
			(stroke
				(width 0.1524)
				(type default)
			)
			(layer "F.SilkS")
		)
		(fp_line
			(start 0.508 -0.9398)
			(end -0.508 -0.9398)
			(stroke
				(width 0.1524)
				(type default)
			)
			(layer "F.SilkS")
		)
		(fp_rect
			(start -0.508 0.9398)
			(end 0.508 -0.9398)
			(stroke
				(width 0)
				(type default)
			)
			(fill no)
			(layer "F.CrtYd")
		)
		(fp_rect
			(start -0.508 0.9398)
			(end 0.508 -0.9398)
			(stroke
				(width 0)
				(type default)
			)
			(fill no)
			(layer "F.Fab")
		)
		(pad "1" smd custom
			(at 0 -0.4445)
			(size 0.1397 0.1397)
			(layers "F.Cu" "F.Mask" "F.Paste")
			(net "FANIN_9")
			(options
				(clearance outline)
				(anchor circle)
			)
			(primitives
				(gr_poly
					(pts
						(arc
							(start -0.1778 -0.2794)
							(mid -0.249642 -0.249642)
							(end -0.2794 -0.1778)
						)
						(arc
							(start -0.2794 0.1778)
							(mid -0.249642 0.249642)
							(end -0.1778 0.2794)
						)
						(arc
							(start 0.1778 0.2794)
							(mid 0.249642 0.249642)
							(end 0.2794 0.1778)
						)
						(arc
							(start 0.2794 -0.1778)
							(mid 0.249642 -0.249642)
							(end 0.1778 -0.2794)
						)
					)
					(width 0)
					(fill yes)
				)
			)
		)
		(pad "2" smd custom
			(at 0 0.4445)
			(size 0.1397 0.1397)
			(layers "F.Cu" "F.Mask" "F.Paste")
			(net "GND")
			(options
				(clearance outline)
				(anchor circle)
			)
			(primitives
				(gr_poly
					(pts
						(arc
							(start -0.1778 -0.2794)
							(mid -0.249642 -0.249642)
							(end -0.2794 -0.1778)
						)
						(arc
							(start -0.2794 0.1778)
							(mid -0.249642 0.249642)
							(end -0.1778 0.2794)
						)
						(arc
							(start 0.1778 0.2794)
							(mid 0.249642 0.249642)
							(end 0.2794 0.1778)
						)
						(arc
							(start 0.2794 -0.1778)
							(mid 0.249642 -0.249642)
							(end 0.1778 -0.2794)
						)
					)
					(width 0)
					(fill yes)
				)
			)
		)
	)
	(footprint ""
		(layer "F.Cu")
		(at 5.1562 -416.6108 -90)
		(property "Reference" "R28"
			(at 0 0 270)
			(layer "F.SilkS")
			(hide yes)
			(effects
				(font
					(size 1.27 1.27)
				)
			)
		)
		(property "Value" "0R2J-2-GP"
			(at 0.064008 -3.993896 270)
			(unlocked yes)
			(layer "F.Fab")
			(hide yes)
			(effects
				(font
					(size 1.016 1.016)
					(thickness 0.1524)
				)
			)
		)
		(property "Device Type" "R402H16"
			(at 0.064008 -5.517896 270)
			(unlocked yes)
			(layer "F.Fab")
			(hide yes)
			(effects
				(font
					(size 1.016 1.016)
					(thickness 0.1524)
				)
			)
		)
		(duplicate_pad_numbers_are_jumpers no)
		(fp_line
			(start -0.508 -0.9398)
			(end -0.508 0.9398)
			(stroke
				(width 0.1524)
				(type default)
			)
			(layer "F.SilkS")
		)
		(fp_line
			(start 0.508 -0.9398)
			(end -0.508 -0.9398)
			(stroke
				(width 0.1524)
				(type default)
			)
			(layer "F.SilkS")
		)
		(fp_rect
			(start -0.508 0.9398)
			(end 0.508 -0.9398)
			(stroke
				(width 0)
				(type default)
			)
			(fill no)
			(layer "F.CrtYd")
		)
		(fp_rect
			(start -0.508 0.9398)
			(end 0.508 -0.9398)
			(stroke
				(width 0)
				(type default)
			)
			(fill no)
			(layer "F.Fab")
		)
		(pad "1" smd custom
			(at 0 -0.4445 270)
			(size 0.1397 0.1397)
			(layers "F.Cu" "F.Mask" "F.Paste")
			(net "LED_DR_LED1_K")
			(options
				(clearance outline)
				(anchor circle)
			)
			(primitives
				(gr_poly
					(pts
						(arc
							(start -0.1778 -0.2794)
							(mid -0.249642 -0.249642)
							(end -0.2794 -0.1778)
						)
						(arc
							(start -0.2794 0.1778)
							(mid -0.249642 0.249642)
							(end -0.1778 0.2794)
						)
						(arc
							(start 0.1778 0.2794)
							(mid 0.249642 0.249642)
							(end 0.2794 0.1778)
						)
						(arc
							(start 0.2794 -0.1778)
							(mid 0.249642 -0.249642)
							(end 0.1778 -0.2794)
						)
					)
					(width 0)
					(fill yes)
				)
			)
		)
		(pad "2" smd custom
			(at 0 0.4445 270)
			(size 0.1397 0.1397)
			(layers "F.Cu" "F.Mask" "F.Paste")
			(net "GND")
			(options
				(clearance outline)
				(anchor circle)
			)
			(primitives
				(gr_poly
					(pts
						(arc
							(start -0.1778 -0.2794)
							(mid -0.249642 -0.249642)
							(end -0.2794 -0.1778)
						)
						(arc
							(start -0.2794 0.1778)
							(mid -0.249642 0.249642)
							(end -0.1778 0.2794)
						)
						(arc
							(start 0.1778 0.2794)
							(mid 0.249642 0.249642)
							(end 0.2794 0.1778)
						)
						(arc
							(start 0.2794 -0.1778)
							(mid 0.249642 -0.249642)
							(end 0.1778 -0.2794)
						)
					)
					(width 0)
					(fill yes)
				)
			)
		)
	)
	(footprint ""
		(layer "F.Cu")
		(at 6.999986 -159.999934)
		(property "Reference" "H7"
			(at 0 0 0)
			(layer "F.SilkS")
			(hide yes)
			(effects
				(font
					(size 1.27 1.27)
				)
			)
		)
		(property "Value" "HOLE315R138"
			(at 0 -7.0612 0)
			(unlocked yes)
			(layer "F.Fab")
			(hide yes)
			(effects
				(font
					(size 1.016 1.016)
					(thickness 0.1524)
				)
			)
		)
		(property "Device Type" "HOLE315R138"
			(at 0 -8.5852 0)
			(unlocked yes)
			(layer "F.Fab")
			(hide yes)
			(effects
				(font
					(size 1.016 1.016)
					(thickness 0.1524)
				)
			)
		)
		(duplicate_pad_numbers_are_jumpers no)
		(fp_poly
			(pts
				(xy 0 4.3053) (xy -0.13462 4.30276) (xy -0.27051 4.29641) (xy -0.40513 4.28625) (xy -0.53975 4.27101)
				(xy -0.6731 4.25196) (xy -0.80645 4.2291) (xy -0.9398 4.20116) (xy -1.07061 4.17068) (xy -1.20142 4.13385)
				(xy -1.33096 4.09448) (xy -1.45796 4.0513) (xy -1.58496 4.00304) (xy -1.70942 3.95097) (xy -1.83261 3.89509)
				(xy -1.95453 3.83667) (xy -2.07391 3.77317) (xy -2.19202 3.70586) (xy -2.30632 3.63474) (xy -2.41935 3.56108)
				(xy -2.53111 3.48361) (xy -2.63906 3.40233) (xy -2.74447 3.31724) (xy -2.84734 3.22961) (xy -2.94767 3.13817)
				(xy -3.04419 3.04419) (xy -3.13817 2.94767) (xy -3.22961 2.84734) (xy -3.31724 2.74447) (xy -3.40233 2.63906)
				(xy -3.48361 2.53111) (xy -3.56108 2.41935) (xy -3.63474 2.30632) (xy -3.70586 2.19202) (xy -3.77317 2.07391)
				(xy -3.83667 1.95453) (xy -3.89509 1.83261) (xy -3.95097 1.70942) (xy -4.00304 1.58496) (xy -4.0513 1.45796)
				(xy -4.09448 1.33096) (xy -4.13385 1.20142) (xy -4.17068 1.07061) (xy -4.20116 0.9398) (xy -4.2291 0.80645)
				(xy -4.25196 0.6731) (xy -4.27101 0.53975) (xy -4.28625 0.40513) (xy -4.29641 0.27051) (xy -4.30276 0.13462)
				(xy -4.3053 0) (xy -4.30276 -0.13462) (xy -4.29641 -0.27051) (xy -4.28625 -0.40513) (xy -4.27101 -0.53975)
				(xy -4.25196 -0.6731) (xy -4.2291 -0.80645) (xy -4.20116 -0.9398) (xy -4.17068 -1.07061) (xy -4.13385 -1.20142)
				(xy -4.09448 -1.33096) (xy -4.0513 -1.45796) (xy -4.00304 -1.58496) (xy -3.95097 -1.70942) (xy -3.89509 -1.83261)
				(xy -3.83667 -1.95453) (xy -3.77317 -2.07391) (xy -3.70586 -2.19202) (xy -3.63474 -2.30632) (xy -3.56108 -2.41935)
				(xy -3.48361 -2.53111) (xy -3.40233 -2.63906) (xy -3.31724 -2.74447) (xy -3.22961 -2.84734) (xy -3.13817 -2.94767)
				(xy -3.04419 -3.04419) (xy -2.94767 -3.13817) (xy -2.84734 -3.22961) (xy -2.74447 -3.31724) (xy -2.63906 -3.40233)
				(xy -2.53111 -3.48361) (xy -2.41935 -3.56108) (xy -2.30632 -3.63474) (xy -2.19202 -3.70586) (xy -2.07391 -3.77317)
				(xy -1.95453 -3.83667) (xy -1.83261 -3.89509) (xy -1.70942 -3.95097) (xy -1.58496 -4.00304) (xy -1.45796 -4.0513)
				(xy -1.33096 -4.09448) (xy -1.20142 -4.13385) (xy -1.07061 -4.17068) (xy -0.9398 -4.20116) (xy -0.80645 -4.2291)
				(xy -0.6731 -4.25196) (xy -0.53975 -4.27101) (xy -0.40513 -4.28625) (xy -0.27051 -4.29641) (xy -0.13462 -4.30276)
				(xy 0 -4.3053) (xy 0.13462 -4.30276) (xy 0.27051 -4.29641) (xy 0.40513 -4.28625) (xy 0.53975 -4.27101)
				(xy 0.6731 -4.25196) (xy 0.80645 -4.2291) (xy 0.9398 -4.20116) (xy 1.07061 -4.17068) (xy 1.20142 -4.13385)
				(xy 1.33096 -4.09448) (xy 1.45796 -4.0513) (xy 1.58496 -4.00304) (xy 1.70942 -3.95097) (xy 1.83261 -3.89509)
				(xy 1.95453 -3.83667) (xy 2.07391 -3.77317) (xy 2.19202 -3.70586) (xy 2.30632 -3.63474) (xy 2.41935 -3.56108)
				(xy 2.53111 -3.48361) (xy 2.63906 -3.40233) (xy 2.74447 -3.31724) (xy 2.84734 -3.22961) (xy 2.94767 -3.13817)
				(xy 3.04419 -3.04419) (xy 3.13817 -2.94767) (xy 3.22961 -2.84734) (xy 3.31724 -2.74447) (xy 3.40233 -2.63906)
				(xy 3.48361 -2.53111) (xy 3.56108 -2.41935) (xy 3.63474 -2.30632) (xy 3.70586 -2.19202) (xy 3.77317 -2.07391)
				(xy 3.83667 -1.95453) (xy 3.89509 -1.83261) (xy 3.95097 -1.70942) (xy 4.00304 -1.58496) (xy 4.0513 -1.45796)
				(xy 4.09448 -1.33096) (xy 4.13385 -1.20142) (xy 4.17068 -1.07061) (xy 4.20116 -0.9398) (xy 4.2291 -0.80645)
				(xy 4.25196 -0.6731) (xy 4.27101 -0.53975) (xy 4.28625 -0.40513) (xy 4.29641 -0.27051) (xy 4.30276 -0.13462)
				(xy 4.3053 0) (xy 4.30276 0.13462) (xy 4.29641 0.27051) (xy 4.28625 0.40513) (xy 4.27101 0.53975)
				(xy 4.25196 0.6731) (xy 4.2291 0.80645) (xy 4.20116 0.9398) (xy 4.17068 1.07061) (xy 4.13385 1.20142)
				(xy 4.09448 1.33096) (xy 4.0513 1.45796) (xy 4.00304 1.58496) (xy 3.95097 1.70942) (xy 3.89509 1.83261)
				(xy 3.83667 1.95453) (xy 3.77317 2.07391) (xy 3.70586 2.19202) (xy 3.63474 2.30632) (xy 3.56108 2.41935)
				(xy 3.48361 2.53111) (xy 3.40233 2.63906) (xy 3.31724 2.74447) (xy 3.22961 2.84734) (xy 3.13817 2.94767)
				(xy 3.04419 3.04419) (xy 2.94767 3.13817) (xy 2.84734 3.22961) (xy 2.74447 3.31724) (xy 2.63906 3.40233)
				(xy 2.53111 3.48361) (xy 2.41935 3.56108) (xy 2.30632 3.63474) (xy 2.19202 3.70586) (xy 2.07391 3.77317)
				(xy 1.95453 3.83667) (xy 1.83261 3.89509) (xy 1.70942 3.95097) (xy 1.58496 4.00304) (xy 1.45796 4.0513)
				(xy 1.33096 4.09448) (xy 1.20142 4.13385) (xy 1.07061 4.17068) (xy 0.9398 4.20116) (xy 0.80645 4.2291)
				(xy 0.6731 4.25196) (xy 0.53975 4.27101) (xy 0.40513 4.28625) (xy 0.27051 4.29641) (xy 0.13462 4.30276)
			)
			(stroke
				(width 0)
				(type default)
			)
			(fill no)
			(layer "F.CrtYd")
		)
		(fp_poly
			(pts
				(xy 0 4.3053) (xy -0.13462 4.30276) (xy -0.27051 4.29641) (xy -0.40513 4.28625) (xy -0.53975 4.27101)
				(xy -0.6731 4.25196) (xy -0.80645 4.2291) (xy -0.9398 4.20116) (xy -1.07061 4.17068) (xy -1.20142 4.13385)
				(xy -1.33096 4.09448) (xy -1.45796 4.0513) (xy -1.58496 4.00304) (xy -1.70942 3.95097) (xy -1.83261 3.89509)
				(xy -1.95453 3.83667) (xy -2.07391 3.77317) (xy -2.19202 3.70586) (xy -2.30632 3.63474) (xy -2.41935 3.56108)
				(xy -2.53111 3.48361) (xy -2.63906 3.40233) (xy -2.74447 3.31724) (xy -2.84734 3.22961) (xy -2.94767 3.13817)
				(xy -3.04419 3.04419) (xy -3.13817 2.94767) (xy -3.22961 2.84734) (xy -3.31724 2.74447) (xy -3.40233 2.63906)
				(xy -3.48361 2.53111) (xy -3.56108 2.41935) (xy -3.63474 2.30632) (xy -3.70586 2.19202) (xy -3.77317 2.07391)
				(xy -3.83667 1.95453) (xy -3.89509 1.83261) (xy -3.95097 1.70942) (xy -4.00304 1.58496) (xy -4.0513 1.45796)
				(xy -4.09448 1.33096) (xy -4.13385 1.20142) (xy -4.17068 1.07061) (xy -4.20116 0.9398) (xy -4.2291 0.80645)
				(xy -4.25196 0.6731) (xy -4.27101 0.53975) (xy -4.28625 0.40513) (xy -4.29641 0.27051) (xy -4.30276 0.13462)
				(xy -4.3053 0) (xy -4.30276 -0.13462) (xy -4.29641 -0.27051) (xy -4.28625 -0.40513) (xy -4.27101 -0.53975)
				(xy -4.25196 -0.6731) (xy -4.2291 -0.80645) (xy -4.20116 -0.9398) (xy -4.17068 -1.07061) (xy -4.13385 -1.20142)
				(xy -4.09448 -1.33096) (xy -4.0513 -1.45796) (xy -4.00304 -1.58496) (xy -3.95097 -1.70942) (xy -3.89509 -1.83261)
				(xy -3.83667 -1.95453) (xy -3.77317 -2.07391) (xy -3.70586 -2.19202) (xy -3.63474 -2.30632) (xy -3.56108 -2.41935)
				(xy -3.48361 -2.53111) (xy -3.40233 -2.63906) (xy -3.31724 -2.74447) (xy -3.22961 -2.84734) (xy -3.13817 -2.94767)
				(xy -3.04419 -3.04419) (xy -2.94767 -3.13817) (xy -2.84734 -3.22961) (xy -2.74447 -3.31724) (xy -2.63906 -3.40233)
				(xy -2.53111 -3.48361) (xy -2.41935 -3.56108) (xy -2.30632 -3.63474) (xy -2.19202 -3.70586) (xy -2.07391 -3.77317)
				(xy -1.95453 -3.83667) (xy -1.83261 -3.89509) (xy -1.70942 -3.95097) (xy -1.58496 -4.00304) (xy -1.45796 -4.0513)
				(xy -1.33096 -4.09448) (xy -1.20142 -4.13385) (xy -1.07061 -4.17068) (xy -0.9398 -4.20116) (xy -0.80645 -4.2291)
				(xy -0.6731 -4.25196) (xy -0.53975 -4.27101) (xy -0.40513 -4.28625) (xy -0.27051 -4.29641) (xy -0.13462 -4.30276)
				(xy 0 -4.3053) (xy 0.13462 -4.30276) (xy 0.27051 -4.29641) (xy 0.40513 -4.28625) (xy 0.53975 -4.27101)
				(xy 0.6731 -4.25196) (xy 0.80645 -4.2291) (xy 0.9398 -4.20116) (xy 1.07061 -4.17068) (xy 1.20142 -4.13385)
				(xy 1.33096 -4.09448) (xy 1.45796 -4.0513) (xy 1.58496 -4.00304) (xy 1.70942 -3.95097) (xy 1.83261 -3.89509)
				(xy 1.95453 -3.83667) (xy 2.07391 -3.77317) (xy 2.19202 -3.70586) (xy 2.30632 -3.63474) (xy 2.41935 -3.56108)
				(xy 2.53111 -3.48361) (xy 2.63906 -3.40233) (xy 2.74447 -3.31724) (xy 2.84734 -3.22961) (xy 2.94767 -3.13817)
				(xy 3.04419 -3.04419) (xy 3.13817 -2.94767) (xy 3.22961 -2.84734) (xy 3.31724 -2.74447) (xy 3.40233 -2.63906)
				(xy 3.48361 -2.53111) (xy 3.56108 -2.41935) (xy 3.63474 -2.30632) (xy 3.70586 -2.19202) (xy 3.77317 -2.07391)
				(xy 3.83667 -1.95453) (xy 3.89509 -1.83261) (xy 3.95097 -1.70942) (xy 4.00304 -1.58496) (xy 4.0513 -1.45796)
				(xy 4.09448 -1.33096) (xy 4.13385 -1.20142) (xy 4.17068 -1.07061) (xy 4.20116 -0.9398) (xy 4.2291 -0.80645)
				(xy 4.25196 -0.6731) (xy 4.27101 -0.53975) (xy 4.28625 -0.40513) (xy 4.29641 -0.27051) (xy 4.30276 -0.13462)
				(xy 4.3053 0) (xy 4.30276 0.13462) (xy 4.29641 0.27051) (xy 4.28625 0.40513) (xy 4.27101 0.53975)
				(xy 4.25196 0.6731) (xy 4.2291 0.80645) (xy 4.20116 0.9398) (xy 4.17068 1.07061) (xy 4.13385 1.20142)
				(xy 4.09448 1.33096) (xy 4.0513 1.45796) (xy 4.00304 1.58496) (xy 3.95097 1.70942) (xy 3.89509 1.83261)
				(xy 3.83667 1.95453) (xy 3.77317 2.07391) (xy 3.70586 2.19202) (xy 3.63474 2.30632) (xy 3.56108 2.41935)
				(xy 3.48361 2.53111) (xy 3.40233 2.63906) (xy 3.31724 2.74447) (xy 3.22961 2.84734) (xy 3.13817 2.94767)
				(xy 3.04419 3.04419) (xy 2.94767 3.13817) (xy 2.84734 3.22961) (xy 2.74447 3.31724) (xy 2.63906 3.40233)
				(xy 2.53111 3.48361) (xy 2.41935 3.56108) (xy 2.30632 3.63474) (xy 2.19202 3.70586) (xy 2.07391 3.77317)
				(xy 1.95453 3.83667) (xy 1.83261 3.89509) (xy 1.70942 3.95097) (xy 1.58496 4.00304) (xy 1.45796 4.0513)
				(xy 1.33096 4.09448) (xy 1.20142 4.13385) (xy 1.07061 4.17068) (xy 0.9398 4.20116) (xy 0.80645 4.2291)
				(xy 0.6731 4.25196) (xy 0.53975 4.27101) (xy 0.40513 4.28625) (xy 0.27051 4.29641) (xy 0.13462 4.30276)
			)
			(stroke
				(width 0)
				(type default)
			)
			(fill no)
			(layer "F.Fab")
		)
		(pad "1" thru_hole circle
			(at 0 0)
			(size 8.001 8.001)
			(drill 3.5052)
			(layers "*.Cu" "*.Mask")
			(remove_unused_layers no)
			(net "GND")
			(clearance -1.7399)
			(thermal_gap 0.3048)
			(padstack
				(mode front_inner_back)
				(layer "Inner"
					(shape circle)
					(size 3.9116 3.9116)
					(clearance 0.3048)
				)
				(layer "B.Cu"
					(shape circle)
					(size 8.001 8.001)
					(clearance -1.7399)
				)
			)
		)
	)
	(footprint ""
		(layer "F.Cu")
		(at 42.418 -371.221)
		(property "Reference" "PR43"
			(at 0 0 0)
			(layer "F.SilkS")
			(hide yes)
			(effects
				(font
					(size 1.27 1.27)
				)
			)
		)
		(property "Value" "1K5R5J-GP"
			(at 0 -8.9535 0)
			(unlocked yes)
			(layer "F.Fab")
			(hide yes)
			(effects
				(font
					(size 1.27 1.016)
					(thickness 0.1524)
				)
			)
		)
		(property "Device Type" "R805H24"
			(at 0 -10.6299 0)
			(unlocked yes)
			(layer "F.Fab")
			(hide yes)
			(effects
				(font
					(size 1.27 1.016)
					(thickness 0.1524)
				)
			)
		)
		(duplicate_pad_numbers_are_jumpers no)
		(fp_line
			(start -0.889 -1.7018)
			(end -0.889 0.2794)
			(stroke
				(width 0.1524)
				(type default)
			)
			(layer "F.SilkS")
		)
		(fp_line
			(start -0.889 0.0762)
			(end -0.889 1.7018)
			(stroke
				(width 0.1524)
				(type default)
			)
			(layer "F.SilkS")
		)
		(fp_line
			(start -0.889 1.7018)
			(end 0.889 1.7018)
			(stroke
				(width 0.1524)
				(type default)
			)
			(layer "F.SilkS")
		)
		(fp_line
			(start 0.889 -1.7018)
			(end -0.889 -1.7018)
			(stroke
				(width 0.1524)
				(type default)
			)
			(layer "F.SilkS")
		)
		(fp_line
			(start 0.889 -1.7018)
			(end 0.889 -0.381)
			(stroke
				(width 0.1524)
				(type default)
			)
			(layer "F.SilkS")
		)
		(fp_line
			(start 0.889 1.7018)
			(end 0.889 -0.508)
			(stroke
				(width 0.1524)
				(type default)
			)
			(layer "F.SilkS")
		)
		(fp_poly
			(pts
				(xy 0.9652 -1.778) (xy 0.9652 1.778) (xy -0.9652 1.778) (xy -0.9652 -1.778)
			)
			(stroke
				(width 0)
				(type default)
			)
			(fill no)
			(layer "F.CrtYd")
		)
		(fp_rect
			(start -0.9652 1.778)
			(end 0.9652 -1.778)
			(stroke
				(width 0)
				(type default)
			)
			(fill no)
			(layer "F.Fab")
		)
		(pad "1" smd rect
			(at 0 -0.9652)
			(size 1.397 1.143)
			(layers "F.Cu" "F.Mask" "F.Paste")
			(net "P12V_AUX")
		)
		(pad "2" smd rect
			(at 0 0.9652)
			(size 1.397 1.143)
			(layers "F.Cu" "F.Mask" "F.Paste")
			(net "ADM1276_EN_NET")
		)
	)
	(footprint ""
		(layer "F.Cu")
		(at 31.7246 -149.073616)
		(property "Reference" "R128"
			(at 0 0 0)
			(layer "F.SilkS")
			(hide yes)
			(effects
				(font
					(size 1.27 1.27)
				)
			)
		)
		(property "Value" "10KR2F-2-GP"
			(at 0.064008 -3.993896 0)
			(unlocked yes)
			(layer "F.Fab")
			(hide yes)
			(effects
				(font
					(size 1.016 1.016)
					(thickness 0.1524)
				)
			)
		)
		(property "Device Type" "R402H16"
			(at 0.064008 -5.517896 0)
			(unlocked yes)
			(layer "F.Fab")
			(hide yes)
			(effects
				(font
					(size 1.016 1.016)
					(thickness 0.1524)
				)
			)
		)
		(duplicate_pad_numbers_are_jumpers no)
		(fp_line
			(start -0.508 -0.9398)
			(end -0.508 0.9398)
			(stroke
				(width 0.1524)
				(type default)
			)
			(layer "F.SilkS")
		)
		(fp_line
			(start 0.508 -0.9398)
			(end -0.508 -0.9398)
			(stroke
				(width 0.1524)
				(type default)
			)
			(layer "F.SilkS")
		)
		(fp_rect
			(start -0.508 0.9398)
			(end 0.508 -0.9398)
			(stroke
				(width 0)
				(type default)
			)
			(fill no)
			(layer "F.CrtYd")
		)
		(fp_rect
			(start -0.508 0.9398)
			(end 0.508 -0.9398)
			(stroke
				(width 0)
				(type default)
			)
			(fill no)
			(layer "F.Fab")
		)
		(pad "1" smd custom
			(at 0 -0.4445)
			(size 0.1397 0.1397)
			(layers "F.Cu" "F.Mask" "F.Paste")
			(net "NCT7904_VSEN7")
			(options
				(clearance outline)
				(anchor circle)
			)
			(primitives
				(gr_poly
					(pts
						(arc
							(start -0.1778 -0.2794)
							(mid -0.249642 -0.249642)
							(end -0.2794 -0.1778)
						)
						(arc
							(start -0.2794 0.1778)
							(mid -0.249642 0.249642)
							(end -0.1778 0.2794)
						)
						(arc
							(start 0.1778 0.2794)
							(mid 0.249642 0.249642)
							(end 0.2794 0.1778)
						)
						(arc
							(start 0.2794 -0.1778)
							(mid 0.249642 -0.249642)
							(end 0.1778 -0.2794)
						)
					)
					(width 0)
					(fill yes)
				)
			)
		)
		(pad "2" smd custom
			(at 0 0.4445)
			(size 0.1397 0.1397)
			(layers "F.Cu" "F.Mask" "F.Paste")
			(net "GND")
			(options
				(clearance outline)
				(anchor circle)
			)
			(primitives
				(gr_poly
					(pts
						(arc
							(start -0.1778 -0.2794)
							(mid -0.249642 -0.249642)
							(end -0.2794 -0.1778)
						)
						(arc
							(start -0.2794 0.1778)
							(mid -0.249642 0.249642)
							(end -0.1778 0.2794)
						)
						(arc
							(start 0.1778 0.2794)
							(mid 0.249642 0.249642)
							(end 0.2794 0.1778)
						)
						(arc
							(start 0.2794 -0.1778)
							(mid 0.249642 -0.249642)
							(end 0.1778 -0.2794)
						)
					)
					(width 0)
					(fill yes)
				)
			)
		)
	)
	(footprint ""
		(layer "F.Cu")
		(at 41.8084 -155.0162 180)
		(property "Reference" "C4"
			(at 0 0 180)
			(layer "F.SilkS")
			(hide yes)
			(effects
				(font
					(size 1.27 1.27)
				)
			)
		)
		(property "Value" "SCD1U16V2KX-3GP"
			(at 1.1811 -2.7051 180)
			(unlocked yes)
			(layer "F.Fab")
			(hide yes)
			(effects
				(font
					(size 1.016 1.016)
					(thickness 0.1524)
				)
			)
		)
		(property "Device Type" "C402H22"
			(at 1.1811 -4.2291 180)
			(unlocked yes)
			(layer "F.Fab")
			(hide yes)
			(effects
				(font
					(size 1.016 1.016)
					(thickness 0.1524)
				)
			)
		)
		(duplicate_pad_numbers_are_jumpers no)
		(fp_rect
			(start -0.4318 0.9525)
			(end 0.4318 -0.9525)
			(stroke
				(width 0)
				(type default)
			)
			(fill no)
			(layer "F.CrtYd")
		)
		(fp_rect
			(start -0.4318 0.9525)
			(end 0.4318 -0.9525)
			(stroke
				(width 0)
				(type default)
			)
			(fill no)
			(layer "F.Fab")
		)
		(pad "1" smd custom
			(at 0 -0.4445 180)
			(size 0.1524 0.1524)
			(layers "F.Cu" "F.Mask" "F.Paste")
			(net "NCT7904_3VSB")
			(options
				(clearance outline)
				(anchor circle)
			)
			(primitives
				(gr_poly
					(pts
						(arc
							(start 0.3048 -0.2032)
							(mid 0.275042 -0.275042)
							(end 0.2032 -0.3048)
						)
						(arc
							(start -0.2032 -0.3048)
							(mid -0.275042 -0.275042)
							(end -0.3048 -0.2032)
						)
						(arc
							(start -0.3048 0.2032)
							(mid -0.275042 0.275042)
							(end -0.2032 0.3048)
						)
						(arc
							(start 0.2032 0.3048)
							(mid 0.275042 0.275042)
							(end 0.3048 0.2032)
						)
					)
					(width 0)
					(fill yes)
				)
			)
		)
		(pad "2" smd custom
			(at 0 0.4445 180)
			(size 0.1524 0.1524)
			(layers "F.Cu" "F.Mask" "F.Paste")
			(net "GND")
			(options
				(clearance outline)
				(anchor circle)
			)
			(primitives
				(gr_poly
					(pts
						(arc
							(start 0.3048 -0.2032)
							(mid 0.275042 -0.275042)
							(end 0.2032 -0.3048)
						)
						(arc
							(start -0.2032 -0.3048)
							(mid -0.275042 -0.275042)
							(end -0.3048 -0.2032)
						)
						(arc
							(start -0.3048 0.2032)
							(mid -0.275042 0.275042)
							(end -0.2032 0.3048)
						)
						(arc
							(start 0.2032 0.3048)
							(mid 0.275042 0.275042)
							(end 0.3048 0.2032)
						)
					)
					(width 0)
					(fill yes)
				)
			)
		)
	)
	(footprint ""
		(layer "F.Cu")
		(at 29.718 -368.808 90)
		(property "Reference" "PU1"
			(at 0 0 90)
			(layer "F.SilkS")
			(hide yes)
			(effects
				(font
					(size 1.27 1.27)
				)
			)
		)
		(property "Value" "ADM1276-3ACPZ-RL-GP"
			(at -5.3975 -5.0292 90)
			(unlocked yes)
			(layer "F.Fab")
			(hide yes)
			(effects
				(font
					(size 1.016 1.016)
					(thickness 0.1524)
				)
			)
		)
		(property "Device Type" "QFN20-G3D25H32"
			(at -5.3975 -6.5532 90)
			(unlocked yes)
			(layer "F.Fab")
			(hide yes)
			(effects
				(font
					(size 1.016 1.016)
					(thickness 0.1524)
				)
			)
		)
		(duplicate_pad_numbers_are_jumpers no)
		(fp_line
			(start -3.5179 -3.5179)
			(end -2.2479 -3.5179)
			(stroke
				(width 0.1524)
				(type default)
			)
			(layer "F.SilkS")
		)
		(fp_line
			(start -1.3208 -3.302)
			(end -1.3208 -3.81)
			(stroke
				(width 0.1524)
				(type default)
			)
			(layer "F.SilkS")
		)
		(fp_line
			(start -3.5179 -2.2479)
			(end -3.5179 -3.5179)
			(stroke
				(width 0.1524)
				(type default)
			)
			(layer "F.SilkS")
		)
		(fp_line
			(start 3.302 -1.2954)
			(end 4.064 -1.2954)
			(stroke
				(width 0.1524)
				(type default)
			)
			(layer "F.SilkS")
		)
		(fp_line
			(start -4.064 1.2954)
			(end -3.302 1.2954)
			(stroke
				(width 0.1524)
				(type default)
			)
			(layer "F.SilkS")
		)
		(fp_line
			(start -3.5179 2.2479)
			(end -3.5179 3.5179)
			(stroke
				(width 0.1524)
				(type default)
			)
			(layer "F.SilkS")
		)
		(fp_line
			(start 3.5179 3.5179)
			(end 3.5179 2.2479)
			(stroke
				(width 0.1524)
				(type default)
			)
			(layer "F.SilkS")
		)
		(fp_line
			(start 2.2479 3.5179)
			(end 3.5179 3.5179)
			(stroke
				(width 0.1524)
				(type default)
			)
			(layer "F.SilkS")
		)
		(fp_line
			(start -3.5179 3.5179)
			(end -2.2479 3.5179)
			(stroke
				(width 0.1524)
				(type default)
			)
			(layer "F.SilkS")
		)
		(fp_line
			(start 1.2954 3.81)
			(end 1.2954 3.302)
			(stroke
				(width 0.1524)
				(type default)
			)
			(layer "F.SilkS")
		)
		(fp_poly
			(pts
				(xy 2.2479 -3.5179) (xy 3.5179 -2.2479) (xy 3.5179 -3.5179)
			)
			(stroke
				(width 0)
				(type default)
			)
			(fill yes)
			(layer "F.SilkS")
		)
		(fp_rect
			(start -2.5019 2.5019)
			(end 2.5019 -2.5019)
			(stroke
				(width 0)
				(type default)
			)
			(fill no)
			(layer "F.CrtYd")
		)
		(fp_poly
			(pts
				(xy -3.5179 3.5179) (xy -3.5179 -2.49682) (xy -2.5019 -2.49682) (xy -2.5019 2.5019) (xy 2.5019 2.5019)
				(xy 2.5019 -2.5019) (xy -3.5179 -2.5019) (xy -3.5179 -3.5179) (xy 3.5179 -3.5179) (xy 3.5179 3.5179)
			)
			(stroke
				(width 0)
				(type default)
			)
			(fill no)
			(layer "F.CrtYd")
		)
		(fp_rect
			(start -3.5179 3.5179)
			(end 3.5179 -3.5179)
			(stroke
				(width 0)
				(type default)
			)
			(fill no)
			(layer "F.Fab")
		)
		(pad "1" smd rect
			(at 1.299972 -2.4384 90)
			(size 0.4064 1.143)
			(layers "F.Cu" "F.Mask" "F.Paste")
			(net "ADM1276_OV")
		)
		(pad "2" smd rect
			(at 0.649986 -2.4384 90)
			(size 0.4064 1.143)
			(layers "F.Cu" "F.Mask" "F.Paste")
			(net "ADM1276_VCAP")
		)
		(pad "3" smd rect
			(at 0 -2.4384 90)
			(size 0.4064 1.143)
			(layers "F.Cu" "F.Mask" "F.Paste")
			(net "ADM1276_ISET")
		)
		(pad "4" smd rect
			(at -0.649986 -2.4384 90)
			(size 0.4064 1.143)
			(layers "F.Cu" "F.Mask" "F.Paste")
			(net "ADM1276_SS")
		)
		(pad "5" smd rect
			(at -1.299972 -2.4384 90)
			(size 0.4064 1.143)
			(layers "F.Cu" "F.Mask" "F.Paste")
			(net "ADM1276_TIMER")
		)
		(pad "6" smd rect
			(at -2.4384 -1.299972 90)
			(size 1.143 0.4064)
			(layers "F.Cu" "F.Mask" "F.Paste")
			(net "ADM1276_LATCH#")
		)
		(pad "7" smd rect
			(at -2.4384 -0.649986 90)
			(size 1.143 0.4064)
			(layers "F.Cu" "F.Mask" "F.Paste")
			(net "ADM1276_ADR")
		)
		(pad "8" smd rect
			(at -2.4384 0 90)
			(size 1.143 0.4064)
			(layers "F.Cu" "F.Mask" "F.Paste")
			(net "ADM1276_EN")
		)
		(pad "9" smd rect
			(at -2.4384 0.649986 90)
			(size 1.143 0.4064)
			(layers "F.Cu" "F.Mask" "F.Paste")
			(net "ADM1276_GPIO2")
		)
		(pad "10" smd rect
			(at -2.4384 1.299972 90)
			(size 1.143 0.4064)
			(layers "F.Cu" "F.Mask" "F.Paste")
			(net "I2C_C_SDA_ADM1276")
		)
		(pad "11" smd rect
			(at -1.299972 2.4384 90)
			(size 0.4064 1.143)
			(layers "F.Cu" "F.Mask" "F.Paste")
			(net "I2C_C_SCL_ADM1276")
		)
		(pad "12" smd rect
			(at -0.649986 2.4384 90)
			(size 0.4064 1.143)
			(layers "F.Cu" "F.Mask" "F.Paste")
			(net "ADM1276_PWRGD")
		)
		(pad "13" smd rect
			(at 0 2.4384 90)
			(size 0.4064 1.143)
			(layers "F.Cu" "F.Mask" "F.Paste")
			(net "ADM1276_FLB")
		)
		(pad "14" smd rect
			(at 0.649986 2.4384 90)
			(size 0.4064 1.143)
			(layers "F.Cu" "F.Mask" "F.Paste")
			(net "ADM1276_VOUT")
		)
		(pad "15" smd rect
			(at 1.299972 2.4384 90)
			(size 0.4064 1.143)
			(layers "F.Cu" "F.Mask" "F.Paste")
			(net "GND")
		)
		(pad "16" smd rect
			(at 2.4384 1.299972 90)
			(size 1.143 0.4064)
			(layers "F.Cu" "F.Mask" "F.Paste")
			(net "ADM1276_GATE_DRV")
		)
		(pad "17" smd rect
			(at 2.4384 0.649986 90)
			(size 1.143 0.4064)
			(layers "F.Cu" "F.Mask" "F.Paste")
			(net "ADM1276_SENSE-")
		)
		(pad "18" smd rect
			(at 2.4384 0 90)
			(size 1.143 0.4064)
			(layers "F.Cu" "F.Mask" "F.Paste")
			(net "ADM1276_SENSE+")
		)
		(pad "19" smd rect
			(at 2.4384 -0.649986 90)
			(size 1.143 0.4064)
			(layers "F.Cu" "F.Mask" "F.Paste")
			(net "ADM1276_VCC")
		)
		(pad "20" smd rect
			(at 2.4384 -1.299972 90)
			(size 1.143 0.4064)
			(layers "F.Cu" "F.Mask" "F.Paste")
			(net "ADM1276_UV")
		)
		(pad "21" smd rect
			(at 0 0 90)
			(size 3.2512 3.2512)
			(layers "F.Cu" "F.Mask" "F.Paste")
			(net "GND")
		)
	)
	(footprint ""
		(layer "F.Cu")
		(at 10.033 -174.752 90)
		(property "Reference" "U10"
			(at 0 0 90)
			(layer "F.SilkS")
			(hide yes)
			(effects
				(font
					(size 1.27 1.27)
				)
			)
		)
		(property "Value" "74LVC1G32GW-1GP"
			(at -2.3368 -8.6868 90)
			(unlocked yes)
			(layer "F.Fab")
			(hide yes)
			(effects
				(font
					(size 1.016 1.016)
					(thickness 0.1524)
				)
			)
		)
		(property "Device Type" "SC70-5H44"
			(at -2.3114 -10.414 90)
			(unlocked yes)
			(layer "F.Fab")
			(hide yes)
			(effects
				(font
					(size 1.016 1.016)
					(thickness 0.1524)
				)
			)
		)
		(duplicate_pad_numbers_are_jumpers no)
		(fp_line
			(start 1.3843 -1.8034)
			(end 1.3843 -1.1176)
			(stroke
				(width 0.3302)
				(type default)
			)
			(layer "F.SilkS")
		)
		(fp_line
			(start 0.6604 -1.8034)
			(end 1.3843 -1.8034)
			(stroke
				(width 0.3302)
				(type default)
			)
			(layer "F.SilkS")
		)
		(fp_line
			(start 1.27 -1.7018)
			(end 1.27 1.7018)
			(stroke
				(width 0.1524)
				(type default)
			)
			(layer "F.SilkS")
		)
		(fp_line
			(start -1.27 -1.7018)
			(end 1.27 -1.7018)
			(stroke
				(width 0.1524)
				(type default)
			)
			(layer "F.SilkS")
		)
		(fp_line
			(start 1.27 1.7018)
			(end -1.27 1.7018)
			(stroke
				(width 0.1524)
				(type default)
			)
			(layer "F.SilkS")
		)
		(fp_line
			(start -1.27 1.7018)
			(end -1.27 -1.7018)
			(stroke
				(width 0.1524)
				(type default)
			)
			(layer "F.SilkS")
		)
		(fp_rect
			(start -1.524 1.9558)
			(end 1.524 -1.9558)
			(stroke
				(width 0)
				(type default)
			)
			(fill no)
			(layer "F.CrtYd")
		)
		(fp_poly
			(pts
				(xy -1.524 -1.9558) (xy 1.524 -1.9558) (xy 1.524 1.9558) (xy -1.524 1.9558)
			)
			(stroke
				(width 0)
				(type default)
			)
			(fill no)
			(layer "F.Fab")
		)
		(pad "1" smd rect
			(at 0.65024 -0.8255 90)
			(size 0.4064 1.2192)
			(layers "F.Cu" "F.Mask" "F.Paste")
			(net "SEB_PEER_1A_HB")
		)
		(pad "2" smd rect
			(at 0 -0.8255 90)
			(size 0.4064 1.2192)
			(layers "F.Cu" "F.Mask" "F.Paste")
			(net "SEB_PEER_1B_HB")
		)
		(pad "3" smd rect
			(at -0.65024 -0.8255 90)
			(size 0.4064 1.2192)
			(layers "F.Cu" "F.Mask" "F.Paste")
			(net "GND")
		)
		(pad "4" smd rect
			(at -0.65024 0.8255 90)
			(size 0.4064 1.2192)
			(layers "F.Cu" "F.Mask" "F.Paste")
			(net "SEB_PEER_1A_1B_HB_OUT")
		)
		(pad "5" smd rect
			(at 0.65024 0.8255 90)
			(size 0.4064 1.2192)
			(layers "F.Cu" "F.Mask" "F.Paste")
			(net "P3V3")
		)
	)
	(footprint ""
		(layer "F.Cu")
		(at 33.655 -410.591)
		(property "Reference" "PR31"
			(at 0 0 0)
			(layer "F.SilkS")
			(hide yes)
			(effects
				(font
					(size 1.27 1.27)
				)
			)
		)
		(property "Value" "D0005RL1632F-GP-U"
			(at 3.2258 1.2954 0)
			(unlocked yes)
			(layer "F.Fab")
			(hide yes)
			(effects
				(font
					(size 1.016 1.016)
					(thickness 0.1524)
				)
			)
		)
		(property "Device Type" "RL3115-4PH45"
			(at 3.2258 -0.2286 0)
			(unlocked yes)
			(layer "F.Fab")
			(hide yes)
			(effects
				(font
					(size 1.016 1.016)
					(thickness 0.1524)
				)
			)
		)
		(duplicate_pad_numbers_are_jumpers no)
		(fp_line
			(start -2.0574 -1.7653)
			(end -2.0574 -0.4064)
			(stroke
				(width 0.3302)
				(type default)
			)
			(layer "F.SilkS")
		)
		(fp_line
			(start -1.9685 -1.651)
			(end 1.9685 -1.651)
			(stroke
				(width 0.1524)
				(type default)
			)
			(layer "F.SilkS")
		)
		(fp_line
			(start -1.9685 1.651)
			(end -1.9685 -1.651)
			(stroke
				(width 0.1524)
				(type default)
			)
			(layer "F.SilkS")
		)
		(fp_line
			(start -0.5334 -1.7653)
			(end -2.0574 -1.7653)
			(stroke
				(width 0.3302)
				(type default)
			)
			(layer "F.SilkS")
		)
		(fp_line
			(start 1.9685 -1.651)
			(end 1.9685 1.651)
			(stroke
				(width 0.1524)
				(type default)
			)
			(layer "F.SilkS")
		)
		(fp_line
			(start 1.9685 1.651)
			(end -1.9685 1.651)
			(stroke
				(width 0.1524)
				(type default)
			)
			(layer "F.SilkS")
		)
		(fp_poly
			(pts
				(xy -0.561594 -1.726946) (xy -0.053594 -2.234946) (xy -1.069594 -2.234946)
			)
			(stroke
				(width 0)
				(type default)
			)
			(fill yes)
			(layer "F.SilkS")
		)
		(fp_rect
			(start -1.524 0.7493)
			(end 1.524 -0.7493)
			(stroke
				(width 0)
				(type default)
			)
			(fill no)
			(layer "F.CrtYd")
		)
		(fp_poly
			(pts
				(xy -2.2225 1.905) (xy -2.2225 -1.905) (xy 2.2225 -1.905) (xy 2.2225 -0.7493) (xy -1.524 -0.7493)
				(xy -1.524 0.7493) (xy 1.524 0.7493) (xy 1.524 -0.7366) (xy 2.2225 -0.7366) (xy 2.2225 1.905)
			)
			(stroke
				(width 0)
				(type default)
			)
			(fill no)
			(layer "F.CrtYd")
		)
		(fp_rect
			(start -2.2225 1.905)
			(end 2.2225 -1.905)
			(stroke
				(width 0)
				(type default)
			)
			(fill no)
			(layer "F.Fab")
		)
		(pad "1" smd rect
			(at -0.5715 -0.813562)
			(size 2.286 1.143)
			(layers "F.Cu" "F.Mask" "F.Paste")
			(net "P12V_AUX")
		)
		(pad "2" smd rect
			(at -0.5715 0.813562)
			(size 2.286 1.143)
			(layers "F.Cu" "F.Mask" "F.Paste")
			(net "P12V_SENSE_TRACE")
		)
		(pad "3" smd rect
			(at 1.334008 -0.813562)
			(size 0.762 1.143)
			(layers "F.Cu" "F.Mask" "F.Paste")
			(net "SENSE+_R3")
		)
		(pad "4" smd rect
			(at 1.334008 0.813562)
			(size 0.762 1.143)
			(layers "F.Cu" "F.Mask" "F.Paste")
			(net "SENSE-_R3")
		)
		(zone
			(layer "F.Cu")
			(hatch none 0.5)
			(connect_pads
				(clearance 0)
			)
			(min_thickness 0.25)
			(keepout
				(tracks allowed)
				(vias not_allowed)
				(pads allowed)
				(copperpour not_allowed)
				(footprints allowed)
			)
			(placement
				(enabled no)
				(sheetname "")
			)
			(fill
				(thermal_gap 0.5)
				(thermal_bridge_width 0.5)
				(island_removal_mode 0)
			)
			(polygon
				(pts
					(xy 34.2265 -410.833062) (xy 34.608008 -410.833062) (xy 34.608008 -411.3403) (xy 34.2265 -411.3403)
				)
			)
		)
		(zone
			(layer "F.Cu")
			(hatch none 0.5)
			(connect_pads
				(clearance 0)
			)
			(min_thickness 0.25)
			(keepout
				(tracks not_allowed)
				(vias allowed)
				(pads allowed)
				(copperpour not_allowed)
				(footprints allowed)
			)
			(placement
				(enabled no)
				(sheetname "")
			)
			(fill
				(thermal_gap 0.5)
				(thermal_bridge_width 0.5)
				(island_removal_mode 0)
			)
			(polygon
				(pts
					(xy 34.2265 -410.833062) (xy 34.608008 -410.833062) (xy 34.608008 -411.3403) (xy 34.2265 -411.3403)
				)
			)
		)
		(zone
			(layer "F.Cu")
			(hatch none 0.5)
			(connect_pads
				(clearance 0)
			)
			(min_thickness 0.25)
			(keepout
				(tracks allowed)
				(vias not_allowed)
				(pads allowed)
				(copperpour not_allowed)
				(footprints allowed)
			)
			(placement
				(enabled no)
				(sheetname "")
			)
			(fill
				(thermal_gap 0.5)
				(thermal_bridge_width 0.5)
				(island_removal_mode 0)
			)
			(polygon
				(pts
					(xy 34.2265 -409.8417) (xy 34.608008 -409.8417) (xy 34.608008 -410.348938) (xy 34.2265 -410.348938)
				)
			)
		)
		(zone
			(layer "F.Cu")
			(hatch none 0.5)
			(connect_pads
				(clearance 0)
			)
			(min_thickness 0.25)
			(keepout
				(tracks not_allowed)
				(vias allowed)
				(pads allowed)
				(copperpour not_allowed)
				(footprints allowed)
			)
			(placement
				(enabled no)
				(sheetname "")
			)
			(fill
				(thermal_gap 0.5)
				(thermal_bridge_width 0.5)
				(island_removal_mode 0)
			)
			(polygon
				(pts
					(xy 34.2265 -409.8417) (xy 34.608008 -409.8417) (xy 34.608008 -410.348938) (xy 34.2265 -410.348938)
				)
			)
		)
	)
	(footprint ""
		(layer "F.Cu")
		(at 23.368 -369.697 -90)
		(property "Reference" "PC4"
			(at 0 0 270)
			(layer "F.SilkS")
			(hide yes)
			(effects
				(font
					(size 1.27 1.27)
				)
			)
		)
		(property "Value" "SC1U25V3KX-1-GP"
			(at 0 -2.8194 270)
			(unlocked yes)
			(layer "F.Fab")
			(hide yes)
			(effects
				(font
					(size 1.016 1.016)
					(thickness 0.1524)
				)
			)
		)
		(property "Device Type" "C603H36"
			(at 0 -4.3434 270)
			(unlocked yes)
			(layer "F.Fab")
			(hide yes)
			(effects
				(font
					(size 1.016 1.016)
					(thickness 0.1524)
				)
			)
		)
		(duplicate_pad_numbers_are_jumpers no)
		(fp_line
			(start 0.508 0)
			(end -0.508 0)
			(stroke
				(width 0.2032)
				(type default)
			)
			(layer "F.SilkS")
		)
		(fp_rect
			(start -0.5842 1.3335)
			(end 0.5842 -1.3335)
			(stroke
				(width 0)
				(type default)
			)
			(fill no)
			(layer "F.CrtYd")
		)
		(fp_rect
			(start -0.5842 1.3335)
			(end 0.5842 -1.3335)
			(stroke
				(width 0)
				(type default)
			)
			(fill no)
			(layer "F.Fab")
		)
		(pad "1" smd custom
			(at 0 -0.762 270)
			(size 0.2159 0.2159)
			(layers "F.Cu" "F.Mask" "F.Paste")
			(net "ADM1276_VCAP")
			(options
				(clearance outline)
				(anchor circle)
			)
			(primitives
				(gr_poly
					(pts
						(arc
							(start -0.3302 -0.4318)
							(mid -0.402042 -0.402042)
							(end -0.4318 -0.3302)
						)
						(arc
							(start -0.4318 0.3302)
							(mid -0.402042 0.402042)
							(end -0.3302 0.4318)
						)
						(arc
							(start 0.3302 0.4318)
							(mid 0.402042 0.402042)
							(end 0.4318 0.3302)
						)
						(arc
							(start 0.4318 -0.3302)
							(mid 0.402042 -0.402042)
							(end 0.3302 -0.4318)
						)
					)
					(width 0)
					(fill yes)
				)
			)
		)
		(pad "2" smd custom
			(at 0 0.762 270)
			(size 0.2159 0.2159)
			(layers "F.Cu" "F.Mask" "F.Paste")
			(net "GND")
			(options
				(clearance outline)
				(anchor circle)
			)
			(primitives
				(gr_poly
					(pts
						(arc
							(start -0.3302 -0.4318)
							(mid -0.402042 -0.402042)
							(end -0.4318 -0.3302)
						)
						(arc
							(start -0.4318 0.3302)
							(mid -0.402042 0.402042)
							(end -0.3302 0.4318)
						)
						(arc
							(start 0.3302 0.4318)
							(mid 0.402042 0.402042)
							(end 0.4318 0.3302)
						)
						(arc
							(start 0.4318 -0.3302)
							(mid 0.402042 -0.402042)
							(end 0.3302 -0.4318)
						)
					)
					(width 0)
					(fill yes)
				)
			)
		)
	)
	(footprint ""
		(layer "F.Cu")
		(at 34.798 -381 180)
		(property "Reference" "PR24"
			(at 0 0 180)
			(layer "F.SilkS")
			(hide yes)
			(effects
				(font
					(size 1.27 1.27)
				)
			)
		)
		(property "Value" "10R2F-L-GP"
			(at 0.064008 -3.993896 180)
			(unlocked yes)
			(layer "F.Fab")
			(hide yes)
			(effects
				(font
					(size 1.016 1.016)
					(thickness 0.1524)
				)
			)
		)
		(property "Device Type" "R402H14"
			(at 0.064008 -5.517896 180)
			(unlocked yes)
			(layer "F.Fab")
			(hide yes)
			(effects
				(font
					(size 1.016 1.016)
					(thickness 0.1524)
				)
			)
		)
		(duplicate_pad_numbers_are_jumpers no)
		(fp_line
			(start 0.508 -0.9398)
			(end -0.508 -0.9398)
			(stroke
				(width 0.1524)
				(type default)
			)
			(layer "F.SilkS")
		)
		(fp_line
			(start -0.508 -0.9398)
			(end -0.508 0.9398)
			(stroke
				(width 0.1524)
				(type default)
			)
			(layer "F.SilkS")
		)
		(fp_rect
			(start -0.508 0.9398)
			(end 0.508 -0.9398)
			(stroke
				(width 0)
				(type default)
			)
			(fill no)
			(layer "F.CrtYd")
		)
		(fp_rect
			(start -0.508 0.9398)
			(end 0.508 -0.9398)
			(stroke
				(width 0)
				(type default)
			)
			(fill no)
			(layer "F.Fab")
		)
		(pad "1" smd custom
			(at 0 -0.4445 180)
			(size 0.1397 0.1397)
			(layers "F.Cu" "F.Mask" "F.Paste")
			(net "ADM1276_SENSE-")
			(options
				(clearance outline)
				(anchor circle)
			)
			(primitives
				(gr_poly
					(pts
						(arc
							(start -0.1778 -0.2794)
							(mid -0.249642 -0.249642)
							(end -0.2794 -0.1778)
						)
						(arc
							(start -0.2794 0.1778)
							(mid -0.249642 0.249642)
							(end -0.1778 0.2794)
						)
						(arc
							(start 0.1778 0.2794)
							(mid 0.249642 0.249642)
							(end 0.2794 0.1778)
						)
						(arc
							(start 0.2794 -0.1778)
							(mid 0.249642 -0.249642)
							(end 0.1778 -0.2794)
						)
					)
					(width 0)
					(fill yes)
				)
			)
		)
		(pad "2" smd custom
			(at 0 0.4445 180)
			(size 0.1397 0.1397)
			(layers "F.Cu" "F.Mask" "F.Paste")
			(net "SENSE-_R4")
			(options
				(clearance outline)
				(anchor circle)
			)
			(primitives
				(gr_poly
					(pts
						(arc
							(start -0.1778 -0.2794)
							(mid -0.249642 -0.249642)
							(end -0.2794 -0.1778)
						)
						(arc
							(start -0.2794 0.1778)
							(mid -0.249642 0.249642)
							(end -0.1778 0.2794)
						)
						(arc
							(start 0.1778 0.2794)
							(mid 0.249642 0.249642)
							(end 0.2794 0.1778)
						)
						(arc
							(start 0.2794 -0.1778)
							(mid 0.249642 -0.249642)
							(end 0.1778 -0.2794)
						)
					)
					(width 0)
					(fill yes)
				)
			)
		)
	)
	(footprint ""
		(layer "F.Cu")
		(at 40.999918 -450.44995 90)
		(property "Reference" "PAD2"
			(at 0 0 90)
			(layer "F.SilkS")
			(hide yes)
			(effects
				(font
					(size 1.27 1.27)
				)
			)
		)
		(property "Value" "PAD-1P-424137-1-OG-GP"
			(at -22.9743 -0.4572 90)
			(unlocked yes)
			(layer "F.Fab")
			(hide yes)
			(effects
				(font
					(size 1.016 1.016)
					(thickness 0.1524)
				)
			)
		)
		(property "Device Type" "PAD-1P-424137-1-OG"
			(at -22.9743 -1.9812 90)
			(unlocked yes)
			(layer "F.Fab")
			(hide yes)
			(effects
				(font
					(size 1.016 1.016)
					(thickness 0.1524)
				)
			)
		)
		(duplicate_pad_numbers_are_jumpers no)
		(fp_line
			(start 21.4503 -7.0993)
			(end 21.4503 7.0993)
			(stroke
				(width 0.1524)
				(type default)
			)
			(layer "F.SilkS")
		)
		(fp_line
			(start 2.816098 -7.0993)
			(end 21.4503 -7.0993)
			(stroke
				(width 0.1524)
				(type default)
			)
			(layer "F.SilkS")
		)
		(fp_line
			(start -0.075946 -7.0993)
			(end -0.075946 -5.750052)
			(stroke
				(width 0.1524)
				(type default)
			)
			(layer "F.SilkS")
		)
		(fp_line
			(start -21.4503 -7.0993)
			(end -0.075946 -7.0993)
			(stroke
				(width 0.1524)
				(type default)
			)
			(layer "F.SilkS")
		)
		(fp_line
			(start 2.816098 -5.750052)
			(end 2.816098 -7.0993)
			(stroke
				(width 0.1524)
				(type default)
			)
			(layer "F.SilkS")
		)
		(fp_line
			(start 21.4503 7.0993)
			(end -21.4503 7.0993)
			(stroke
				(width 0.1524)
				(type default)
			)
			(layer "F.SilkS")
		)
		(fp_line
			(start -21.4503 7.0993)
			(end -21.4503 -7.0993)
			(stroke
				(width 0.1524)
				(type default)
			)
			(layer "F.SilkS")
		)
		(fp_arc
			(start 2.816098 -5.750052)
			(mid 1.37008 -4.30403)
			(end -0.075946 -5.750052)
			(stroke
				(width 0.1524)
				(type default)
			)
			(layer "F.SilkS")
		)
		(fp_poly
			(pts
				(xy -21.7043 7.3533) (xy -21.7043 -7.3533) (xy 0.178054 -7.3533)
				(arc
					(start 0.178054 -5.750052)
					(mid 1.370076 -4.55803)
					(end 2.562098 -5.750052)
				)
				(xy 2.562098 -7.3533) (xy 21.7043 -7.3533) (xy 21.7043 7.3533)
			)
			(stroke
				(width 0)
				(type default)
			)
			(fill no)
			(layer "F.CrtYd")
		)
		(fp_poly
			(pts
				(xy -21.7043 7.3533) (xy -21.7043 -7.3533) (xy 0.178054 -7.3533)
				(arc
					(start 0.178054 -5.750052)
					(mid 1.370076 -4.55803)
					(end 2.562098 -5.750052)
				)
				(xy 2.562098 -7.3533) (xy 21.7043 -7.3533) (xy 21.7043 7.3533)
			)
			(stroke
				(width 0)
				(type default)
			)
			(fill no)
			(layer "F.Fab")
		)
		(pad "1" smd custom
			(at 0 0 90)
			(size 3.425063 3.425063)
			(layers "F.Cu" "F.Mask" "F.Paste")
			(net "GND")
			(options
				(clearance outline)
				(anchor circle)
			)
			(primitives
				(gr_poly
					(pts
						(xy -0.329946 -6.850126) (xy -21.20011 -6.850126) (xy -21.20011 6.850126) (xy 21.20011 6.850126)
						(xy 21.20011 -6.850126) (xy 3.070098 -6.850126)
						(arc
							(start 3.070098 -5.750052)
							(mid 1.370076 -4.05003)
							(end -0.329946 -5.750052)
						)
					)
					(width 0)
					(fill yes)
				)
			)
		)
	)
	(footprint ""
		(layer "F.Cu")
		(at 15.113 -55.118 90)
		(property "Reference" "R358"
			(at 0 0 90)
			(layer "F.SilkS")
			(hide yes)
			(effects
				(font
					(size 1.27 1.27)
				)
			)
		)
		(property "Value" "10KR2F-2-GP"
			(at 0.064008 -3.993896 90)
			(unlocked yes)
			(layer "F.Fab")
			(hide yes)
			(effects
				(font
					(size 1.016 1.016)
					(thickness 0.1524)
				)
			)
		)
		(property "Device Type" "R402H16"
			(at 0.064008 -5.517896 90)
			(unlocked yes)
			(layer "F.Fab")
			(hide yes)
			(effects
				(font
					(size 1.016 1.016)
					(thickness 0.1524)
				)
			)
		)
		(duplicate_pad_numbers_are_jumpers no)
		(fp_line
			(start 0.508 -0.9398)
			(end -0.508 -0.9398)
			(stroke
				(width 0.1524)
				(type default)
			)
			(layer "F.SilkS")
		)
		(fp_line
			(start -0.508 -0.9398)
			(end -0.508 0.9398)
			(stroke
				(width 0.1524)
				(type default)
			)
			(layer "F.SilkS")
		)
		(fp_rect
			(start -0.508 0.9398)
			(end 0.508 -0.9398)
			(stroke
				(width 0)
				(type default)
			)
			(fill no)
			(layer "F.CrtYd")
		)
		(fp_rect
			(start -0.508 0.9398)
			(end 0.508 -0.9398)
			(stroke
				(width 0)
				(type default)
			)
			(fill no)
			(layer "F.Fab")
		)
		(pad "1" smd custom
			(at 0 -0.4445 90)
			(size 0.1397 0.1397)
			(layers "F.Cu" "F.Mask" "F.Paste")
			(net "P3V3")
			(options
				(clearance outline)
				(anchor circle)
			)
			(primitives
				(gr_poly
					(pts
						(arc
							(start -0.1778 -0.2794)
							(mid -0.249642 -0.249642)
							(end -0.2794 -0.1778)
						)
						(arc
							(start -0.2794 0.1778)
							(mid -0.249642 0.249642)
							(end -0.1778 0.2794)
						)
						(arc
							(start 0.1778 0.2794)
							(mid 0.249642 0.249642)
							(end 0.2794 0.1778)
						)
						(arc
							(start 0.2794 -0.1778)
							(mid 0.249642 -0.249642)
							(end 0.1778 -0.2794)
						)
					)
					(width 0)
					(fill yes)
				)
			)
		)
		(pad "2" smd custom
			(at 0 0.4445 90)
			(size 0.1397 0.1397)
			(layers "F.Cu" "F.Mask" "F.Paste")
			(net "LOWER_TRAY_ID")
			(options
				(clearance outline)
				(anchor circle)
			)
			(primitives
				(gr_poly
					(pts
						(arc
							(start -0.1778 -0.2794)
							(mid -0.249642 -0.249642)
							(end -0.2794 -0.1778)
						)
						(arc
							(start -0.2794 0.1778)
							(mid -0.249642 0.249642)
							(end -0.1778 0.2794)
						)
						(arc
							(start 0.1778 0.2794)
							(mid 0.249642 0.249642)
							(end 0.2794 0.1778)
						)
						(arc
							(start 0.2794 -0.1778)
							(mid 0.249642 -0.249642)
							(end 0.1778 -0.2794)
						)
					)
					(width 0)
					(fill yes)
				)
			)
		)
	)
	(footprint ""
		(layer "F.Cu")
		(at 21.209 -371.729)
		(property "Reference" "PR33"
			(at 0 0 0)
			(layer "F.SilkS")
			(hide yes)
			(effects
				(font
					(size 1.27 1.27)
				)
			)
		)
		(property "Value" "51KR2F-L-GP"
			(at 0.064008 -3.993896 0)
			(unlocked yes)
			(layer "F.Fab")
			(hide yes)
			(effects
				(font
					(size 1.016 1.016)
					(thickness 0.1524)
				)
			)
		)
		(property "Device Type" "R402H16"
			(at 0.064008 -5.517896 0)
			(unlocked yes)
			(layer "F.Fab")
			(hide yes)
			(effects
				(font
					(size 1.016 1.016)
					(thickness 0.1524)
				)
			)
		)
		(duplicate_pad_numbers_are_jumpers no)
		(fp_line
			(start -0.508 -0.9398)
			(end -0.508 0.9398)
			(stroke
				(width 0.1524)
				(type default)
			)
			(layer "F.SilkS")
		)
		(fp_line
			(start 0.508 -0.9398)
			(end -0.508 -0.9398)
			(stroke
				(width 0.1524)
				(type default)
			)
			(layer "F.SilkS")
		)
		(fp_rect
			(start -0.508 0.9398)
			(end 0.508 -0.9398)
			(stroke
				(width 0)
				(type default)
			)
			(fill no)
			(layer "F.CrtYd")
		)
		(fp_rect
			(start -0.508 0.9398)
			(end 0.508 -0.9398)
			(stroke
				(width 0)
				(type default)
			)
			(fill no)
			(layer "F.Fab")
		)
		(pad "1" smd custom
			(at 0 -0.4445)
			(size 0.1397 0.1397)
			(layers "F.Cu" "F.Mask" "F.Paste")
			(net "P12V_AUX")
			(options
				(clearance outline)
				(anchor circle)
			)
			(primitives
				(gr_poly
					(pts
						(arc
							(start -0.1778 -0.2794)
							(mid -0.249642 -0.249642)
							(end -0.2794 -0.1778)
						)
						(arc
							(start -0.2794 0.1778)
							(mid -0.249642 0.249642)
							(end -0.1778 0.2794)
						)
						(arc
							(start 0.1778 0.2794)
							(mid 0.249642 0.249642)
							(end 0.2794 0.1778)
						)
						(arc
							(start 0.2794 -0.1778)
							(mid 0.249642 -0.249642)
							(end 0.1778 -0.2794)
						)
					)
					(width 0)
					(fill yes)
				)
			)
		)
		(pad "2" smd custom
			(at 0 0.4445)
			(size 0.1397 0.1397)
			(layers "F.Cu" "F.Mask" "F.Paste")
			(net "ADM1276_OV")
			(options
				(clearance outline)
				(anchor circle)
			)
			(primitives
				(gr_poly
					(pts
						(arc
							(start -0.1778 -0.2794)
							(mid -0.249642 -0.249642)
							(end -0.2794 -0.1778)
						)
						(arc
							(start -0.2794 0.1778)
							(mid -0.249642 0.249642)
							(end -0.1778 0.2794)
						)
						(arc
							(start 0.1778 0.2794)
							(mid 0.249642 0.249642)
							(end 0.2794 0.1778)
						)
						(arc
							(start 0.2794 -0.1778)
							(mid 0.249642 -0.249642)
							(end 0.1778 -0.2794)
						)
					)
					(width 0)
					(fill yes)
				)
			)
		)
	)
	(footprint ""
		(layer "F.Cu")
		(at 35.6616 -144.6784 180)
		(property "Reference" "PC92"
			(at 0 0 180)
			(layer "F.SilkS")
			(hide yes)
			(effects
				(font
					(size 1.27 1.27)
				)
			)
		)
		(property "Value" "SCD01U50V3KX-4GP"
			(at 0 -2.8194 180)
			(unlocked yes)
			(layer "F.Fab")
			(hide yes)
			(effects
				(font
					(size 1.016 1.016)
					(thickness 0.1524)
				)
			)
		)
		(property "Device Type" "C603H36"
			(at 0 -4.3434 180)
			(unlocked yes)
			(layer "F.Fab")
			(hide yes)
			(effects
				(font
					(size 1.016 1.016)
					(thickness 0.1524)
				)
			)
		)
		(duplicate_pad_numbers_are_jumpers no)
		(fp_line
			(start 0.508 0)
			(end -0.508 0)
			(stroke
				(width 0.2032)
				(type default)
			)
			(layer "F.SilkS")
		)
		(fp_rect
			(start -0.5842 1.3335)
			(end 0.5842 -1.3335)
			(stroke
				(width 0)
				(type default)
			)
			(fill no)
			(layer "F.CrtYd")
		)
		(fp_rect
			(start -0.5842 1.3335)
			(end 0.5842 -1.3335)
			(stroke
				(width 0)
				(type default)
			)
			(fill no)
			(layer "F.Fab")
		)
		(pad "1" smd custom
			(at 0 -0.762 180)
			(size 0.2159 0.2159)
			(layers "F.Cu" "F.Mask" "F.Paste")
			(net "P12VL_2490_TIMER")
			(options
				(clearance outline)
				(anchor circle)
			)
			(primitives
				(gr_poly
					(pts
						(arc
							(start -0.3302 -0.4318)
							(mid -0.402042 -0.402042)
							(end -0.4318 -0.3302)
						)
						(arc
							(start -0.4318 0.3302)
							(mid -0.402042 0.402042)
							(end -0.3302 0.4318)
						)
						(arc
							(start 0.3302 0.4318)
							(mid 0.402042 0.402042)
							(end 0.4318 0.3302)
						)
						(arc
							(start 0.4318 -0.3302)
							(mid 0.402042 -0.402042)
							(end 0.3302 -0.4318)
						)
					)
					(width 0)
					(fill yes)
				)
			)
		)
		(pad "2" smd custom
			(at 0 0.762 180)
			(size 0.2159 0.2159)
			(layers "F.Cu" "F.Mask" "F.Paste")
			(net "GND")
			(options
				(clearance outline)
				(anchor circle)
			)
			(primitives
				(gr_poly
					(pts
						(arc
							(start -0.3302 -0.4318)
							(mid -0.402042 -0.402042)
							(end -0.4318 -0.3302)
						)
						(arc
							(start -0.4318 0.3302)
							(mid -0.402042 0.402042)
							(end -0.3302 0.4318)
						)
						(arc
							(start 0.3302 0.4318)
							(mid 0.402042 0.402042)
							(end 0.4318 0.3302)
						)
						(arc
							(start 0.4318 -0.3302)
							(mid 0.402042 -0.402042)
							(end 0.3302 -0.4318)
						)
					)
					(width 0)
					(fill yes)
				)
			)
		)
	)
	(footprint ""
		(layer "F.Cu")
		(at 28.702 -195.3514 90)
		(property "Reference" "C42"
			(at 0 0 90)
			(layer "F.SilkS")
			(hide yes)
			(effects
				(font
					(size 1.27 1.27)
				)
			)
		)
		(property "Value" "SC1U25V3KX-1-GP"
			(at 0 -2.8194 90)
			(unlocked yes)
			(layer "F.Fab")
			(hide yes)
			(effects
				(font
					(size 1.016 1.016)
					(thickness 0.1524)
				)
			)
		)
		(property "Device Type" "C603H36"
			(at 0 -4.3434 90)
			(unlocked yes)
			(layer "F.Fab")
			(hide yes)
			(effects
				(font
					(size 1.016 1.016)
					(thickness 0.1524)
				)
			)
		)
		(duplicate_pad_numbers_are_jumpers no)
		(fp_line
			(start 0.508 0)
			(end -0.508 0)
			(stroke
				(width 0.2032)
				(type default)
			)
			(layer "F.SilkS")
		)
		(fp_rect
			(start -0.5842 1.3335)
			(end 0.5842 -1.3335)
			(stroke
				(width 0)
				(type default)
			)
			(fill no)
			(layer "F.CrtYd")
		)
		(fp_rect
			(start -0.5842 1.3335)
			(end 0.5842 -1.3335)
			(stroke
				(width 0)
				(type default)
			)
			(fill no)
			(layer "F.Fab")
		)
		(pad "1" smd custom
			(at 0 -0.762 90)
			(size 0.2159 0.2159)
			(layers "F.Cu" "F.Mask" "F.Paste")
			(net "P12V")
			(options
				(clearance outline)
				(anchor circle)
			)
			(primitives
				(gr_poly
					(pts
						(arc
							(start -0.3302 -0.4318)
							(mid -0.402042 -0.402042)
							(end -0.4318 -0.3302)
						)
						(arc
							(start -0.4318 0.3302)
							(mid -0.402042 0.402042)
							(end -0.3302 0.4318)
						)
						(arc
							(start 0.3302 0.4318)
							(mid 0.402042 0.402042)
							(end 0.4318 0.3302)
						)
						(arc
							(start 0.4318 -0.3302)
							(mid 0.402042 -0.402042)
							(end 0.3302 -0.4318)
						)
					)
					(width 0)
					(fill yes)
				)
			)
		)
		(pad "2" smd custom
			(at 0 0.762 90)
			(size 0.2159 0.2159)
			(layers "F.Cu" "F.Mask" "F.Paste")
			(net "GND")
			(options
				(clearance outline)
				(anchor circle)
			)
			(primitives
				(gr_poly
					(pts
						(arc
							(start -0.3302 -0.4318)
							(mid -0.402042 -0.402042)
							(end -0.4318 -0.3302)
						)
						(arc
							(start -0.4318 0.3302)
							(mid -0.402042 0.402042)
							(end -0.3302 0.4318)
						)
						(arc
							(start 0.3302 0.4318)
							(mid 0.402042 0.402042)
							(end 0.4318 0.3302)
						)
						(arc
							(start 0.4318 -0.3302)
							(mid 0.402042 -0.402042)
							(end 0.3302 -0.4318)
						)
					)
					(width 0)
					(fill yes)
				)
			)
		)
	)
	(footprint ""
		(layer "F.Cu")
		(at 28.9814 -96.5454 -90)
		(property "Reference" "C24"
			(at 0 0 270)
			(layer "F.SilkS")
			(hide yes)
			(effects
				(font
					(size 1.27 1.27)
				)
			)
		)
		(property "Value" "SCD1U50V3KX-GP"
			(at 0 -2.8194 270)
			(unlocked yes)
			(layer "F.Fab")
			(hide yes)
			(effects
				(font
					(size 1.016 1.016)
					(thickness 0.1524)
				)
			)
		)
		(property "Device Type" "C603H36"
			(at 0 -4.3434 270)
			(unlocked yes)
			(layer "F.Fab")
			(hide yes)
			(effects
				(font
					(size 1.016 1.016)
					(thickness 0.1524)
				)
			)
		)
		(duplicate_pad_numbers_are_jumpers no)
		(fp_line
			(start 0.508 0)
			(end -0.508 0)
			(stroke
				(width 0.2032)
				(type default)
			)
			(layer "F.SilkS")
		)
		(fp_rect
			(start -0.5842 1.3335)
			(end 0.5842 -1.3335)
			(stroke
				(width 0)
				(type default)
			)
			(fill no)
			(layer "F.CrtYd")
		)
		(fp_rect
			(start -0.5842 1.3335)
			(end 0.5842 -1.3335)
			(stroke
				(width 0)
				(type default)
			)
			(fill no)
			(layer "F.Fab")
		)
		(pad "1" smd custom
			(at 0 -0.762 270)
			(size 0.2159 0.2159)
			(layers "F.Cu" "F.Mask" "F.Paste")
			(net "P12VL")
			(options
				(clearance outline)
				(anchor circle)
			)
			(primitives
				(gr_poly
					(pts
						(arc
							(start -0.3302 -0.4318)
							(mid -0.402042 -0.402042)
							(end -0.4318 -0.3302)
						)
						(arc
							(start -0.4318 0.3302)
							(mid -0.402042 0.402042)
							(end -0.3302 0.4318)
						)
						(arc
							(start 0.3302 0.4318)
							(mid 0.402042 0.402042)
							(end 0.4318 0.3302)
						)
						(arc
							(start 0.4318 -0.3302)
							(mid 0.402042 -0.402042)
							(end 0.3302 -0.4318)
						)
					)
					(width 0)
					(fill yes)
				)
			)
		)
		(pad "2" smd custom
			(at 0 0.762 270)
			(size 0.2159 0.2159)
			(layers "F.Cu" "F.Mask" "F.Paste")
			(net "GND")
			(options
				(clearance outline)
				(anchor circle)
			)
			(primitives
				(gr_poly
					(pts
						(arc
							(start -0.3302 -0.4318)
							(mid -0.402042 -0.402042)
							(end -0.4318 -0.3302)
						)
						(arc
							(start -0.4318 0.3302)
							(mid -0.402042 0.402042)
							(end -0.3302 0.4318)
						)
						(arc
							(start 0.3302 0.4318)
							(mid 0.402042 0.402042)
							(end 0.4318 0.3302)
						)
						(arc
							(start 0.4318 -0.3302)
							(mid 0.402042 -0.402042)
							(end 0.3302 -0.4318)
						)
					)
					(width 0)
					(fill yes)
				)
			)
		)
	)
	(footprint ""
		(layer "F.Cu")
		(at 29.3624 -167.259 180)
		(property "Reference" "R162"
			(at 0 0 180)
			(layer "F.SilkS")
			(hide yes)
			(effects
				(font
					(size 1.27 1.27)
				)
			)
		)
		(property "Value" "0R2J-2-GP"
			(at 0.064008 -3.993896 180)
			(unlocked yes)
			(layer "F.Fab")
			(hide yes)
			(effects
				(font
					(size 1.016 1.016)
					(thickness 0.1524)
				)
			)
		)
		(property "Device Type" "R402H16"
			(at 0.064008 -5.517896 180)
			(unlocked yes)
			(layer "F.Fab")
			(hide yes)
			(effects
				(font
					(size 1.016 1.016)
					(thickness 0.1524)
				)
			)
		)
		(duplicate_pad_numbers_are_jumpers no)
		(fp_line
			(start 0.508 -0.9398)
			(end -0.508 -0.9398)
			(stroke
				(width 0.1524)
				(type default)
			)
			(layer "F.SilkS")
		)
		(fp_line
			(start -0.508 -0.9398)
			(end -0.508 0.9398)
			(stroke
				(width 0.1524)
				(type default)
			)
			(layer "F.SilkS")
		)
		(fp_rect
			(start -0.508 0.9398)
			(end 0.508 -0.9398)
			(stroke
				(width 0)
				(type default)
			)
			(fill no)
			(layer "F.CrtYd")
		)
		(fp_rect
			(start -0.508 0.9398)
			(end 0.508 -0.9398)
			(stroke
				(width 0)
				(type default)
			)
			(fill no)
			(layer "F.Fab")
		)
		(pad "1" smd custom
			(at 0 -0.4445 180)
			(size 0.1397 0.1397)
			(layers "F.Cu" "F.Mask" "F.Paste")
			(net "NCT7904D_PWM2")
			(options
				(clearance outline)
				(anchor circle)
			)
			(primitives
				(gr_poly
					(pts
						(arc
							(start -0.1778 -0.2794)
							(mid -0.249642 -0.249642)
							(end -0.2794 -0.1778)
						)
						(arc
							(start -0.2794 0.1778)
							(mid -0.249642 0.249642)
							(end -0.1778 0.2794)
						)
						(arc
							(start 0.1778 0.2794)
							(mid 0.249642 0.249642)
							(end 0.2794 0.1778)
						)
						(arc
							(start 0.2794 -0.1778)
							(mid 0.249642 -0.249642)
							(end 0.1778 -0.2794)
						)
					)
					(width 0)
					(fill yes)
				)
			)
		)
		(pad "2" smd custom
			(at 0 0.4445 180)
			(size 0.1397 0.1397)
			(layers "F.Cu" "F.Mask" "F.Paste")
			(net "PWM_BUFFER_IN_FAN3_FAN4")
			(options
				(clearance outline)
				(anchor circle)
			)
			(primitives
				(gr_poly
					(pts
						(arc
							(start -0.1778 -0.2794)
							(mid -0.249642 -0.249642)
							(end -0.2794 -0.1778)
						)
						(arc
							(start -0.2794 0.1778)
							(mid -0.249642 0.249642)
							(end -0.1778 0.2794)
						)
						(arc
							(start 0.1778 0.2794)
							(mid 0.249642 0.249642)
							(end 0.2794 0.1778)
						)
						(arc
							(start 0.2794 -0.1778)
							(mid 0.249642 -0.249642)
							(end 0.1778 -0.2794)
						)
					)
					(width 0)
					(fill yes)
				)
			)
		)
	)
	(footprint ""
		(layer "F.Cu")
		(at 23.63851 -151.325834)
		(property "Reference" "R12"
			(at 0 0 0)
			(layer "F.SilkS")
			(hide yes)
			(effects
				(font
					(size 1.27 1.27)
				)
			)
		)
		(property "Value" "4K7R2F-GP"
			(at 0.064008 -3.993896 0)
			(unlocked yes)
			(layer "F.Fab")
			(hide yes)
			(effects
				(font
					(size 1.016 1.016)
					(thickness 0.1524)
				)
			)
		)
		(property "Device Type" "R402H16"
			(at 0.064008 -5.517896 0)
			(unlocked yes)
			(layer "F.Fab")
			(hide yes)
			(effects
				(font
					(size 1.016 1.016)
					(thickness 0.1524)
				)
			)
		)
		(duplicate_pad_numbers_are_jumpers no)
		(fp_line
			(start -0.508 -0.9398)
			(end -0.508 0.9398)
			(stroke
				(width 0.1524)
				(type default)
			)
			(layer "F.SilkS")
		)
		(fp_line
			(start 0.508 -0.9398)
			(end -0.508 -0.9398)
			(stroke
				(width 0.1524)
				(type default)
			)
			(layer "F.SilkS")
		)
		(fp_rect
			(start -0.508 0.9398)
			(end 0.508 -0.9398)
			(stroke
				(width 0)
				(type default)
			)
			(fill no)
			(layer "F.CrtYd")
		)
		(fp_rect
			(start -0.508 0.9398)
			(end 0.508 -0.9398)
			(stroke
				(width 0)
				(type default)
			)
			(fill no)
			(layer "F.Fab")
		)
		(pad "1" smd custom
			(at 0 -0.4445)
			(size 0.1397 0.1397)
			(layers "F.Cu" "F.Mask" "F.Paste")
			(net "NCT7904_RESET")
			(options
				(clearance outline)
				(anchor circle)
			)
			(primitives
				(gr_poly
					(pts
						(arc
							(start -0.1778 -0.2794)
							(mid -0.249642 -0.249642)
							(end -0.2794 -0.1778)
						)
						(arc
							(start -0.2794 0.1778)
							(mid -0.249642 0.249642)
							(end -0.1778 0.2794)
						)
						(arc
							(start 0.1778 0.2794)
							(mid 0.249642 0.249642)
							(end 0.2794 0.1778)
						)
						(arc
							(start 0.2794 -0.1778)
							(mid 0.249642 -0.249642)
							(end 0.1778 -0.2794)
						)
					)
					(width 0)
					(fill yes)
				)
			)
		)
		(pad "2" smd custom
			(at 0 0.4445)
			(size 0.1397 0.1397)
			(layers "F.Cu" "F.Mask" "F.Paste")
			(net "P3V3")
			(options
				(clearance outline)
				(anchor circle)
			)
			(primitives
				(gr_poly
					(pts
						(arc
							(start -0.1778 -0.2794)
							(mid -0.249642 -0.249642)
							(end -0.2794 -0.1778)
						)
						(arc
							(start -0.2794 0.1778)
							(mid -0.249642 0.249642)
							(end -0.1778 0.2794)
						)
						(arc
							(start 0.1778 0.2794)
							(mid 0.249642 0.249642)
							(end 0.2794 0.1778)
						)
						(arc
							(start 0.2794 -0.1778)
							(mid 0.249642 -0.249642)
							(end 0.1778 -0.2794)
						)
					)
					(width 0)
					(fill yes)
				)
			)
		)
	)
	(footprint ""
		(layer "F.Cu")
		(at 16.053308 -287.311338)
		(property "Reference" "R98"
			(at 0 0 0)
			(layer "F.SilkS")
			(hide yes)
			(effects
				(font
					(size 1.27 1.27)
				)
			)
		)
		(property "Value" "27KR3F-GP"
			(at -0.0254 -2.5146 0)
			(unlocked yes)
			(layer "F.Fab")
			(hide yes)
			(effects
				(font
					(size 1.016 1.016)
					(thickness 0.1524)
				)
			)
		)
		(property "Device Type" "R603H22"
			(at -0.0254 -4.0386 0)
			(unlocked yes)
			(layer "F.Fab")
			(hide yes)
			(effects
				(font
					(size 1.016 1.016)
					(thickness 0.1524)
				)
			)
		)
		(duplicate_pad_numbers_are_jumpers no)
		(fp_line
			(start -0.4826 0)
			(end -0.2032 0)
			(stroke
				(width 0.2032)
				(type default)
			)
			(layer "F.SilkS")
		)
		(fp_line
			(start 0.2032 0)
			(end 0.4826 0)
			(stroke
				(width 0.2032)
				(type default)
			)
			(layer "F.SilkS")
		)
		(fp_rect
			(start -0.5842 1.3335)
			(end 0.5842 -1.3335)
			(stroke
				(width 0)
				(type default)
			)
			(fill no)
			(layer "F.CrtYd")
		)
		(fp_rect
			(start -0.5842 1.3335)
			(end 0.5842 -1.3335)
			(stroke
				(width 0)
				(type default)
			)
			(fill no)
			(layer "F.Fab")
		)
		(pad "1" smd custom
			(at 0 -0.762)
			(size 0.2159 0.2159)
			(layers "F.Cu" "F.Mask" "F.Paste")
			(net "FANIN_3")
			(options
				(clearance outline)
				(anchor circle)
			)
			(primitives
				(gr_poly
					(pts
						(arc
							(start -0.3302 -0.4318)
							(mid -0.402042 -0.402042)
							(end -0.4318 -0.3302)
						)
						(arc
							(start -0.4318 0.3302)
							(mid -0.402042 0.402042)
							(end -0.3302 0.4318)
						)
						(arc
							(start 0.3302 0.4318)
							(mid 0.402042 0.402042)
							(end 0.4318 0.3302)
						)
						(arc
							(start 0.4318 -0.3302)
							(mid 0.402042 -0.402042)
							(end 0.3302 -0.4318)
						)
					)
					(width 0)
					(fill yes)
				)
			)
		)
		(pad "2" smd custom
			(at 0 0.762)
			(size 0.2159 0.2159)
			(layers "F.Cu" "F.Mask" "F.Paste")
			(net "FAN_TACH3")
			(options
				(clearance outline)
				(anchor circle)
			)
			(primitives
				(gr_poly
					(pts
						(arc
							(start -0.3302 -0.4318)
							(mid -0.402042 -0.402042)
							(end -0.4318 -0.3302)
						)
						(arc
							(start -0.4318 0.3302)
							(mid -0.402042 0.402042)
							(end -0.3302 0.4318)
						)
						(arc
							(start 0.3302 0.4318)
							(mid 0.402042 0.402042)
							(end 0.4318 0.3302)
						)
						(arc
							(start 0.4318 -0.3302)
							(mid 0.402042 -0.402042)
							(end 0.3302 -0.4318)
						)
					)
					(width 0)
					(fill yes)
				)
			)
		)
	)
	(footprint ""
		(layer "F.Cu")
		(at 26.4922 -251.6632 -90)
		(property "Reference" "C13"
			(at 0 0 270)
			(layer "F.SilkS")
			(hide yes)
			(effects
				(font
					(size 1.27 1.27)
				)
			)
		)
		(property "Value" "SC1U16V3KX-5GP"
			(at 0 -2.8194 270)
			(unlocked yes)
			(layer "F.Fab")
			(hide yes)
			(effects
				(font
					(size 1.016 1.016)
					(thickness 0.1524)
				)
			)
		)
		(property "Device Type" "C603H36"
			(at 0 -4.3434 270)
			(unlocked yes)
			(layer "F.Fab")
			(hide yes)
			(effects
				(font
					(size 1.016 1.016)
					(thickness 0.1524)
				)
			)
		)
		(duplicate_pad_numbers_are_jumpers no)
		(fp_line
			(start 0.508 0)
			(end -0.508 0)
			(stroke
				(width 0.2032)
				(type default)
			)
			(layer "F.SilkS")
		)
		(fp_rect
			(start -0.5842 1.3335)
			(end 0.5842 -1.3335)
			(stroke
				(width 0)
				(type default)
			)
			(fill no)
			(layer "F.CrtYd")
		)
		(fp_rect
			(start -0.5842 1.3335)
			(end 0.5842 -1.3335)
			(stroke
				(width 0)
				(type default)
			)
			(fill no)
			(layer "F.Fab")
		)
		(pad "1" smd custom
			(at 0 -0.762 270)
			(size 0.2159 0.2159)
			(layers "F.Cu" "F.Mask" "F.Paste")
			(net "P3V3")
			(options
				(clearance outline)
				(anchor circle)
			)
			(primitives
				(gr_poly
					(pts
						(arc
							(start -0.3302 -0.4318)
							(mid -0.402042 -0.402042)
							(end -0.4318 -0.3302)
						)
						(arc
							(start -0.4318 0.3302)
							(mid -0.402042 0.402042)
							(end -0.3302 0.4318)
						)
						(arc
							(start 0.3302 0.4318)
							(mid 0.402042 0.402042)
							(end 0.4318 0.3302)
						)
						(arc
							(start 0.4318 -0.3302)
							(mid 0.402042 -0.402042)
							(end 0.3302 -0.4318)
						)
					)
					(width 0)
					(fill yes)
				)
			)
		)
		(pad "2" smd custom
			(at 0 0.762 270)
			(size 0.2159 0.2159)
			(layers "F.Cu" "F.Mask" "F.Paste")
			(net "GND")
			(options
				(clearance outline)
				(anchor circle)
			)
			(primitives
				(gr_poly
					(pts
						(arc
							(start -0.3302 -0.4318)
							(mid -0.402042 -0.402042)
							(end -0.4318 -0.3302)
						)
						(arc
							(start -0.4318 0.3302)
							(mid -0.402042 0.402042)
							(end -0.3302 0.4318)
						)
						(arc
							(start 0.3302 0.4318)
							(mid 0.402042 0.402042)
							(end 0.4318 0.3302)
						)
						(arc
							(start 0.4318 -0.3302)
							(mid 0.402042 -0.402042)
							(end 0.3302 -0.4318)
						)
					)
					(width 0)
					(fill yes)
				)
			)
		)
	)
	(footprint ""
		(layer "F.Cu")
		(at 7.949946 -267.865098 -90)
		(property "Reference" "LED3"
			(at 0 0 270)
			(layer "F.SilkS")
			(hide yes)
			(effects
				(font
					(size 1.27 1.27)
				)
			)
		)
		(property "Value" "LED-RB-6-GP"
			(at -4.6736 3.8354 270)
			(unlocked yes)
			(layer "F.Fab")
			(hide yes)
			(effects
				(font
					(size 1.016 1.016)
					(thickness 0.1524)
				)
			)
		)
		(property "Device Type" "LED-100-3P-067106H325"
			(at -4.6736 2.3114 270)
			(unlocked yes)
			(layer "F.Fab")
			(hide yes)
			(effects
				(font
					(size 1.016 1.016)
					(thickness 0.1524)
				)
			)
		)
		(duplicate_pad_numbers_are_jumpers no)
		(fp_line
			(start -1.7526 10.414)
			(end -1.7526 6.6548)
			(stroke
				(width 0.1524)
				(type default)
			)
			(layer "F.SilkS")
		)
		(fp_line
			(start 1.7526 10.414)
			(end -1.7526 10.414)
			(stroke
				(width 0.1524)
				(type default)
			)
			(layer "F.SilkS")
		)
		(fp_line
			(start -3.6068 6.6548)
			(end -3.6068 -0.889)
			(stroke
				(width 0.1524)
				(type default)
			)
			(layer "F.SilkS")
		)
		(fp_line
			(start -1.7526 6.6548)
			(end -3.6068 6.6548)
			(stroke
				(width 0.1524)
				(type default)
			)
			(layer "F.SilkS")
		)
		(fp_line
			(start 1.7526 6.6548)
			(end 1.7526 10.414)
			(stroke
				(width 0.1524)
				(type default)
			)
			(layer "F.SilkS")
		)
		(fp_line
			(start 3.6068 6.6548)
			(end 1.7526 6.6548)
			(stroke
				(width 0.1524)
				(type default)
			)
			(layer "F.SilkS")
		)
		(fp_line
			(start -3.6068 -0.889)
			(end 3.6068 -0.889)
			(stroke
				(width 0.1524)
				(type default)
			)
			(layer "F.SilkS")
		)
		(fp_line
			(start 3.6068 -0.889)
			(end 3.6068 6.6548)
			(stroke
				(width 0.1524)
				(type default)
			)
			(layer "F.SilkS")
		)
		(fp_circle
			(center -2.54 0)
			(end -2.54 -0.9906)
			(stroke
				(width 0.3048)
				(type default)
			)
			(fill no)
			(layer "F.SilkS")
		)
		(fp_circle
			(center 0 0)
			(end 0 -0.9906)
			(stroke
				(width 0.3048)
				(type default)
			)
			(fill no)
			(layer "F.SilkS")
		)
		(fp_circle
			(center 2.54 0)
			(end 2.54 -0.9906)
			(stroke
				(width 0.3048)
				(type default)
			)
			(fill no)
			(layer "F.SilkS")
		)
		(fp_poly
			(pts
				(xy -1.4986 10.1473) (xy -1.4986 6.4008) (xy -3.3528 6.4008) (xy -3.3528 -0.3937) (xy 3.3528 -0.3937)
				(xy 3.3528 6.4008) (xy 1.4986 6.4008) (xy 1.4986 10.1473)
			)
			(stroke
				(width 0)
				(type default)
			)
			(fill no)
			(layer "F.CrtYd")
		)
		(fp_poly
			(pts
				(xy -2.0066 10.668) (xy 2.0066 10.668) (xy 2.0066 6.9088) (xy 3.8608 6.9088) (xy 3.8608 2.2098)
				(xy 3.3528 2.2098) (xy 3.3528 6.4008) (xy 1.4986 6.4008) (xy 1.4986 10.1473) (xy -1.4986 10.1473)
				(xy -1.4986 6.4008) (xy -3.3528 6.4008) (xy -3.3528 -0.3937) (xy 3.3528 -0.3937) (xy 3.3528 2.1971)
				(xy 3.8608 2.1971) (xy 3.8608 -1.143) (xy -3.8608 -1.143) (xy -3.8608 6.9088) (xy -2.0066 6.9088)
			)
			(stroke
				(width 0)
				(type default)
			)
			(fill no)
			(layer "F.CrtYd")
		)
		(fp_poly
			(pts
				(xy -2.0066 10.668) (xy -2.0066 6.9088) (xy -3.8608 6.9088) (xy -3.8608 -1.143) (xy 3.8608 -1.143)
				(xy 3.8608 6.9088) (xy 2.0066 6.9088) (xy 2.0066 10.668)
			)
			(stroke
				(width 0)
				(type default)
			)
			(fill no)
			(layer "F.Fab")
		)
		(pad "1" thru_hole circle
			(at 2.54 0 270)
			(size 1.27 1.27)
			(drill 0.889)
			(layers "*.Cu" "*.Mask")
			(remove_unused_layers no)
			(net "LED_DR_LED2_BLUE")
			(clearance 0.1651)
			(thermal_gap 0.1651)
		)
		(pad "2" thru_hole circle
			(at 0 0 270)
			(size 1.27 1.27)
			(drill 0.889)
			(layers "*.Cu" "*.Mask")
			(remove_unused_layers no)
			(net "LED_DR_LED2_K")
			(clearance 0.1651)
			(thermal_gap 0.1651)
		)
		(pad "3" thru_hole circle
			(at -2.54 0 270)
			(size 1.27 1.27)
			(drill 0.889)
			(layers "*.Cu" "*.Mask")
			(remove_unused_layers no)
			(net "LED_DR_LED2")
			(clearance 0.1651)
			(thermal_gap 0.1651)
		)
	)
	(footprint ""
		(layer "F.Cu")
		(at 4.040124 -306.660042 -90)
		(property "Reference" "CN3"
			(at 0 0 270)
			(layer "F.SilkS")
			(hide yes)
			(effects
				(font
					(size 1.27 1.27)
				)
			)
		)
		(property "Value" "JWT-CON5-42-GP"
			(at -7.8105 2.9591 270)
			(unlocked yes)
			(layer "F.Fab")
			(hide yes)
			(effects
				(font
					(size 1.016 1.016)
					(thickness 0.1524)
				)
			)
		)
		(property "Device Type" "A2541WR0-1TX5PA-6T-0E"
			(at -7.8105 1.4351 270)
			(unlocked yes)
			(layer "F.Fab")
			(hide yes)
			(effects
				(font
					(size 1.016 1.016)
					(thickness 0.1524)
				)
			)
		)
		(duplicate_pad_numbers_are_jumpers no)
		(fp_line
			(start -6.604 10.287)
			(end 6.604 10.287)
			(stroke
				(width 0.1524)
				(type default)
			)
			(layer "F.SilkS")
		)
		(fp_line
			(start 6.604 10.287)
			(end 6.604 -0.9652)
			(stroke
				(width 0.1524)
				(type default)
			)
			(layer "F.SilkS")
		)
		(fp_line
			(start -6.604 -0.9652)
			(end -6.604 10.287)
			(stroke
				(width 0.1524)
				(type default)
			)
			(layer "F.SilkS")
		)
		(fp_line
			(start 6.604 -0.9652)
			(end -6.604 -0.9652)
			(stroke
				(width 0.1524)
				(type default)
			)
			(layer "F.SilkS")
		)
		(fp_line
			(start -6.731 -1.0922)
			(end -6.731 0.1778)
			(stroke
				(width 0.4064)
				(type default)
			)
			(layer "F.SilkS")
		)
		(fp_line
			(start -5.461 -1.0922)
			(end -6.731 -1.0922)
			(stroke
				(width 0.4064)
				(type default)
			)
			(layer "F.SilkS")
		)
		(fp_circle
			(center -5.08 0)
			(end -5.08 -1.0668)
			(stroke
				(width 0.3048)
				(type default)
			)
			(fill no)
			(layer "F.SilkS")
		)
		(fp_circle
			(center -2.54 0)
			(end -2.54 -1.0668)
			(stroke
				(width 0.3048)
				(type default)
			)
			(fill no)
			(layer "F.SilkS")
		)
		(fp_circle
			(center 0 0)
			(end 0 -1.0668)
			(stroke
				(width 0.3048)
				(type default)
			)
			(fill no)
			(layer "F.SilkS")
		)
		(fp_circle
			(center 2.54 0)
			(end 2.54 -1.0668)
			(stroke
				(width 0.3048)
				(type default)
			)
			(fill no)
			(layer "F.SilkS")
		)
		(fp_circle
			(center 5.08 0)
			(end 5.08 -1.0668)
			(stroke
				(width 0.3048)
				(type default)
			)
			(fill no)
			(layer "F.SilkS")
		)
		(fp_rect
			(start -6.35 10.033)
			(end 6.35 -0.3302)
			(stroke
				(width 0)
				(type default)
			)
			(fill no)
			(layer "F.CrtYd")
		)
		(fp_poly
			(pts
				(xy -6.35 -0.3302) (xy 6.858 -0.3302) (xy 6.858 -1.2192) (xy -6.858 -1.2192) (xy -6.858 10.541)
				(xy 6.858 10.541) (xy 6.858 -0.3175) (xy 6.35 -0.3175) (xy 6.35 10.033) (xy -6.35 10.033)
			)
			(stroke
				(width 0)
				(type default)
			)
			(fill no)
			(layer "F.CrtYd")
		)
		(fp_rect
			(start -6.858 10.541)
			(end 6.858 -1.2192)
			(stroke
				(width 0)
				(type default)
			)
			(fill no)
			(layer "F.Fab")
		)
		(pad "1" thru_hole circle
			(at -5.08 0 270)
			(size 1.4224 1.4224)
			(drill 1.016)
			(layers "*.Cu" "*.Mask")
			(remove_unused_layers no)
			(net "GND")
			(clearance 0.1524)
			(thermal_gap 0.1524)
		)
		(pad "2" thru_hole circle
			(at -2.54 0 270)
			(size 1.4224 1.4224)
			(drill 1.016)
			(layers "*.Cu" "*.Mask")
			(remove_unused_layers no)
			(net "P12V_FAN3")
			(clearance 0.1524)
			(thermal_gap 0.1524)
		)
		(pad "3" thru_hole circle
			(at 0 0 270)
			(size 1.4224 1.4224)
			(drill 1.016)
			(layers "*.Cu" "*.Mask")
			(remove_unused_layers no)
			(net "FAN_TACH6")
			(clearance 0.1524)
			(thermal_gap 0.1524)
		)
		(pad "4" thru_hole circle
			(at 2.54 0 270)
			(size 1.4224 1.4224)
			(drill 1.016)
			(layers "*.Cu" "*.Mask")
			(remove_unused_layers no)
			(net "PWM_OUT_FAN3_NET")
			(clearance 0.1524)
			(thermal_gap 0.1524)
		)
		(pad "5" thru_hole circle
			(at 5.08 0 270)
			(size 1.4224 1.4224)
			(drill 1.016)
			(layers "*.Cu" "*.Mask")
			(remove_unused_layers no)
			(net "FAN_TACH5")
			(clearance 0.1524)
			(thermal_gap 0.1524)
		)
	)
	(footprint ""
		(layer "F.Cu")
		(at 11.9634 -232.7656 90)
		(property "Reference" "R34"
			(at 0 0 90)
			(layer "F.SilkS")
			(hide yes)
			(effects
				(font
					(size 1.27 1.27)
				)
			)
		)
		(property "Value" "0R2J-2-GP"
			(at 0.064008 -3.993896 90)
			(unlocked yes)
			(layer "F.Fab")
			(hide yes)
			(effects
				(font
					(size 1.016 1.016)
					(thickness 0.1524)
				)
			)
		)
		(property "Device Type" "R402H16"
			(at 0.064008 -5.517896 90)
			(unlocked yes)
			(layer "F.Fab")
			(hide yes)
			(effects
				(font
					(size 1.016 1.016)
					(thickness 0.1524)
				)
			)
		)
		(duplicate_pad_numbers_are_jumpers no)
		(fp_line
			(start 0.508 -0.9398)
			(end -0.508 -0.9398)
			(stroke
				(width 0.1524)
				(type default)
			)
			(layer "F.SilkS")
		)
		(fp_line
			(start -0.508 -0.9398)
			(end -0.508 0.9398)
			(stroke
				(width 0.1524)
				(type default)
			)
			(layer "F.SilkS")
		)
		(fp_rect
			(start -0.508 0.9398)
			(end 0.508 -0.9398)
			(stroke
				(width 0)
				(type default)
			)
			(fill no)
			(layer "F.CrtYd")
		)
		(fp_rect
			(start -0.508 0.9398)
			(end 0.508 -0.9398)
			(stroke
				(width 0)
				(type default)
			)
			(fill no)
			(layer "F.Fab")
		)
		(pad "1" smd custom
			(at 0 -0.4445 90)
			(size 0.1397 0.1397)
			(layers "F.Cu" "F.Mask" "F.Paste")
			(net "LED_DR_LED3_K")
			(options
				(clearance outline)
				(anchor circle)
			)
			(primitives
				(gr_poly
					(pts
						(arc
							(start -0.1778 -0.2794)
							(mid -0.249642 -0.249642)
							(end -0.2794 -0.1778)
						)
						(arc
							(start -0.2794 0.1778)
							(mid -0.249642 0.249642)
							(end -0.1778 0.2794)
						)
						(arc
							(start 0.1778 0.2794)
							(mid 0.249642 0.249642)
							(end 0.2794 0.1778)
						)
						(arc
							(start 0.2794 -0.1778)
							(mid 0.249642 -0.249642)
							(end 0.1778 -0.2794)
						)
					)
					(width 0)
					(fill yes)
				)
			)
		)
		(pad "2" smd custom
			(at 0 0.4445 90)
			(size 0.1397 0.1397)
			(layers "F.Cu" "F.Mask" "F.Paste")
			(net "GND")
			(options
				(clearance outline)
				(anchor circle)
			)
			(primitives
				(gr_poly
					(pts
						(arc
							(start -0.1778 -0.2794)
							(mid -0.249642 -0.249642)
							(end -0.2794 -0.1778)
						)
						(arc
							(start -0.2794 0.1778)
							(mid -0.249642 0.249642)
							(end -0.1778 0.2794)
						)
						(arc
							(start 0.1778 0.2794)
							(mid 0.249642 0.249642)
							(end 0.2794 0.1778)
						)
						(arc
							(start 0.2794 -0.1778)
							(mid 0.249642 -0.249642)
							(end 0.1778 -0.2794)
						)
					)
					(width 0)
					(fill yes)
				)
			)
		)
	)
	(footprint ""
		(layer "F.Cu")
		(at 19.558508 -288.594038)
		(property "Reference" "R103"
			(at 0 0 0)
			(layer "F.SilkS")
			(hide yes)
			(effects
				(font
					(size 1.27 1.27)
				)
			)
		)
		(property "Value" "10KR2F-2-GP"
			(at 0.064008 -3.993896 0)
			(unlocked yes)
			(layer "F.Fab")
			(hide yes)
			(effects
				(font
					(size 1.016 1.016)
					(thickness 0.1524)
				)
			)
		)
		(property "Device Type" "R402H16"
			(at 0.064008 -5.517896 0)
			(unlocked yes)
			(layer "F.Fab")
			(hide yes)
			(effects
				(font
					(size 1.016 1.016)
					(thickness 0.1524)
				)
			)
		)
		(duplicate_pad_numbers_are_jumpers no)
		(fp_line
			(start -0.508 -0.9398)
			(end -0.508 0.9398)
			(stroke
				(width 0.1524)
				(type default)
			)
			(layer "F.SilkS")
		)
		(fp_line
			(start 0.508 -0.9398)
			(end -0.508 -0.9398)
			(stroke
				(width 0.1524)
				(type default)
			)
			(layer "F.SilkS")
		)
		(fp_rect
			(start -0.508 0.9398)
			(end 0.508 -0.9398)
			(stroke
				(width 0)
				(type default)
			)
			(fill no)
			(layer "F.CrtYd")
		)
		(fp_rect
			(start -0.508 0.9398)
			(end 0.508 -0.9398)
			(stroke
				(width 0)
				(type default)
			)
			(fill no)
			(layer "F.Fab")
		)
		(pad "1" smd custom
			(at 0 -0.4445)
			(size 0.1397 0.1397)
			(layers "F.Cu" "F.Mask" "F.Paste")
			(net "FANIN_4")
			(options
				(clearance outline)
				(anchor circle)
			)
			(primitives
				(gr_poly
					(pts
						(arc
							(start -0.1778 -0.2794)
							(mid -0.249642 -0.249642)
							(end -0.2794 -0.1778)
						)
						(arc
							(start -0.2794 0.1778)
							(mid -0.249642 0.249642)
							(end -0.1778 0.2794)
						)
						(arc
							(start 0.1778 0.2794)
							(mid 0.249642 0.249642)
							(end 0.2794 0.1778)
						)
						(arc
							(start 0.2794 -0.1778)
							(mid 0.249642 -0.249642)
							(end 0.1778 -0.2794)
						)
					)
					(width 0)
					(fill yes)
				)
			)
		)
		(pad "2" smd custom
			(at 0 0.4445)
			(size 0.1397 0.1397)
			(layers "F.Cu" "F.Mask" "F.Paste")
			(net "GND")
			(options
				(clearance outline)
				(anchor circle)
			)
			(primitives
				(gr_poly
					(pts
						(arc
							(start -0.1778 -0.2794)
							(mid -0.249642 -0.249642)
							(end -0.2794 -0.1778)
						)
						(arc
							(start -0.2794 0.1778)
							(mid -0.249642 0.249642)
							(end -0.1778 0.2794)
						)
						(arc
							(start 0.1778 0.2794)
							(mid 0.249642 0.249642)
							(end 0.2794 0.1778)
						)
						(arc
							(start 0.2794 -0.1778)
							(mid 0.249642 -0.249642)
							(end 0.1778 -0.2794)
						)
					)
					(width 0)
					(fill yes)
				)
			)
		)
	)
	(footprint ""
		(layer "F.Cu")
		(at 14.8082 -66.4464 180)
		(property "Reference" "R150"
			(at 0 0 180)
			(layer "F.SilkS")
			(hide yes)
			(effects
				(font
					(size 1.27 1.27)
				)
			)
		)
		(property "Value" "10R2F-L-GP"
			(at 0.064008 -3.993896 180)
			(unlocked yes)
			(layer "F.Fab")
			(hide yes)
			(effects
				(font
					(size 1.016 1.016)
					(thickness 0.1524)
				)
			)
		)
		(property "Device Type" "R402H14"
			(at 0.064008 -5.517896 180)
			(unlocked yes)
			(layer "F.Fab")
			(hide yes)
			(effects
				(font
					(size 1.016 1.016)
					(thickness 0.1524)
				)
			)
		)
		(duplicate_pad_numbers_are_jumpers no)
		(fp_line
			(start 0.508 -0.9398)
			(end -0.508 -0.9398)
			(stroke
				(width 0.1524)
				(type default)
			)
			(layer "F.SilkS")
		)
		(fp_line
			(start -0.508 -0.9398)
			(end -0.508 0.9398)
			(stroke
				(width 0.1524)
				(type default)
			)
			(layer "F.SilkS")
		)
		(fp_rect
			(start -0.508 0.9398)
			(end 0.508 -0.9398)
			(stroke
				(width 0)
				(type default)
			)
			(fill no)
			(layer "F.CrtYd")
		)
		(fp_rect
			(start -0.508 0.9398)
			(end 0.508 -0.9398)
			(stroke
				(width 0)
				(type default)
			)
			(fill no)
			(layer "F.Fab")
		)
		(pad "1" smd custom
			(at 0 -0.4445 180)
			(size 0.1397 0.1397)
			(layers "F.Cu" "F.Mask" "F.Paste")
			(net "I2C_C_SDA_CONN_R")
			(options
				(clearance outline)
				(anchor circle)
			)
			(primitives
				(gr_poly
					(pts
						(arc
							(start -0.1778 -0.2794)
							(mid -0.249642 -0.249642)
							(end -0.2794 -0.1778)
						)
						(arc
							(start -0.2794 0.1778)
							(mid -0.249642 0.249642)
							(end -0.1778 0.2794)
						)
						(arc
							(start 0.1778 0.2794)
							(mid 0.249642 0.249642)
							(end 0.2794 0.1778)
						)
						(arc
							(start 0.2794 -0.1778)
							(mid 0.249642 -0.249642)
							(end 0.1778 -0.2794)
						)
					)
					(width 0)
					(fill yes)
				)
			)
		)
		(pad "2" smd custom
			(at 0 0.4445 180)
			(size 0.1397 0.1397)
			(layers "F.Cu" "F.Mask" "F.Paste")
			(net "I2C_C_SDA")
			(options
				(clearance outline)
				(anchor circle)
			)
			(primitives
				(gr_poly
					(pts
						(arc
							(start -0.1778 -0.2794)
							(mid -0.249642 -0.249642)
							(end -0.2794 -0.1778)
						)
						(arc
							(start -0.2794 0.1778)
							(mid -0.249642 0.249642)
							(end -0.1778 0.2794)
						)
						(arc
							(start 0.1778 0.2794)
							(mid 0.249642 0.249642)
							(end 0.2794 0.1778)
						)
						(arc
							(start 0.2794 -0.1778)
							(mid 0.249642 -0.249642)
							(end 0.1778 -0.2794)
						)
					)
					(width 0)
					(fill yes)
				)
			)
		)
	)
	(footprint ""
		(layer "F.Cu")
		(at 43.815 -389.001 90)
		(property "Reference" "TC9"
			(at 0 0 90)
			(layer "F.SilkS")
			(hide yes)
			(effects
				(font
					(size 1.27 1.27)
				)
			)
		)
		(property "Value" "ST68U16VDM-1-GP"
			(at 0 -9.6012 90)
			(unlocked yes)
			(layer "F.Fab")
			(hide yes)
			(effects
				(font
					(size 1.016 1.016)
					(thickness 0.1524)
				)
			)
		)
		(property "Device Type" "CT7343H79"
			(at 0 -11.1252 90)
			(unlocked yes)
			(layer "F.Fab")
			(hide yes)
			(effects
				(font
					(size 1.016 1.016)
					(thickness 0.1524)
				)
			)
		)
		(duplicate_pad_numbers_are_jumpers no)
		(fp_line
			(start 2.286 -4.8768)
			(end -2.286 -4.8768)
			(stroke
				(width 0.1524)
				(type default)
			)
			(layer "F.SilkS")
		)
		(fp_line
			(start -2.286 -4.8768)
			(end -2.286 -2.032)
			(stroke
				(width 0.1524)
				(type default)
			)
			(layer "F.SilkS")
		)
		(fp_line
			(start 2.1082 -4.699)
			(end -2.1082 -4.699)
			(stroke
				(width 0.508)
				(type default)
			)
			(layer "F.SilkS")
		)
		(fp_line
			(start 2.286 -2.032)
			(end 2.286 -4.8768)
			(stroke
				(width 0.1524)
				(type default)
			)
			(layer "F.SilkS")
		)
		(fp_line
			(start 2.286 2.032)
			(end 2.286 4.8768)
			(stroke
				(width 0.1524)
				(type default)
			)
			(layer "F.SilkS")
		)
		(fp_line
			(start 2.286 4.8768)
			(end -2.286 4.8768)
			(stroke
				(width 0.1524)
				(type default)
			)
			(layer "F.SilkS")
		)
		(fp_line
			(start -2.286 4.8768)
			(end -2.286 2.032)
			(stroke
				(width 0.1524)
				(type default)
			)
			(layer "F.SilkS")
		)
		(fp_rect
			(start -2.1463 3.6449)
			(end 2.1463 -3.6449)
			(stroke
				(width 0)
				(type default)
			)
			(fill no)
			(layer "F.CrtYd")
		)
		(fp_poly
			(pts
				(xy -2.54 4.953) (xy -2.54 4.2926) (xy -3.81 4.2926) (xy -3.81 -4.2926) (xy -2.54 -4.2926) (xy -2.54 -4.953)
				(xy 2.54 -4.953) (xy 2.54 -4.2926) (xy 3.81 -4.2926) (xy 3.81 -1.6256) (xy 2.1463 -1.6256) (xy 2.1463 -3.6449)
				(xy -2.1463 -3.6449) (xy -2.1463 3.6449) (xy 2.1463 3.6449) (xy 2.1463 -1.6129) (xy 3.81 -1.6129)
				(xy 3.81 4.2926) (xy 2.54 4.2926) (xy 2.54 4.953)
			)
			(stroke
				(width 0)
				(type default)
			)
			(fill no)
			(layer "F.CrtYd")
		)
		(fp_rect
			(start 2.54 4.2926)
			(end 3.81 -4.2926)
			(stroke
				(width 0)
				(type default)
			)
			(fill no)
			(layer "F.Fab")
		)
		(fp_rect
			(start -3.81 4.2926)
			(end -2.54 -4.2926)
			(stroke
				(width 0)
				(type default)
			)
			(fill no)
			(layer "F.Fab")
		)
		(fp_rect
			(start -2.54 4.953)
			(end 2.54 -4.953)
			(stroke
				(width 0)
				(type default)
			)
			(fill no)
			(layer "F.Fab")
		)
		(pad "1" smd rect
			(at 0 -3.1496 90)
			(size 2.413 2.286)
			(layers "F.Cu" "F.Mask" "F.Paste")
			(net "P12V")
		)
		(pad "2" smd rect
			(at 0 3.1496 90)
			(size 2.413 2.286)
			(layers "F.Cu" "F.Mask" "F.Paste")
			(net "GND")
		)
		(zone
			(layer "F.Cu")
			(hatch none 0.5)
			(connect_pads
				(clearance 0)
			)
			(min_thickness 0.25)
			(keepout
				(tracks allowed)
				(vias not_allowed)
				(pads allowed)
				(copperpour not_allowed)
				(footprints allowed)
			)
			(placement
				(enabled no)
				(sheetname "")
			)
			(fill
				(thermal_gap 0.5)
				(thermal_bridge_width 0.5)
				(island_removal_mode 0)
			)
			(polygon
				(pts
					(xy 42.1259 -390.5123) (xy 39.2176 -390.5123) (xy 39.2176 -387.4897) (xy 42.1132 -387.4897) (xy 42.4434 -387.4897)
					(xy 42.4434 -390.5123)
				)
			)
		)
		(zone
			(layer "F.Cu")
			(hatch none 0.5)
			(connect_pads
				(clearance 0)
			)
			(min_thickness 0.25)
			(keepout
				(tracks allowed)
				(vias not_allowed)
				(pads allowed)
				(copperpour not_allowed)
				(footprints allowed)
			)
			(placement
				(enabled no)
				(sheetname "")
			)
			(fill
				(thermal_gap 0.5)
				(thermal_bridge_width 0.5)
				(island_removal_mode 0)
			)
			(polygon
				(pts
					(xy 48.4124 -387.4897) (xy 48.4124 -390.5123) (xy 45.5168 -390.5123) (xy 45.1866 -390.5123) (xy 45.1866 -387.4897)
					(xy 45.5168 -387.4897)
				)
			)
		)
	)
	(footprint ""
		(layer "F.Cu")
		(at 5.1054 -437.0578 90)
		(property "Reference" "R121"
			(at 0 0 90)
			(layer "F.SilkS")
			(hide yes)
			(effects
				(font
					(size 1.27 1.27)
				)
			)
		)
		(property "Value" "2KR2F-3-GP"
			(at 0.064008 -3.993896 90)
			(unlocked yes)
			(layer "F.Fab")
			(hide yes)
			(effects
				(font
					(size 1.016 1.016)
					(thickness 0.1524)
				)
			)
		)
		(property "Device Type" "R402H16"
			(at 0.064008 -5.517896 90)
			(unlocked yes)
			(layer "F.Fab")
			(hide yes)
			(effects
				(font
					(size 1.016 1.016)
					(thickness 0.1524)
				)
			)
		)
		(duplicate_pad_numbers_are_jumpers no)
		(fp_line
			(start 0.508 -0.9398)
			(end -0.508 -0.9398)
			(stroke
				(width 0.1524)
				(type default)
			)
			(layer "F.SilkS")
		)
		(fp_line
			(start -0.508 -0.9398)
			(end -0.508 0.9398)
			(stroke
				(width 0.1524)
				(type default)
			)
			(layer "F.SilkS")
		)
		(fp_rect
			(start -0.508 0.9398)
			(end 0.508 -0.9398)
			(stroke
				(width 0)
				(type default)
			)
			(fill no)
			(layer "F.CrtYd")
		)
		(fp_rect
			(start -0.508 0.9398)
			(end 0.508 -0.9398)
			(stroke
				(width 0)
				(type default)
			)
			(fill no)
			(layer "F.Fab")
		)
		(pad "1" smd custom
			(at 0 -0.4445 90)
			(size 0.1397 0.1397)
			(layers "F.Cu" "F.Mask" "F.Paste")
			(net "LED_DR_LED0")
			(options
				(clearance outline)
				(anchor circle)
			)
			(primitives
				(gr_poly
					(pts
						(arc
							(start -0.1778 -0.2794)
							(mid -0.249642 -0.249642)
							(end -0.2794 -0.1778)
						)
						(arc
							(start -0.2794 0.1778)
							(mid -0.249642 0.249642)
							(end -0.1778 0.2794)
						)
						(arc
							(start 0.1778 0.2794)
							(mid 0.249642 0.249642)
							(end 0.2794 0.1778)
						)
						(arc
							(start 0.2794 -0.1778)
							(mid 0.249642 -0.249642)
							(end 0.1778 -0.2794)
						)
					)
					(width 0)
					(fill yes)
				)
			)
		)
		(pad "2" smd custom
			(at 0 0.4445 90)
			(size 0.1397 0.1397)
			(layers "F.Cu" "F.Mask" "F.Paste")
			(net "LED_DR_LED0_B")
			(options
				(clearance outline)
				(anchor circle)
			)
			(primitives
				(gr_poly
					(pts
						(arc
							(start -0.1778 -0.2794)
							(mid -0.249642 -0.249642)
							(end -0.2794 -0.1778)
						)
						(arc
							(start -0.2794 0.1778)
							(mid -0.249642 0.249642)
							(end -0.1778 0.2794)
						)
						(arc
							(start 0.1778 0.2794)
							(mid 0.249642 0.249642)
							(end 0.2794 0.1778)
						)
						(arc
							(start 0.2794 -0.1778)
							(mid 0.249642 -0.249642)
							(end 0.1778 -0.2794)
						)
					)
					(width 0)
					(fill yes)
				)
			)
		)
	)
	(footprint ""
		(layer "F.Cu")
		(at 44.069 -178.0794 90)
		(property "Reference" "R270"
			(at 0 0 90)
			(layer "F.SilkS")
			(hide yes)
			(effects
				(font
					(size 1.27 1.27)
				)
			)
		)
		(property "Value" "0R2J-2-GP"
			(at 0.064008 -3.993896 90)
			(unlocked yes)
			(layer "F.Fab")
			(hide yes)
			(effects
				(font
					(size 1.016 1.016)
					(thickness 0.1524)
				)
			)
		)
		(property "Device Type" "R402H16"
			(at 0.064008 -5.517896 90)
			(unlocked yes)
			(layer "F.Fab")
			(hide yes)
			(effects
				(font
					(size 1.016 1.016)
					(thickness 0.1524)
				)
			)
		)
		(duplicate_pad_numbers_are_jumpers no)
		(fp_line
			(start 0.508 -0.9398)
			(end -0.508 -0.9398)
			(stroke
				(width 0.1524)
				(type default)
			)
			(layer "F.SilkS")
		)
		(fp_line
			(start -0.508 -0.9398)
			(end -0.508 0.9398)
			(stroke
				(width 0.1524)
				(type default)
			)
			(layer "F.SilkS")
		)
		(fp_rect
			(start -0.508 0.9398)
			(end 0.508 -0.9398)
			(stroke
				(width 0)
				(type default)
			)
			(fill no)
			(layer "F.CrtYd")
		)
		(fp_rect
			(start -0.508 0.9398)
			(end 0.508 -0.9398)
			(stroke
				(width 0)
				(type default)
			)
			(fill no)
			(layer "F.Fab")
		)
		(pad "1" smd custom
			(at 0 -0.4445 90)
			(size 0.1397 0.1397)
			(layers "F.Cu" "F.Mask" "F.Paste")
			(net "D_LATCH_Q")
			(options
				(clearance outline)
				(anchor circle)
			)
			(primitives
				(gr_poly
					(pts
						(arc
							(start -0.1778 -0.2794)
							(mid -0.249642 -0.249642)
							(end -0.2794 -0.1778)
						)
						(arc
							(start -0.2794 0.1778)
							(mid -0.249642 0.249642)
							(end -0.1778 0.2794)
						)
						(arc
							(start 0.1778 0.2794)
							(mid 0.249642 0.249642)
							(end 0.2794 0.1778)
						)
						(arc
							(start 0.2794 -0.1778)
							(mid 0.249642 -0.249642)
							(end 0.1778 -0.2794)
						)
					)
					(width 0)
					(fill yes)
				)
			)
		)
		(pad "2" smd custom
			(at 0 0.4445 90)
			(size 0.1397 0.1397)
			(layers "F.Cu" "F.Mask" "F.Paste")
			(net "ADM1276_EN")
			(options
				(clearance outline)
				(anchor circle)
			)
			(primitives
				(gr_poly
					(pts
						(arc
							(start -0.1778 -0.2794)
							(mid -0.249642 -0.249642)
							(end -0.2794 -0.1778)
						)
						(arc
							(start -0.2794 0.1778)
							(mid -0.249642 0.249642)
							(end -0.1778 0.2794)
						)
						(arc
							(start 0.1778 0.2794)
							(mid 0.249642 0.249642)
							(end 0.2794 0.1778)
						)
						(arc
							(start 0.2794 -0.1778)
							(mid 0.249642 -0.249642)
							(end 0.1778 -0.2794)
						)
					)
					(width 0)
					(fill yes)
				)
			)
		)
	)
	(footprint ""
		(layer "F.Cu")
		(at 5.1562 -417.6522 90)
		(property "Reference" "R27"
			(at 0 0 90)
			(layer "F.SilkS")
			(hide yes)
			(effects
				(font
					(size 1.27 1.27)
				)
			)
		)
		(property "Value" "33R2F-3-GP"
			(at 0.064008 -3.993896 90)
			(unlocked yes)
			(layer "F.Fab")
			(hide yes)
			(effects
				(font
					(size 1.016 1.016)
					(thickness 0.1524)
				)
			)
		)
		(property "Device Type" "R402H16"
			(at 0.064008 -5.517896 90)
			(unlocked yes)
			(layer "F.Fab")
			(hide yes)
			(effects
				(font
					(size 1.016 1.016)
					(thickness 0.1524)
				)
			)
		)
		(duplicate_pad_numbers_are_jumpers no)
		(fp_line
			(start 0.508 -0.9398)
			(end -0.508 -0.9398)
			(stroke
				(width 0.1524)
				(type default)
			)
			(layer "F.SilkS")
		)
		(fp_line
			(start -0.508 -0.9398)
			(end -0.508 0.9398)
			(stroke
				(width 0.1524)
				(type default)
			)
			(layer "F.SilkS")
		)
		(fp_rect
			(start -0.508 0.9398)
			(end 0.508 -0.9398)
			(stroke
				(width 0)
				(type default)
			)
			(fill no)
			(layer "F.CrtYd")
		)
		(fp_rect
			(start -0.508 0.9398)
			(end 0.508 -0.9398)
			(stroke
				(width 0)
				(type default)
			)
			(fill no)
			(layer "F.Fab")
		)
		(pad "1" smd custom
			(at 0 -0.4445 90)
			(size 0.1397 0.1397)
			(layers "F.Cu" "F.Mask" "F.Paste")
			(net "P3V3")
			(options
				(clearance outline)
				(anchor circle)
			)
			(primitives
				(gr_poly
					(pts
						(arc
							(start -0.1778 -0.2794)
							(mid -0.249642 -0.249642)
							(end -0.2794 -0.1778)
						)
						(arc
							(start -0.2794 0.1778)
							(mid -0.249642 0.249642)
							(end -0.1778 0.2794)
						)
						(arc
							(start 0.1778 0.2794)
							(mid 0.249642 0.249642)
							(end 0.2794 0.1778)
						)
						(arc
							(start 0.2794 -0.1778)
							(mid 0.249642 -0.249642)
							(end 0.1778 -0.2794)
						)
					)
					(width 0)
					(fill yes)
				)
			)
		)
		(pad "2" smd custom
			(at 0 0.4445 90)
			(size 0.1397 0.1397)
			(layers "F.Cu" "F.Mask" "F.Paste")
			(net "LED_DR_LED1_BLUE")
			(options
				(clearance outline)
				(anchor circle)
			)
			(primitives
				(gr_poly
					(pts
						(arc
							(start -0.1778 -0.2794)
							(mid -0.249642 -0.249642)
							(end -0.2794 -0.1778)
						)
						(arc
							(start -0.2794 0.1778)
							(mid -0.249642 0.249642)
							(end -0.1778 0.2794)
						)
						(arc
							(start 0.1778 0.2794)
							(mid 0.249642 0.249642)
							(end 0.2794 0.1778)
						)
						(arc
							(start 0.2794 -0.1778)
							(mid 0.249642 -0.249642)
							(end 0.1778 -0.2794)
						)
					)
					(width 0)
					(fill yes)
				)
			)
		)
	)
	(footprint ""
		(layer "F.Cu")
		(at 12.2428 -55.2196 -90)
		(property "Reference" "R63"
			(at 0 0 270)
			(layer "F.SilkS")
			(hide yes)
			(effects
				(font
					(size 1.27 1.27)
				)
			)
		)
		(property "Value" "0R2J-2-GP"
			(at 0.064008 -3.993896 270)
			(unlocked yes)
			(layer "F.Fab")
			(hide yes)
			(effects
				(font
					(size 1.016 1.016)
					(thickness 0.1524)
				)
			)
		)
		(property "Device Type" "R402H16"
			(at 0.064008 -5.517896 270)
			(unlocked yes)
			(layer "F.Fab")
			(hide yes)
			(effects
				(font
					(size 1.016 1.016)
					(thickness 0.1524)
				)
			)
		)
		(duplicate_pad_numbers_are_jumpers no)
		(fp_line
			(start -0.508 -0.9398)
			(end -0.508 0.9398)
			(stroke
				(width 0.1524)
				(type default)
			)
			(layer "F.SilkS")
		)
		(fp_line
			(start 0.508 -0.9398)
			(end -0.508 -0.9398)
			(stroke
				(width 0.1524)
				(type default)
			)
			(layer "F.SilkS")
		)
		(fp_rect
			(start -0.508 0.9398)
			(end 0.508 -0.9398)
			(stroke
				(width 0)
				(type default)
			)
			(fill no)
			(layer "F.CrtYd")
		)
		(fp_rect
			(start -0.508 0.9398)
			(end 0.508 -0.9398)
			(stroke
				(width 0)
				(type default)
			)
			(fill no)
			(layer "F.Fab")
		)
		(pad "1" smd custom
			(at 0 -0.4445 270)
			(size 0.1397 0.1397)
			(layers "F.Cu" "F.Mask" "F.Paste")
			(net "SELF_TRAY_PRESENT_LOWER")
			(options
				(clearance outline)
				(anchor circle)
			)
			(primitives
				(gr_poly
					(pts
						(arc
							(start -0.1778 -0.2794)
							(mid -0.249642 -0.249642)
							(end -0.2794 -0.1778)
						)
						(arc
							(start -0.2794 0.1778)
							(mid -0.249642 0.249642)
							(end -0.1778 0.2794)
						)
						(arc
							(start 0.1778 0.2794)
							(mid 0.249642 0.249642)
							(end 0.2794 0.1778)
						)
						(arc
							(start 0.2794 -0.1778)
							(mid 0.249642 -0.249642)
							(end 0.1778 -0.2794)
						)
					)
					(width 0)
					(fill yes)
				)
			)
		)
		(pad "2" smd custom
			(at 0 0.4445 270)
			(size 0.1397 0.1397)
			(layers "F.Cu" "F.Mask" "F.Paste")
			(net "PEER_TRAY PRESENT_UPPER")
			(options
				(clearance outline)
				(anchor circle)
			)
			(primitives
				(gr_poly
					(pts
						(arc
							(start -0.1778 -0.2794)
							(mid -0.249642 -0.249642)
							(end -0.2794 -0.1778)
						)
						(arc
							(start -0.2794 0.1778)
							(mid -0.249642 0.249642)
							(end -0.1778 0.2794)
						)
						(arc
							(start 0.1778 0.2794)
							(mid 0.249642 0.249642)
							(end 0.2794 0.1778)
						)
						(arc
							(start 0.2794 -0.1778)
							(mid 0.249642 -0.249642)
							(end 0.1778 -0.2794)
						)
					)
					(width 0)
					(fill yes)
				)
			)
		)
	)
	(footprint ""
		(layer "F.Cu")
		(at 27.500072 -144.999964 90)
		(property "Reference" "Q1"
			(at 0 0 90)
			(layer "F.SilkS")
			(hide yes)
			(effects
				(font
					(size 1.27 1.27)
				)
			)
		)
		(property "Value" "PMBS3904-1-GP"
			(at 0 -9.0932 90)
			(unlocked yes)
			(layer "F.Fab")
			(hide yes)
			(effects
				(font
					(size 1.016 1.016)
					(thickness 0.1524)
				)
			)
		)
		(property "Device Type" "SOT-23-10H44"
			(at 0 -10.6172 90)
			(unlocked yes)
			(layer "F.Fab")
			(hide yes)
			(effects
				(font
					(size 1.016 1.016)
					(thickness 0.1524)
				)
			)
		)
		(duplicate_pad_numbers_are_jumpers no)
		(fp_line
			(start 1.651 -1.778)
			(end -1.651 -1.778)
			(stroke
				(width 0.1524)
				(type default)
			)
			(layer "F.SilkS")
		)
		(fp_line
			(start -1.651 -1.778)
			(end -1.651 1.778)
			(stroke
				(width 0.1524)
				(type default)
			)
			(layer "F.SilkS")
		)
		(fp_line
			(start 1.651 1.778)
			(end 1.651 -1.778)
			(stroke
				(width 0.1524)
				(type default)
			)
			(layer "F.SilkS")
		)
		(fp_line
			(start -1.651 1.778)
			(end 1.651 1.778)
			(stroke
				(width 0.1524)
				(type default)
			)
			(layer "F.SilkS")
		)
		(fp_line
			(start -0.9906 1.86309)
			(end -0.701294 2.15265)
			(stroke
				(width 0.0127)
				(type default)
			)
			(layer "F.SilkS")
		)
		(fp_line
			(start -0.994156 1.8669)
			(end -0.987044 1.8669)
			(stroke
				(width 0.0127)
				(type default)
			)
			(layer "F.SilkS")
		)
		(fp_line
			(start -1.003808 1.876552)
			(end -0.977646 1.876552)
			(stroke
				(width 0.0127)
				(type default)
			)
			(layer "F.SilkS")
		)
		(fp_line
			(start -0.635 1.8796)
			(end -1.7526 1.8796)
			(stroke
				(width 0.3302)
				(type default)
			)
			(layer "F.SilkS")
		)
		(fp_line
			(start -1.7526 1.8796)
			(end -1.7526 0.9906)
			(stroke
				(width 0.3302)
				(type default)
			)
			(layer "F.SilkS")
		)
		(fp_line
			(start -1.013206 1.88595)
			(end -0.967994 1.88595)
			(stroke
				(width 0.0127)
				(type default)
			)
			(layer "F.SilkS")
		)
		(fp_line
			(start -1.022858 1.895602)
			(end -0.958596 1.895602)
			(stroke
				(width 0.0127)
				(type default)
			)
			(layer "F.SilkS")
		)
		(fp_line
			(start -1.032256 1.905)
			(end -0.948944 1.905)
			(stroke
				(width 0.0127)
				(type default)
			)
			(layer "F.SilkS")
		)
		(fp_line
			(start -1.041908 1.914652)
			(end -0.939546 1.914652)
			(stroke
				(width 0.0127)
				(type default)
			)
			(layer "F.SilkS")
		)
		(fp_line
			(start -1.051306 1.92405)
			(end -0.929894 1.92405)
			(stroke
				(width 0.0127)
				(type default)
			)
			(layer "F.SilkS")
		)
		(fp_line
			(start -1.060958 1.933702)
			(end -0.920496 1.933702)
			(stroke
				(width 0.0127)
				(type default)
			)
			(layer "F.SilkS")
		)
		(fp_line
			(start -1.070356 1.9431)
			(end -0.910844 1.9431)
			(stroke
				(width 0.0127)
				(type default)
			)
			(layer "F.SilkS")
		)
		(fp_line
			(start -1.080008 1.952752)
			(end -0.901446 1.952752)
			(stroke
				(width 0.0127)
				(type default)
			)
			(layer "F.SilkS")
		)
		(fp_line
			(start -1.089406 1.96215)
			(end -0.891794 1.96215)
			(stroke
				(width 0.0127)
				(type default)
			)
			(layer "F.SilkS")
		)
		(fp_line
			(start -1.099058 1.971802)
			(end -0.882396 1.971802)
			(stroke
				(width 0.0127)
				(type default)
			)
			(layer "F.SilkS")
		)
		(fp_line
			(start -1.108456 1.9812)
			(end -0.872744 1.9812)
			(stroke
				(width 0.0127)
				(type default)
			)
			(layer "F.SilkS")
		)
		(fp_line
			(start -1.118108 1.990852)
			(end -0.863346 1.990852)
			(stroke
				(width 0.0127)
				(type default)
			)
			(layer "F.SilkS")
		)
		(fp_line
			(start -1.127506 2.00025)
			(end -0.853694 2.00025)
			(stroke
				(width 0.0127)
				(type default)
			)
			(layer "F.SilkS")
		)
		(fp_line
			(start -1.137158 2.009902)
			(end -0.844296 2.009902)
			(stroke
				(width 0.0127)
				(type default)
			)
			(layer "F.SilkS")
		)
		(fp_line
			(start -1.146556 2.0193)
			(end -0.834644 2.0193)
			(stroke
				(width 0.0127)
				(type default)
			)
			(layer "F.SilkS")
		)
		(fp_line
			(start -1.156208 2.028952)
			(end -0.825246 2.028952)
			(stroke
				(width 0.0127)
				(type default)
			)
			(layer "F.SilkS")
		)
		(fp_line
			(start -1.165606 2.03835)
			(end -0.815594 2.03835)
			(stroke
				(width 0.0127)
				(type default)
			)
			(layer "F.SilkS")
		)
		(fp_line
			(start -1.175258 2.048002)
			(end -0.806196 2.048002)
			(stroke
				(width 0.0127)
				(type default)
			)
			(layer "F.SilkS")
		)
		(fp_line
			(start -1.184656 2.0574)
			(end -0.796544 2.0574)
			(stroke
				(width 0.0127)
				(type default)
			)
			(layer "F.SilkS")
		)
		(fp_line
			(start -1.194308 2.067052)
			(end -0.787146 2.067052)
			(stroke
				(width 0.0127)
				(type default)
			)
			(layer "F.SilkS")
		)
		(fp_line
			(start -1.203706 2.07645)
			(end -0.777494 2.07645)
			(stroke
				(width 0.0127)
				(type default)
			)
			(layer "F.SilkS")
		)
		(fp_line
			(start -1.213358 2.086102)
			(end -0.768096 2.086102)
			(stroke
				(width 0.0127)
				(type default)
			)
			(layer "F.SilkS")
		)
		(fp_line
			(start -1.222756 2.0955)
			(end -0.758444 2.0955)
			(stroke
				(width 0.0127)
				(type default)
			)
			(layer "F.SilkS")
		)
		(fp_line
			(start -1.232408 2.105152)
			(end -0.749046 2.105152)
			(stroke
				(width 0.0127)
				(type default)
			)
			(layer "F.SilkS")
		)
		(fp_line
			(start -1.241806 2.11455)
			(end -0.739394 2.11455)
			(stroke
				(width 0.0127)
				(type default)
			)
			(layer "F.SilkS")
		)
		(fp_line
			(start -1.251458 2.124202)
			(end -0.729996 2.124202)
			(stroke
				(width 0.0127)
				(type default)
			)
			(layer "F.SilkS")
		)
		(fp_line
			(start -1.260856 2.1336)
			(end -0.720344 2.1336)
			(stroke
				(width 0.0127)
				(type default)
			)
			(layer "F.SilkS")
		)
		(fp_line
			(start -0.719074 2.145538)
			(end -1.265936 2.14122)
			(stroke
				(width 0.0127)
				(type default)
			)
			(layer "F.SilkS")
		)
		(fp_line
			(start -1.279398 2.152142)
			(end -0.9906 1.86309)
			(stroke
				(width 0.0127)
				(type default)
			)
			(layer "F.SilkS")
		)
		(fp_line
			(start -0.71628 2.15265)
			(end -1.26492 2.15265)
			(stroke
				(width 0.0127)
				(type default)
			)
			(layer "F.SilkS")
		)
		(fp_line
			(start -1.279144 2.15265)
			(end -0.701294 2.15265)
			(stroke
				(width 0.0127)
				(type default)
			)
			(layer "F.SilkS")
		)
		(fp_poly
			(pts
				(xy -1.285748 2.159) (xy -1.285748 1.8796) (xy -1.778 1.8796) (xy -1.778 -1.8796) (xy 1.778 -1.8796)
				(xy 1.778 1.8796) (xy -0.694944 1.8796) (xy -0.694944 2.159)
			)
			(stroke
				(width 0)
				(type default)
			)
			(fill no)
			(layer "F.CrtYd")
		)
		(fp_poly
			(pts
				(xy -1.285748 2.159) (xy -1.285748 1.8796) (xy -1.778 1.8796) (xy -1.778 -1.8796) (xy 1.778 -1.8796)
				(xy 1.778 1.8796) (xy -0.694944 1.8796) (xy -0.694944 2.159)
			)
			(stroke
				(width 0)
				(type default)
			)
			(fill no)
			(layer "F.Fab")
		)
		(pad "1" smd rect
			(at -0.98425 0.9525 90)
			(size 0.762 1.143)
			(layers "F.Cu" "F.Mask" "F.Paste")
			(net "NCT7904_D1+")
		)
		(pad "2" smd rect
			(at 0.98425 0.9525 90)
			(size 0.762 1.143)
			(layers "F.Cu" "F.Mask" "F.Paste")
			(net "NCT7904_D1-")
		)
		(pad "3" smd rect
			(at 0 -0.9525 90)
			(size 0.762 1.143)
			(layers "F.Cu" "F.Mask" "F.Paste")
			(net "NCT7904_D1+")
		)
	)
	(footprint ""
		(layer "F.Cu")
		(at 32.004 -180.467 90)
		(property "Reference" "D13"
			(at 0 0 90)
			(layer "F.SilkS")
			(hide yes)
			(effects
				(font
					(size 1.27 1.27)
				)
			)
		)
		(property "Value" "BZG05C3V9-GP"
			(at 0.027178 -8.482076 90)
			(unlocked yes)
			(layer "F.Fab")
			(hide yes)
			(effects
				(font
					(size 1.016 1.016)
					(thickness 0.1524)
				)
			)
		)
		(property "Device Type" "D5226155AKH91"
			(at 0.027178 -10.006076 90)
			(unlocked yes)
			(layer "F.Fab")
			(hide yes)
			(effects
				(font
					(size 1.016 1.016)
					(thickness 0.1524)
				)
			)
		)
		(duplicate_pad_numbers_are_jumpers no)
		(fp_line
			(start 1.524 -3.4798)
			(end -1.524 -3.4798)
			(stroke
				(width 0.1524)
				(type default)
			)
			(layer "F.SilkS")
		)
		(fp_line
			(start -1.524 -3.4798)
			(end -1.524 3.4798)
			(stroke
				(width 0.1524)
				(type default)
			)
			(layer "F.SilkS")
		)
		(fp_line
			(start 1.524 3.4798)
			(end 1.524 -3.4798)
			(stroke
				(width 0.1524)
				(type default)
			)
			(layer "F.SilkS")
		)
		(fp_line
			(start -1.524 3.4798)
			(end 1.524 3.4798)
			(stroke
				(width 0.1524)
				(type default)
			)
			(layer "F.SilkS")
		)
		(fp_line
			(start -1.524 3.6576)
			(end 1.524 3.6576)
			(stroke
				(width 0.508)
				(type default)
			)
			(layer "F.SilkS")
		)
		(fp_rect
			(start -1.27 2.6035)
			(end 1.27 -2.6035)
			(stroke
				(width 0)
				(type default)
			)
			(fill no)
			(layer "F.CrtYd")
		)
		(fp_poly
			(pts
				(xy 1.778 -0.2921) (xy 1.27 -0.2921) (xy 1.27 -2.6035) (xy -1.27 -2.6035) (xy -1.27 2.6035) (xy 1.27 2.6035)
				(xy 1.27 -0.2794) (xy 1.778 -0.2794) (xy 1.778 3.556) (xy -1.778 3.556) (xy -1.778 -3.556) (xy 1.778 -3.556)
			)
			(stroke
				(width 0)
				(type default)
			)
			(fill no)
			(layer "F.CrtYd")
		)
		(fp_rect
			(start -1.778 3.556)
			(end 1.778 -3.556)
			(stroke
				(width 0)
				(type default)
			)
			(fill no)
			(layer "F.Fab")
		)
		(pad "A" smd rect
			(at 0 -2.212086 90)
			(size 1.8034 2.032)
			(layers "F.Cu" "F.Mask" "F.Paste")
			(net "GND")
		)
		(pad "K" smd rect
			(at 0 2.212086 90)
			(size 1.8034 2.032)
			(layers "F.Cu" "F.Mask" "F.Paste")
			(net "P3V3_AUX_BJT_B")
		)
	)
	(footprint ""
		(layer "F.Cu")
		(at 22.352 -188.0616 90)
		(property "Reference" "D6"
			(at 0 0 90)
			(layer "F.SilkS")
			(hide yes)
			(effects
				(font
					(size 1.27 1.27)
				)
			)
		)
		(property "Value" "BAS16H-GP"
			(at 0 -5.5372 90)
			(unlocked yes)
			(layer "F.Fab")
			(hide yes)
			(effects
				(font
					(size 1.016 1.016)
					(thickness 0.1524)
				)
			)
		)
		(property "Device Type" "SOD123AKH48"
			(at 0 -7.0612 90)
			(unlocked yes)
			(layer "F.Fab")
			(hide yes)
			(effects
				(font
					(size 1.016 1.016)
					(thickness 0.1524)
				)
			)
		)
		(duplicate_pad_numbers_are_jumpers no)
		(fp_line
			(start 1.016 -2.667)
			(end -1.016 -2.667)
			(stroke
				(width 0.1524)
				(type default)
			)
			(layer "F.SilkS")
		)
		(fp_line
			(start -1.016 -2.667)
			(end -1.016 2.667)
			(stroke
				(width 0.1524)
				(type default)
			)
			(layer "F.SilkS")
		)
		(fp_line
			(start 1.016 2.667)
			(end 1.016 -2.667)
			(stroke
				(width 0.1524)
				(type default)
			)
			(layer "F.SilkS")
		)
		(fp_line
			(start -1.016 2.667)
			(end 1.016 2.667)
			(stroke
				(width 0.1524)
				(type default)
			)
			(layer "F.SilkS")
		)
		(fp_line
			(start 0.889 2.921)
			(end -0.889 2.921)
			(stroke
				(width 0.508)
				(type default)
			)
			(layer "F.SilkS")
		)
		(fp_rect
			(start -1.143 3.175)
			(end 1.143 -2.794)
			(stroke
				(width 0)
				(type default)
			)
			(fill no)
			(layer "F.CrtYd")
		)
		(fp_poly
			(pts
				(xy -1.143 -2.794) (xy 1.143 -2.794) (xy 1.143 3.175) (xy -1.143 3.175)
			)
			(stroke
				(width 0)
				(type default)
			)
			(fill no)
			(layer "F.Fab")
		)
		(pad "A" smd rect
			(at 0 -1.6891 90)
			(size 0.889 1.397)
			(layers "F.Cu" "F.Mask" "F.Paste")
			(net "FAN_TACH8")
		)
		(pad "K" smd rect
			(at 0 1.6891 90)
			(size 0.889 1.397)
			(layers "F.Cu" "F.Mask" "F.Paste")
			(net "P12V")
		)
	)
	(footprint ""
		(layer "F.Cu")
		(at 39.784274 -363.062774 180)
		(property "Reference" "PR42"
			(at 0 0 180)
			(layer "F.SilkS")
			(hide yes)
			(effects
				(font
					(size 1.27 1.27)
				)
			)
		)
		(property "Value" "10KR2F-2-GP"
			(at 0.064008 -3.993896 180)
			(unlocked yes)
			(layer "F.Fab")
			(hide yes)
			(effects
				(font
					(size 1.016 1.016)
					(thickness 0.1524)
				)
			)
		)
		(property "Device Type" "R402H16"
			(at 0.064008 -5.517896 180)
			(unlocked yes)
			(layer "F.Fab")
			(hide yes)
			(effects
				(font
					(size 1.016 1.016)
					(thickness 0.1524)
				)
			)
		)
		(duplicate_pad_numbers_are_jumpers no)
		(fp_line
			(start 0.508 -0.9398)
			(end -0.508 -0.9398)
			(stroke
				(width 0.1524)
				(type default)
			)
			(layer "F.SilkS")
		)
		(fp_line
			(start -0.508 -0.9398)
			(end -0.508 0.9398)
			(stroke
				(width 0.1524)
				(type default)
			)
			(layer "F.SilkS")
		)
		(fp_rect
			(start -0.508 0.9398)
			(end 0.508 -0.9398)
			(stroke
				(width 0)
				(type default)
			)
			(fill no)
			(layer "F.CrtYd")
		)
		(fp_rect
			(start -0.508 0.9398)
			(end 0.508 -0.9398)
			(stroke
				(width 0)
				(type default)
			)
			(fill no)
			(layer "F.Fab")
		)
		(pad "1" smd custom
			(at 0 -0.4445 180)
			(size 0.1397 0.1397)
			(layers "F.Cu" "F.Mask" "F.Paste")
			(net "TEMP_ALM#_JP_1")
			(options
				(clearance outline)
				(anchor circle)
			)
			(primitives
				(gr_poly
					(pts
						(arc
							(start -0.1778 -0.2794)
							(mid -0.249642 -0.249642)
							(end -0.2794 -0.1778)
						)
						(arc
							(start -0.2794 0.1778)
							(mid -0.249642 0.249642)
							(end -0.1778 0.2794)
						)
						(arc
							(start 0.1778 0.2794)
							(mid 0.249642 0.249642)
							(end 0.2794 0.1778)
						)
						(arc
							(start 0.2794 -0.1778)
							(mid 0.249642 -0.249642)
							(end 0.1778 -0.2794)
						)
					)
					(width 0)
					(fill yes)
				)
			)
		)
		(pad "2" smd custom
			(at 0 0.4445 180)
			(size 0.1397 0.1397)
			(layers "F.Cu" "F.Mask" "F.Paste")
			(net "TEMP_ALM#_REVERSE")
			(options
				(clearance outline)
				(anchor circle)
			)
			(primitives
				(gr_poly
					(pts
						(arc
							(start -0.1778 -0.2794)
							(mid -0.249642 -0.249642)
							(end -0.2794 -0.1778)
						)
						(arc
							(start -0.2794 0.1778)
							(mid -0.249642 0.249642)
							(end -0.1778 0.2794)
						)
						(arc
							(start 0.1778 0.2794)
							(mid 0.249642 0.249642)
							(end 0.2794 0.1778)
						)
						(arc
							(start 0.2794 -0.1778)
							(mid 0.249642 -0.249642)
							(end 0.1778 -0.2794)
						)
					)
					(width 0)
					(fill yes)
				)
			)
		)
	)
	(footprint ""
		(layer "F.Cu")
		(at 25.5016 -140.5382 90)
		(property "Reference" "PC85"
			(at 0 0 90)
			(layer "F.SilkS")
			(hide yes)
			(effects
				(font
					(size 1.27 1.27)
				)
			)
		)
		(property "Value" "SCD01U25V2KX-3GP"
			(at 1.1811 -2.7051 90)
			(unlocked yes)
			(layer "F.Fab")
			(hide yes)
			(effects
				(font
					(size 1.016 1.016)
					(thickness 0.1524)
				)
			)
		)
		(property "Device Type" "C402H22"
			(at 1.1811 -4.2291 90)
			(unlocked yes)
			(layer "F.Fab")
			(hide yes)
			(effects
				(font
					(size 1.016 1.016)
					(thickness 0.1524)
				)
			)
		)
		(duplicate_pad_numbers_are_jumpers no)
		(fp_rect
			(start -0.4318 0.9525)
			(end 0.4318 -0.9525)
			(stroke
				(width 0)
				(type default)
			)
			(fill no)
			(layer "F.CrtYd")
		)
		(fp_rect
			(start -0.4318 0.9525)
			(end 0.4318 -0.9525)
			(stroke
				(width 0)
				(type default)
			)
			(fill no)
			(layer "F.Fab")
		)
		(pad "1" smd custom
			(at 0 -0.4445 90)
			(size 0.1524 0.1524)
			(layers "F.Cu" "F.Mask" "F.Paste")
			(net "P12VU_2490_RC")
			(options
				(clearance outline)
				(anchor circle)
			)
			(primitives
				(gr_poly
					(pts
						(arc
							(start 0.3048 -0.2032)
							(mid 0.275042 -0.275042)
							(end 0.2032 -0.3048)
						)
						(arc
							(start -0.2032 -0.3048)
							(mid -0.275042 -0.275042)
							(end -0.3048 -0.2032)
						)
						(arc
							(start -0.3048 0.2032)
							(mid -0.275042 0.275042)
							(end -0.2032 0.3048)
						)
						(arc
							(start 0.2032 0.3048)
							(mid 0.275042 0.275042)
							(end 0.3048 0.2032)
						)
					)
					(width 0)
					(fill yes)
				)
			)
		)
		(pad "2" smd custom
			(at 0 0.4445 90)
			(size 0.1524 0.1524)
			(layers "F.Cu" "F.Mask" "F.Paste")
			(net "GND")
			(options
				(clearance outline)
				(anchor circle)
			)
			(primitives
				(gr_poly
					(pts
						(arc
							(start 0.3048 -0.2032)
							(mid 0.275042 -0.275042)
							(end 0.2032 -0.3048)
						)
						(arc
							(start -0.2032 -0.3048)
							(mid -0.275042 -0.275042)
							(end -0.3048 -0.2032)
						)
						(arc
							(start -0.3048 0.2032)
							(mid -0.275042 0.275042)
							(end -0.2032 0.3048)
						)
						(arc
							(start 0.2032 0.3048)
							(mid 0.275042 0.275042)
							(end 0.3048 0.2032)
						)
					)
					(width 0)
					(fill yes)
				)
			)
		)
	)
	(footprint ""
		(layer "F.Cu")
		(at 14.4526 -60.5282)
		(property "Reference" "R362"
			(at 0 0 0)
			(layer "F.SilkS")
			(hide yes)
			(effects
				(font
					(size 1.27 1.27)
				)
			)
		)
		(property "Value" "100R2J-2-GP"
			(at 0.064008 -3.993896 0)
			(unlocked yes)
			(layer "F.Fab")
			(hide yes)
			(effects
				(font
					(size 1.016 1.016)
					(thickness 0.1524)
				)
			)
		)
		(property "Device Type" "R402H14"
			(at 0.064008 -5.517896 0)
			(unlocked yes)
			(layer "F.Fab")
			(hide yes)
			(effects
				(font
					(size 1.016 1.016)
					(thickness 0.1524)
				)
			)
		)
		(duplicate_pad_numbers_are_jumpers no)
		(fp_line
			(start -0.508 -0.9398)
			(end -0.508 0.9398)
			(stroke
				(width 0.1524)
				(type default)
			)
			(layer "F.SilkS")
		)
		(fp_line
			(start 0.508 -0.9398)
			(end -0.508 -0.9398)
			(stroke
				(width 0.1524)
				(type default)
			)
			(layer "F.SilkS")
		)
		(fp_rect
			(start -0.508 0.9398)
			(end 0.508 -0.9398)
			(stroke
				(width 0)
				(type default)
			)
			(fill no)
			(layer "F.CrtYd")
		)
		(fp_rect
			(start -0.508 0.9398)
			(end 0.508 -0.9398)
			(stroke
				(width 0)
				(type default)
			)
			(fill no)
			(layer "F.Fab")
		)
		(pad "1" smd custom
			(at 0 -0.4445)
			(size 0.1397 0.1397)
			(layers "F.Cu" "F.Mask" "F.Paste")
			(net "UPPER_TRAY_ID")
			(options
				(clearance outline)
				(anchor circle)
			)
			(primitives
				(gr_poly
					(pts
						(arc
							(start -0.1778 -0.2794)
							(mid -0.249642 -0.249642)
							(end -0.2794 -0.1778)
						)
						(arc
							(start -0.2794 0.1778)
							(mid -0.249642 0.249642)
							(end -0.1778 0.2794)
						)
						(arc
							(start 0.1778 0.2794)
							(mid 0.249642 0.249642)
							(end 0.2794 0.1778)
						)
						(arc
							(start 0.2794 -0.1778)
							(mid 0.249642 -0.249642)
							(end 0.1778 -0.2794)
						)
					)
					(width 0)
					(fill yes)
				)
			)
		)
		(pad "2" smd custom
			(at 0 0.4445)
			(size 0.1397 0.1397)
			(layers "F.Cu" "F.Mask" "F.Paste")
			(net "GND")
			(options
				(clearance outline)
				(anchor circle)
			)
			(primitives
				(gr_poly
					(pts
						(arc
							(start -0.1778 -0.2794)
							(mid -0.249642 -0.249642)
							(end -0.2794 -0.1778)
						)
						(arc
							(start -0.2794 0.1778)
							(mid -0.249642 0.249642)
							(end -0.1778 0.2794)
						)
						(arc
							(start 0.1778 0.2794)
							(mid 0.249642 0.249642)
							(end 0.2794 0.1778)
						)
						(arc
							(start 0.2794 -0.1778)
							(mid 0.249642 -0.249642)
							(end 0.1778 -0.2794)
						)
					)
					(width 0)
					(fill yes)
				)
			)
		)
	)
	(footprint ""
		(layer "F.Cu")
		(at 18.8214 -145.6436 180)
		(property "Reference" "PC91"
			(at 0 0 180)
			(layer "F.SilkS")
			(hide yes)
			(effects
				(font
					(size 1.27 1.27)
				)
			)
		)
		(property "Value" "SCD01U50V3KX-4GP"
			(at 0 -2.8194 180)
			(unlocked yes)
			(layer "F.Fab")
			(hide yes)
			(effects
				(font
					(size 1.016 1.016)
					(thickness 0.1524)
				)
			)
		)
		(property "Device Type" "C603H36"
			(at 0 -4.3434 180)
			(unlocked yes)
			(layer "F.Fab")
			(hide yes)
			(effects
				(font
					(size 1.016 1.016)
					(thickness 0.1524)
				)
			)
		)
		(duplicate_pad_numbers_are_jumpers no)
		(fp_line
			(start 0.508 0)
			(end -0.508 0)
			(stroke
				(width 0.2032)
				(type default)
			)
			(layer "F.SilkS")
		)
		(fp_rect
			(start -0.5842 1.3335)
			(end 0.5842 -1.3335)
			(stroke
				(width 0)
				(type default)
			)
			(fill no)
			(layer "F.CrtYd")
		)
		(fp_rect
			(start -0.5842 1.3335)
			(end 0.5842 -1.3335)
			(stroke
				(width 0)
				(type default)
			)
			(fill no)
			(layer "F.Fab")
		)
		(pad "1" smd custom
			(at 0 -0.762 180)
			(size 0.2159 0.2159)
			(layers "F.Cu" "F.Mask" "F.Paste")
			(net "P12VU_2490_TIMER")
			(options
				(clearance outline)
				(anchor circle)
			)
			(primitives
				(gr_poly
					(pts
						(arc
							(start -0.3302 -0.4318)
							(mid -0.402042 -0.402042)
							(end -0.4318 -0.3302)
						)
						(arc
							(start -0.4318 0.3302)
							(mid -0.402042 0.402042)
							(end -0.3302 0.4318)
						)
						(arc
							(start 0.3302 0.4318)
							(mid 0.402042 0.402042)
							(end 0.4318 0.3302)
						)
						(arc
							(start 0.4318 -0.3302)
							(mid 0.402042 -0.402042)
							(end 0.3302 -0.4318)
						)
					)
					(width 0)
					(fill yes)
				)
			)
		)
		(pad "2" smd custom
			(at 0 0.762 180)
			(size 0.2159 0.2159)
			(layers "F.Cu" "F.Mask" "F.Paste")
			(net "GND")
			(options
				(clearance outline)
				(anchor circle)
			)
			(primitives
				(gr_poly
					(pts
						(arc
							(start -0.3302 -0.4318)
							(mid -0.402042 -0.402042)
							(end -0.4318 -0.3302)
						)
						(arc
							(start -0.4318 0.3302)
							(mid -0.402042 0.402042)
							(end -0.3302 0.4318)
						)
						(arc
							(start 0.3302 0.4318)
							(mid 0.402042 0.402042)
							(end 0.4318 0.3302)
						)
						(arc
							(start 0.4318 -0.3302)
							(mid 0.402042 -0.402042)
							(end 0.3302 -0.4318)
						)
					)
					(width 0)
					(fill yes)
				)
			)
		)
	)
	(footprint ""
		(layer "F.Cu")
		(at 8.001 -169.418 -90)
		(property "Reference" "TC14"
			(at 0 0 270)
			(layer "F.SilkS")
			(hide yes)
			(effects
				(font
					(size 1.27 1.27)
				)
			)
		)
		(property "Value" "ST15U25VDM-1-GP"
			(at 0 -9.6012 270)
			(unlocked yes)
			(layer "F.Fab")
			(hide yes)
			(effects
				(font
					(size 1.016 1.016)
					(thickness 0.1524)
				)
			)
		)
		(property "Device Type" "CT7343H79"
			(at 0 -11.1252 270)
			(unlocked yes)
			(layer "F.Fab")
			(hide yes)
			(effects
				(font
					(size 1.016 1.016)
					(thickness 0.1524)
				)
			)
		)
		(duplicate_pad_numbers_are_jumpers no)
		(fp_line
			(start -2.286 4.8768)
			(end -2.286 2.032)
			(stroke
				(width 0.1524)
				(type default)
			)
			(layer "F.SilkS")
		)
		(fp_line
			(start 2.286 4.8768)
			(end -2.286 4.8768)
			(stroke
				(width 0.1524)
				(type default)
			)
			(layer "F.SilkS")
		)
		(fp_line
			(start 2.286 2.032)
			(end 2.286 4.8768)
			(stroke
				(width 0.1524)
				(type default)
			)
			(layer "F.SilkS")
		)
		(fp_line
			(start 2.286 -2.032)
			(end 2.286 -4.8768)
			(stroke
				(width 0.1524)
				(type default)
			)
			(layer "F.SilkS")
		)
		(fp_line
			(start 2.1082 -4.699)
			(end -2.1082 -4.699)
			(stroke
				(width 0.508)
				(type default)
			)
			(layer "F.SilkS")
		)
		(fp_line
			(start -2.286 -4.8768)
			(end -2.286 -2.032)
			(stroke
				(width 0.1524)
				(type default)
			)
			(layer "F.SilkS")
		)
		(fp_line
			(start 2.286 -4.8768)
			(end -2.286 -4.8768)
			(stroke
				(width 0.1524)
				(type default)
			)
			(layer "F.SilkS")
		)
		(fp_rect
			(start -2.1463 3.6449)
			(end 2.1463 -3.6449)
			(stroke
				(width 0)
				(type default)
			)
			(fill no)
			(layer "F.CrtYd")
		)
		(fp_poly
			(pts
				(xy -2.54 4.953) (xy -2.54 4.2926) (xy -3.81 4.2926) (xy -3.81 -4.2926) (xy -2.54 -4.2926) (xy -2.54 -4.953)
				(xy 2.54 -4.953) (xy 2.54 -4.2926) (xy 3.81 -4.2926) (xy 3.81 -1.6256) (xy 2.1463 -1.6256) (xy 2.1463 -3.6449)
				(xy -2.1463 -3.6449) (xy -2.1463 3.6449) (xy 2.1463 3.6449) (xy 2.1463 -1.6129) (xy 3.81 -1.6129)
				(xy 3.81 4.2926) (xy 2.54 4.2926) (xy 2.54 4.953)
			)
			(stroke
				(width 0)
				(type default)
			)
			(fill no)
			(layer "F.CrtYd")
		)
		(fp_rect
			(start -2.54 4.953)
			(end 2.54 -4.953)
			(stroke
				(width 0)
				(type default)
			)
			(fill no)
			(layer "F.Fab")
		)
		(fp_rect
			(start -3.81 4.2926)
			(end -2.54 -4.2926)
			(stroke
				(width 0)
				(type default)
			)
			(fill no)
			(layer "F.Fab")
		)
		(fp_rect
			(start 2.54 4.2926)
			(end 3.81 -4.2926)
			(stroke
				(width 0)
				(type default)
			)
			(fill no)
			(layer "F.Fab")
		)
		(pad "1" smd rect
			(at 0 -3.1496 270)
			(size 2.413 2.286)
			(layers "F.Cu" "F.Mask" "F.Paste")
			(net "P12V")
		)
		(pad "2" smd rect
			(at 0 3.1496 270)
			(size 2.413 2.286)
			(layers "F.Cu" "F.Mask" "F.Paste")
			(net "GND")
		)
		(zone
			(layer "F.Cu")
			(hatch none 0.5)
			(connect_pads
				(clearance 0)
			)
			(min_thickness 0.25)
			(keepout
				(tracks allowed)
				(vias not_allowed)
				(pads allowed)
				(copperpour not_allowed)
				(footprints allowed)
			)
			(placement
				(enabled no)
				(sheetname "")
			)
			(fill
				(thermal_gap 0.5)
				(thermal_bridge_width 0.5)
				(island_removal_mode 0)
			)
			(polygon
				(pts
					(xy 3.4036 -170.9293) (xy 3.4036 -167.9067) (xy 6.2992 -167.9067) (xy 6.6294 -167.9067) (xy 6.6294 -170.9293)
					(xy 6.2992 -170.9293)
				)
			)
		)
		(zone
			(layer "F.Cu")
			(hatch none 0.5)
			(connect_pads
				(clearance 0)
			)
			(min_thickness 0.25)
			(keepout
				(tracks allowed)
				(vias not_allowed)
				(pads allowed)
				(copperpour not_allowed)
				(footprints allowed)
			)
			(placement
				(enabled no)
				(sheetname "")
			)
			(fill
				(thermal_gap 0.5)
				(thermal_bridge_width 0.5)
				(island_removal_mode 0)
			)
			(polygon
				(pts
					(xy 9.6901 -167.9067) (xy 12.5984 -167.9067) (xy 12.5984 -170.9293) (xy 9.7028 -170.9293) (xy 9.3726 -170.9293)
					(xy 9.3726 -167.9067)
				)
			)
		)
	)
	(footprint ""
		(layer "F.Cu")
		(at 32.399224 -174.76851 90)
		(property "Reference" "R18"
			(at 0 0 90)
			(layer "F.SilkS")
			(hide yes)
			(effects
				(font
					(size 1.27 1.27)
				)
			)
		)
		(property "Value" "100KR2F-L1-GP"
			(at 0.064008 -3.993896 90)
			(unlocked yes)
			(layer "F.Fab")
			(hide yes)
			(effects
				(font
					(size 1.016 1.016)
					(thickness 0.1524)
				)
			)
		)
		(property "Device Type" "R402H16"
			(at 0.064008 -5.517896 90)
			(unlocked yes)
			(layer "F.Fab")
			(hide yes)
			(effects
				(font
					(size 1.016 1.016)
					(thickness 0.1524)
				)
			)
		)
		(duplicate_pad_numbers_are_jumpers no)
		(fp_line
			(start 0.508 -0.9398)
			(end -0.508 -0.9398)
			(stroke
				(width 0.1524)
				(type default)
			)
			(layer "F.SilkS")
		)
		(fp_line
			(start -0.508 -0.9398)
			(end -0.508 0.9398)
			(stroke
				(width 0.1524)
				(type default)
			)
			(layer "F.SilkS")
		)
		(fp_rect
			(start -0.508 0.9398)
			(end 0.508 -0.9398)
			(stroke
				(width 0)
				(type default)
			)
			(fill no)
			(layer "F.CrtYd")
		)
		(fp_rect
			(start -0.508 0.9398)
			(end 0.508 -0.9398)
			(stroke
				(width 0)
				(type default)
			)
			(fill no)
			(layer "F.Fab")
		)
		(pad "1" smd custom
			(at 0 -0.4445 90)
			(size 0.1397 0.1397)
			(layers "F.Cu" "F.Mask" "F.Paste")
			(net "PWM_EXP_1B")
			(options
				(clearance outline)
				(anchor circle)
			)
			(primitives
				(gr_poly
					(pts
						(arc
							(start -0.1778 -0.2794)
							(mid -0.249642 -0.249642)
							(end -0.2794 -0.1778)
						)
						(arc
							(start -0.2794 0.1778)
							(mid -0.249642 0.249642)
							(end -0.1778 0.2794)
						)
						(arc
							(start 0.1778 0.2794)
							(mid 0.249642 0.249642)
							(end 0.2794 0.1778)
						)
						(arc
							(start 0.2794 -0.1778)
							(mid 0.249642 -0.249642)
							(end 0.1778 -0.2794)
						)
					)
					(width 0)
					(fill yes)
				)
			)
		)
		(pad "2" smd custom
			(at 0 0.4445 90)
			(size 0.1397 0.1397)
			(layers "F.Cu" "F.Mask" "F.Paste")
			(net "GND")
			(options
				(clearance outline)
				(anchor circle)
			)
			(primitives
				(gr_poly
					(pts
						(arc
							(start -0.1778 -0.2794)
							(mid -0.249642 -0.249642)
							(end -0.2794 -0.1778)
						)
						(arc
							(start -0.2794 0.1778)
							(mid -0.249642 0.249642)
							(end -0.1778 0.2794)
						)
						(arc
							(start 0.1778 0.2794)
							(mid 0.249642 0.249642)
							(end 0.2794 0.1778)
						)
						(arc
							(start 0.2794 -0.1778)
							(mid 0.249642 -0.249642)
							(end 0.1778 -0.2794)
						)
					)
					(width 0)
					(fill yes)
				)
			)
		)
	)
	(footprint ""
		(layer "F.Cu")
		(at 13.97 -174.752 90)
		(property "Reference" "U11"
			(at 0 0 90)
			(layer "F.SilkS")
			(hide yes)
			(effects
				(font
					(size 1.27 1.27)
				)
			)
		)
		(property "Value" "74LVC1G32GW-1GP"
			(at -2.3368 -8.6868 90)
			(unlocked yes)
			(layer "F.Fab")
			(hide yes)
			(effects
				(font
					(size 1.016 1.016)
					(thickness 0.1524)
				)
			)
		)
		(property "Device Type" "SC70-5H44"
			(at -2.3114 -10.414 90)
			(unlocked yes)
			(layer "F.Fab")
			(hide yes)
			(effects
				(font
					(size 1.016 1.016)
					(thickness 0.1524)
				)
			)
		)
		(duplicate_pad_numbers_are_jumpers no)
		(fp_line
			(start 1.3843 -1.8034)
			(end 1.3843 -1.1176)
			(stroke
				(width 0.3302)
				(type default)
			)
			(layer "F.SilkS")
		)
		(fp_line
			(start 0.6604 -1.8034)
			(end 1.3843 -1.8034)
			(stroke
				(width 0.3302)
				(type default)
			)
			(layer "F.SilkS")
		)
		(fp_line
			(start 1.27 -1.7018)
			(end 1.27 1.7018)
			(stroke
				(width 0.1524)
				(type default)
			)
			(layer "F.SilkS")
		)
		(fp_line
			(start -1.27 -1.7018)
			(end 1.27 -1.7018)
			(stroke
				(width 0.1524)
				(type default)
			)
			(layer "F.SilkS")
		)
		(fp_line
			(start 1.27 1.7018)
			(end -1.27 1.7018)
			(stroke
				(width 0.1524)
				(type default)
			)
			(layer "F.SilkS")
		)
		(fp_line
			(start -1.27 1.7018)
			(end -1.27 -1.7018)
			(stroke
				(width 0.1524)
				(type default)
			)
			(layer "F.SilkS")
		)
		(fp_rect
			(start -1.524 1.9558)
			(end 1.524 -1.9558)
			(stroke
				(width 0)
				(type default)
			)
			(fill no)
			(layer "F.CrtYd")
		)
		(fp_poly
			(pts
				(xy -1.524 -1.9558) (xy 1.524 -1.9558) (xy 1.524 1.9558) (xy -1.524 1.9558)
			)
			(stroke
				(width 0)
				(type default)
			)
			(fill no)
			(layer "F.Fab")
		)
		(pad "1" smd rect
			(at 0.65024 -0.8255 90)
			(size 0.4064 1.2192)
			(layers "F.Cu" "F.Mask" "F.Paste")
			(net "SEB_PEER_2A_HB")
		)
		(pad "2" smd rect
			(at 0 -0.8255 90)
			(size 0.4064 1.2192)
			(layers "F.Cu" "F.Mask" "F.Paste")
			(net "SEB_PEER_2B_HB")
		)
		(pad "3" smd rect
			(at -0.65024 -0.8255 90)
			(size 0.4064 1.2192)
			(layers "F.Cu" "F.Mask" "F.Paste")
			(net "GND")
		)
		(pad "4" smd rect
			(at -0.65024 0.8255 90)
			(size 0.4064 1.2192)
			(layers "F.Cu" "F.Mask" "F.Paste")
			(net "SEB_PEER_2A_2B_HB_OUT")
		)
		(pad "5" smd rect
			(at 0.65024 0.8255 90)
			(size 0.4064 1.2192)
			(layers "F.Cu" "F.Mask" "F.Paste")
			(net "P3V3")
		)
	)
	(footprint ""
		(layer "F.Cu")
		(at 14.5796 -53.2384)
		(property "Reference" "R360"
			(at 0 0 0)
			(layer "F.SilkS")
			(hide yes)
			(effects
				(font
					(size 1.27 1.27)
				)
			)
		)
		(property "Value" "100R2J-2-GP"
			(at 0.064008 -3.993896 0)
			(unlocked yes)
			(layer "F.Fab")
			(hide yes)
			(effects
				(font
					(size 1.016 1.016)
					(thickness 0.1524)
				)
			)
		)
		(property "Device Type" "R402H14"
			(at 0.064008 -5.517896 0)
			(unlocked yes)
			(layer "F.Fab")
			(hide yes)
			(effects
				(font
					(size 1.016 1.016)
					(thickness 0.1524)
				)
			)
		)
		(duplicate_pad_numbers_are_jumpers no)
		(fp_line
			(start -0.508 -0.9398)
			(end -0.508 0.9398)
			(stroke
				(width 0.1524)
				(type default)
			)
			(layer "F.SilkS")
		)
		(fp_line
			(start 0.508 -0.9398)
			(end -0.508 -0.9398)
			(stroke
				(width 0.1524)
				(type default)
			)
			(layer "F.SilkS")
		)
		(fp_rect
			(start -0.508 0.9398)
			(end 0.508 -0.9398)
			(stroke
				(width 0)
				(type default)
			)
			(fill no)
			(layer "F.CrtYd")
		)
		(fp_rect
			(start -0.508 0.9398)
			(end 0.508 -0.9398)
			(stroke
				(width 0)
				(type default)
			)
			(fill no)
			(layer "F.Fab")
		)
		(pad "1" smd custom
			(at 0 -0.4445)
			(size 0.1397 0.1397)
			(layers "F.Cu" "F.Mask" "F.Paste")
			(net "FCB_HW_REVISION")
			(options
				(clearance outline)
				(anchor circle)
			)
			(primitives
				(gr_poly
					(pts
						(arc
							(start -0.1778 -0.2794)
							(mid -0.249642 -0.249642)
							(end -0.2794 -0.1778)
						)
						(arc
							(start -0.2794 0.1778)
							(mid -0.249642 0.249642)
							(end -0.1778 0.2794)
						)
						(arc
							(start 0.1778 0.2794)
							(mid 0.249642 0.249642)
							(end 0.2794 0.1778)
						)
						(arc
							(start 0.2794 -0.1778)
							(mid 0.249642 -0.249642)
							(end 0.1778 -0.2794)
						)
					)
					(width 0)
					(fill yes)
				)
			)
		)
		(pad "2" smd custom
			(at 0 0.4445)
			(size 0.1397 0.1397)
			(layers "F.Cu" "F.Mask" "F.Paste")
			(net "GND")
			(options
				(clearance outline)
				(anchor circle)
			)
			(primitives
				(gr_poly
					(pts
						(arc
							(start -0.1778 -0.2794)
							(mid -0.249642 -0.249642)
							(end -0.2794 -0.1778)
						)
						(arc
							(start -0.2794 0.1778)
							(mid -0.249642 0.249642)
							(end -0.1778 0.2794)
						)
						(arc
							(start 0.1778 0.2794)
							(mid 0.249642 0.249642)
							(end 0.2794 0.1778)
						)
						(arc
							(start 0.2794 -0.1778)
							(mid 0.249642 -0.249642)
							(end 0.1778 -0.2794)
						)
					)
					(width 0)
					(fill yes)
				)
			)
		)
	)
	(footprint ""
		(layer "F.Cu")
		(at 21.766784 -216.6366 90)
		(property "Reference" "R132"
			(at 0 0 90)
			(layer "F.SilkS")
			(hide yes)
			(effects
				(font
					(size 1.27 1.27)
				)
			)
		)
		(property "Value" "4K7R2F-GP"
			(at 0.064008 -3.993896 90)
			(unlocked yes)
			(layer "F.Fab")
			(hide yes)
			(effects
				(font
					(size 1.016 1.016)
					(thickness 0.1524)
				)
			)
		)
		(property "Device Type" "R402H16"
			(at 0.064008 -5.517896 90)
			(unlocked yes)
			(layer "F.Fab")
			(hide yes)
			(effects
				(font
					(size 1.016 1.016)
					(thickness 0.1524)
				)
			)
		)
		(duplicate_pad_numbers_are_jumpers no)
		(fp_line
			(start 0.508 -0.9398)
			(end -0.508 -0.9398)
			(stroke
				(width 0.1524)
				(type default)
			)
			(layer "F.SilkS")
		)
		(fp_line
			(start -0.508 -0.9398)
			(end -0.508 0.9398)
			(stroke
				(width 0.1524)
				(type default)
			)
			(layer "F.SilkS")
		)
		(fp_rect
			(start -0.508 0.9398)
			(end 0.508 -0.9398)
			(stroke
				(width 0)
				(type default)
			)
			(fill no)
			(layer "F.CrtYd")
		)
		(fp_rect
			(start -0.508 0.9398)
			(end 0.508 -0.9398)
			(stroke
				(width 0)
				(type default)
			)
			(fill no)
			(layer "F.Fab")
		)
		(pad "1" smd custom
			(at 0 -0.4445 90)
			(size 0.1397 0.1397)
			(layers "F.Cu" "F.Mask" "F.Paste")
			(net "P3V3")
			(options
				(clearance outline)
				(anchor circle)
			)
			(primitives
				(gr_poly
					(pts
						(arc
							(start -0.1778 -0.2794)
							(mid -0.249642 -0.249642)
							(end -0.2794 -0.1778)
						)
						(arc
							(start -0.2794 0.1778)
							(mid -0.249642 0.249642)
							(end -0.1778 0.2794)
						)
						(arc
							(start 0.1778 0.2794)
							(mid 0.249642 0.249642)
							(end 0.2794 0.1778)
						)
						(arc
							(start 0.2794 -0.1778)
							(mid 0.249642 -0.249642)
							(end 0.1778 -0.2794)
						)
					)
					(width 0)
					(fill yes)
				)
			)
		)
		(pad "2" smd custom
			(at 0 0.4445 90)
			(size 0.1397 0.1397)
			(layers "F.Cu" "F.Mask" "F.Paste")
			(net "PWM_OUT_FAN4")
			(options
				(clearance outline)
				(anchor circle)
			)
			(primitives
				(gr_poly
					(pts
						(arc
							(start -0.1778 -0.2794)
							(mid -0.249642 -0.249642)
							(end -0.2794 -0.1778)
						)
						(arc
							(start -0.2794 0.1778)
							(mid -0.249642 0.249642)
							(end -0.1778 0.2794)
						)
						(arc
							(start 0.1778 0.2794)
							(mid 0.249642 0.249642)
							(end 0.2794 0.1778)
						)
						(arc
							(start 0.2794 -0.1778)
							(mid 0.249642 -0.249642)
							(end 0.1778 -0.2794)
						)
					)
					(width 0)
					(fill yes)
				)
			)
		)
	)
	(footprint ""
		(layer "F.Cu")
		(at 30.3784 -210.8454 180)
		(property "Reference" "R139"
			(at 0 0 180)
			(layer "F.SilkS")
			(hide yes)
			(effects
				(font
					(size 1.27 1.27)
				)
			)
		)
		(property "Value" "0R2J-2-GP"
			(at 0.064008 -3.993896 180)
			(unlocked yes)
			(layer "F.Fab")
			(hide yes)
			(effects
				(font
					(size 1.016 1.016)
					(thickness 0.1524)
				)
			)
		)
		(property "Device Type" "R402H16"
			(at 0.064008 -5.517896 180)
			(unlocked yes)
			(layer "F.Fab")
			(hide yes)
			(effects
				(font
					(size 1.016 1.016)
					(thickness 0.1524)
				)
			)
		)
		(duplicate_pad_numbers_are_jumpers no)
		(fp_line
			(start 0.508 -0.9398)
			(end -0.508 -0.9398)
			(stroke
				(width 0.1524)
				(type default)
			)
			(layer "F.SilkS")
		)
		(fp_line
			(start -0.508 -0.9398)
			(end -0.508 0.9398)
			(stroke
				(width 0.1524)
				(type default)
			)
			(layer "F.SilkS")
		)
		(fp_rect
			(start -0.508 0.9398)
			(end 0.508 -0.9398)
			(stroke
				(width 0)
				(type default)
			)
			(fill no)
			(layer "F.CrtYd")
		)
		(fp_rect
			(start -0.508 0.9398)
			(end 0.508 -0.9398)
			(stroke
				(width 0)
				(type default)
			)
			(fill no)
			(layer "F.Fab")
		)
		(pad "1" smd custom
			(at 0 -0.4445 180)
			(size 0.1397 0.1397)
			(layers "F.Cu" "F.Mask" "F.Paste")
			(net "PWM_OUT_FAN4_NET")
			(options
				(clearance outline)
				(anchor circle)
			)
			(primitives
				(gr_poly
					(pts
						(arc
							(start -0.1778 -0.2794)
							(mid -0.249642 -0.249642)
							(end -0.2794 -0.1778)
						)
						(arc
							(start -0.2794 0.1778)
							(mid -0.249642 0.249642)
							(end -0.1778 0.2794)
						)
						(arc
							(start 0.1778 0.2794)
							(mid 0.249642 0.249642)
							(end 0.2794 0.1778)
						)
						(arc
							(start 0.2794 -0.1778)
							(mid 0.249642 -0.249642)
							(end 0.1778 -0.2794)
						)
					)
					(width 0)
					(fill yes)
				)
			)
		)
		(pad "2" smd custom
			(at 0 0.4445 180)
			(size 0.1397 0.1397)
			(layers "F.Cu" "F.Mask" "F.Paste")
			(net "PWM_OUT_FAN4")
			(options
				(clearance outline)
				(anchor circle)
			)
			(primitives
				(gr_poly
					(pts
						(arc
							(start -0.1778 -0.2794)
							(mid -0.249642 -0.249642)
							(end -0.2794 -0.1778)
						)
						(arc
							(start -0.2794 0.1778)
							(mid -0.249642 0.249642)
							(end -0.1778 0.2794)
						)
						(arc
							(start 0.1778 0.2794)
							(mid 0.249642 0.249642)
							(end 0.2794 0.1778)
						)
						(arc
							(start 0.2794 -0.1778)
							(mid 0.249642 -0.249642)
							(end 0.1778 -0.2794)
						)
					)
					(width 0)
					(fill yes)
				)
			)
		)
	)
	(footprint ""
		(layer "F.Cu")
		(at 28.2956 -361.0864 -90)
		(property "Reference" "PR16"
			(at 0 0 270)
			(layer "F.SilkS")
			(hide yes)
			(effects
				(font
					(size 1.27 1.27)
				)
			)
		)
		(property "Value" "1KR2F-3-GP"
			(at 0.064008 -3.993896 270)
			(unlocked yes)
			(layer "F.Fab")
			(hide yes)
			(effects
				(font
					(size 1.016 1.016)
					(thickness 0.1524)
				)
			)
		)
		(property "Device Type" "R402H16"
			(at 0.064008 -5.517896 270)
			(unlocked yes)
			(layer "F.Fab")
			(hide yes)
			(effects
				(font
					(size 1.016 1.016)
					(thickness 0.1524)
				)
			)
		)
		(duplicate_pad_numbers_are_jumpers no)
		(fp_line
			(start -0.508 -0.9398)
			(end -0.508 0.9398)
			(stroke
				(width 0.1524)
				(type default)
			)
			(layer "F.SilkS")
		)
		(fp_line
			(start 0.508 -0.9398)
			(end -0.508 -0.9398)
			(stroke
				(width 0.1524)
				(type default)
			)
			(layer "F.SilkS")
		)
		(fp_rect
			(start -0.508 0.9398)
			(end 0.508 -0.9398)
			(stroke
				(width 0)
				(type default)
			)
			(fill no)
			(layer "F.CrtYd")
		)
		(fp_rect
			(start -0.508 0.9398)
			(end 0.508 -0.9398)
			(stroke
				(width 0)
				(type default)
			)
			(fill no)
			(layer "F.Fab")
		)
		(pad "1" smd custom
			(at 0 -0.4445 270)
			(size 0.1397 0.1397)
			(layers "F.Cu" "F.Mask" "F.Paste")
			(net "ADM1276_EN")
			(options
				(clearance outline)
				(anchor circle)
			)
			(primitives
				(gr_poly
					(pts
						(arc
							(start -0.1778 -0.2794)
							(mid -0.249642 -0.249642)
							(end -0.2794 -0.1778)
						)
						(arc
							(start -0.2794 0.1778)
							(mid -0.249642 0.249642)
							(end -0.1778 0.2794)
						)
						(arc
							(start 0.1778 0.2794)
							(mid 0.249642 0.249642)
							(end 0.2794 0.1778)
						)
						(arc
							(start 0.2794 -0.1778)
							(mid 0.249642 -0.249642)
							(end 0.1778 -0.2794)
						)
					)
					(width 0)
					(fill yes)
				)
			)
		)
		(pad "2" smd custom
			(at 0 0.4445 270)
			(size 0.1397 0.1397)
			(layers "F.Cu" "F.Mask" "F.Paste")
			(net "GND")
			(options
				(clearance outline)
				(anchor circle)
			)
			(primitives
				(gr_poly
					(pts
						(arc
							(start -0.1778 -0.2794)
							(mid -0.249642 -0.249642)
							(end -0.2794 -0.1778)
						)
						(arc
							(start -0.2794 0.1778)
							(mid -0.249642 0.249642)
							(end -0.1778 0.2794)
						)
						(arc
							(start 0.1778 0.2794)
							(mid 0.249642 0.249642)
							(end 0.2794 0.1778)
						)
						(arc
							(start 0.2794 -0.1778)
							(mid 0.249642 -0.249642)
							(end 0.1778 -0.2794)
						)
					)
					(width 0)
					(fill yes)
				)
			)
		)
	)
	(footprint ""
		(layer "F.Cu")
		(at 27.7876 -150.7998 90)
		(property "Reference" "C7"
			(at 0 0 90)
			(layer "F.SilkS")
			(hide yes)
			(effects
				(font
					(size 1.27 1.27)
				)
			)
		)
		(property "Value" "SC2200P50V2KX-2GP"
			(at 1.1811 -2.7051 90)
			(unlocked yes)
			(layer "F.Fab")
			(hide yes)
			(effects
				(font
					(size 1.016 1.016)
					(thickness 0.1524)
				)
			)
		)
		(property "Device Type" "C402H22"
			(at 1.1811 -4.2291 90)
			(unlocked yes)
			(layer "F.Fab")
			(hide yes)
			(effects
				(font
					(size 1.016 1.016)
					(thickness 0.1524)
				)
			)
		)
		(duplicate_pad_numbers_are_jumpers no)
		(fp_rect
			(start -0.4318 0.9525)
			(end 0.4318 -0.9525)
			(stroke
				(width 0)
				(type default)
			)
			(fill no)
			(layer "F.CrtYd")
		)
		(fp_rect
			(start -0.4318 0.9525)
			(end 0.4318 -0.9525)
			(stroke
				(width 0)
				(type default)
			)
			(fill no)
			(layer "F.Fab")
		)
		(pad "1" smd custom
			(at 0 -0.4445 90)
			(size 0.1524 0.1524)
			(layers "F.Cu" "F.Mask" "F.Paste")
			(net "NCT7904_D1+")
			(options
				(clearance outline)
				(anchor circle)
			)
			(primitives
				(gr_poly
					(pts
						(arc
							(start 0.3048 -0.2032)
							(mid 0.275042 -0.275042)
							(end 0.2032 -0.3048)
						)
						(arc
							(start -0.2032 -0.3048)
							(mid -0.275042 -0.275042)
							(end -0.3048 -0.2032)
						)
						(arc
							(start -0.3048 0.2032)
							(mid -0.275042 0.275042)
							(end -0.2032 0.3048)
						)
						(arc
							(start 0.2032 0.3048)
							(mid 0.275042 0.275042)
							(end 0.3048 0.2032)
						)
					)
					(width 0)
					(fill yes)
				)
			)
		)
		(pad "2" smd custom
			(at 0 0.4445 90)
			(size 0.1524 0.1524)
			(layers "F.Cu" "F.Mask" "F.Paste")
			(net "NCT7904_D1-")
			(options
				(clearance outline)
				(anchor circle)
			)
			(primitives
				(gr_poly
					(pts
						(arc
							(start 0.3048 -0.2032)
							(mid 0.275042 -0.275042)
							(end 0.2032 -0.3048)
						)
						(arc
							(start -0.2032 -0.3048)
							(mid -0.275042 -0.275042)
							(end -0.3048 -0.2032)
						)
						(arc
							(start -0.3048 0.2032)
							(mid -0.275042 0.275042)
							(end -0.2032 0.3048)
						)
						(arc
							(start 0.2032 0.3048)
							(mid 0.275042 0.275042)
							(end 0.3048 0.2032)
						)
					)
					(width 0)
					(fill yes)
				)
			)
		)
	)
	(footprint ""
		(layer "F.Cu")
		(at 40.64 -410.591)
		(property "Reference" "PR32"
			(at 0 0 0)
			(layer "F.SilkS")
			(hide yes)
			(effects
				(font
					(size 1.27 1.27)
				)
			)
		)
		(property "Value" "D0005RL1632F-GP-U"
			(at 3.2258 1.2954 0)
			(unlocked yes)
			(layer "F.Fab")
			(hide yes)
			(effects
				(font
					(size 1.016 1.016)
					(thickness 0.1524)
				)
			)
		)
		(property "Device Type" "RL3115-4PH45"
			(at 3.2258 -0.2286 0)
			(unlocked yes)
			(layer "F.Fab")
			(hide yes)
			(effects
				(font
					(size 1.016 1.016)
					(thickness 0.1524)
				)
			)
		)
		(duplicate_pad_numbers_are_jumpers no)
		(fp_line
			(start -2.0574 -1.7653)
			(end -2.0574 -0.4064)
			(stroke
				(width 0.3302)
				(type default)
			)
			(layer "F.SilkS")
		)
		(fp_line
			(start -1.9685 -1.651)
			(end 1.9685 -1.651)
			(stroke
				(width 0.1524)
				(type default)
			)
			(layer "F.SilkS")
		)
		(fp_line
			(start -1.9685 1.651)
			(end -1.9685 -1.651)
			(stroke
				(width 0.1524)
				(type default)
			)
			(layer "F.SilkS")
		)
		(fp_line
			(start -0.5334 -1.7653)
			(end -2.0574 -1.7653)
			(stroke
				(width 0.3302)
				(type default)
			)
			(layer "F.SilkS")
		)
		(fp_line
			(start 1.9685 -1.651)
			(end 1.9685 1.651)
			(stroke
				(width 0.1524)
				(type default)
			)
			(layer "F.SilkS")
		)
		(fp_line
			(start 1.9685 1.651)
			(end -1.9685 1.651)
			(stroke
				(width 0.1524)
				(type default)
			)
			(layer "F.SilkS")
		)
		(fp_poly
			(pts
				(xy -0.561594 -1.726946) (xy -0.053594 -2.234946) (xy -1.069594 -2.234946)
			)
			(stroke
				(width 0)
				(type default)
			)
			(fill yes)
			(layer "F.SilkS")
		)
		(fp_rect
			(start -1.524 0.7493)
			(end 1.524 -0.7493)
			(stroke
				(width 0)
				(type default)
			)
			(fill no)
			(layer "F.CrtYd")
		)
		(fp_poly
			(pts
				(xy -2.2225 1.905) (xy -2.2225 -1.905) (xy 2.2225 -1.905) (xy 2.2225 -0.7493) (xy -1.524 -0.7493)
				(xy -1.524 0.7493) (xy 1.524 0.7493) (xy 1.524 -0.7366) (xy 2.2225 -0.7366) (xy 2.2225 1.905)
			)
			(stroke
				(width 0)
				(type default)
			)
			(fill no)
			(layer "F.CrtYd")
		)
		(fp_rect
			(start -2.2225 1.905)
			(end 2.2225 -1.905)
			(stroke
				(width 0)
				(type default)
			)
			(fill no)
			(layer "F.Fab")
		)
		(pad "1" smd rect
			(at -0.5715 -0.813562)
			(size 2.286 1.143)
			(layers "F.Cu" "F.Mask" "F.Paste")
			(net "P12V_AUX")
		)
		(pad "2" smd rect
			(at -0.5715 0.813562)
			(size 2.286 1.143)
			(layers "F.Cu" "F.Mask" "F.Paste")
			(net "P12V_SENSE_TRACE")
		)
		(pad "3" smd rect
			(at 1.334008 -0.813562)
			(size 0.762 1.143)
			(layers "F.Cu" "F.Mask" "F.Paste")
			(net "SENSE+_R4")
		)
		(pad "4" smd rect
			(at 1.334008 0.813562)
			(size 0.762 1.143)
			(layers "F.Cu" "F.Mask" "F.Paste")
			(net "SENSE-_R4")
		)
		(zone
			(layer "F.Cu")
			(hatch none 0.5)
			(connect_pads
				(clearance 0)
			)
			(min_thickness 0.25)
			(keepout
				(tracks not_allowed)
				(vias allowed)
				(pads allowed)
				(copperpour not_allowed)
				(footprints allowed)
			)
			(placement
				(enabled no)
				(sheetname "")
			)
			(fill
				(thermal_gap 0.5)
				(thermal_bridge_width 0.5)
				(island_removal_mode 0)
			)
			(polygon
				(pts
					(xy 41.2115 -410.833062) (xy 41.593008 -410.833062) (xy 41.593008 -411.3403) (xy 41.2115 -411.3403)
				)
			)
		)
		(zone
			(layer "F.Cu")
			(hatch none 0.5)
			(connect_pads
				(clearance 0)
			)
			(min_thickness 0.25)
			(keepout
				(tracks allowed)
				(vias not_allowed)
				(pads allowed)
				(copperpour not_allowed)
				(footprints allowed)
			)
			(placement
				(enabled no)
				(sheetname "")
			)
			(fill
				(thermal_gap 0.5)
				(thermal_bridge_width 0.5)
				(island_removal_mode 0)
			)
			(polygon
				(pts
					(xy 41.2115 -410.833062) (xy 41.593008 -410.833062) (xy 41.593008 -411.3403) (xy 41.2115 -411.3403)
				)
			)
		)
		(zone
			(layer "F.Cu")
			(hatch none 0.5)
			(connect_pads
				(clearance 0)
			)
			(min_thickness 0.25)
			(keepout
				(tracks allowed)
				(vias not_allowed)
				(pads allowed)
				(copperpour not_allowed)
				(footprints allowed)
			)
			(placement
				(enabled no)
				(sheetname "")
			)
			(fill
				(thermal_gap 0.5)
				(thermal_bridge_width 0.5)
				(island_removal_mode 0)
			)
			(polygon
				(pts
					(xy 41.2115 -409.8417) (xy 41.593008 -409.8417) (xy 41.593008 -410.348938) (xy 41.2115 -410.348938)
				)
			)
		)
		(zone
			(layer "F.Cu")
			(hatch none 0.5)
			(connect_pads
				(clearance 0)
			)
			(min_thickness 0.25)
			(keepout
				(tracks not_allowed)
				(vias allowed)
				(pads allowed)
				(copperpour not_allowed)
				(footprints allowed)
			)
			(placement
				(enabled no)
				(sheetname "")
			)
			(fill
				(thermal_gap 0.5)
				(thermal_bridge_width 0.5)
				(island_removal_mode 0)
			)
			(polygon
				(pts
					(xy 41.2115 -409.8417) (xy 41.593008 -409.8417) (xy 41.593008 -410.348938) (xy 41.2115 -410.348938)
				)
			)
		)
	)
	(footprint ""
		(layer "F.Cu")
		(at 43.8912 -90.6018 90)
		(property "Reference" "TC6"
			(at 0 0 90)
			(layer "F.SilkS")
			(hide yes)
			(effects
				(font
					(size 1.27 1.27)
				)
			)
		)
		(property "Value" "ST68U16VDM-1-GP"
			(at 0 -9.6012 90)
			(unlocked yes)
			(layer "F.Fab")
			(hide yes)
			(effects
				(font
					(size 1.016 1.016)
					(thickness 0.1524)
				)
			)
		)
		(property "Device Type" "CT7343H79"
			(at 0 -11.1252 90)
			(unlocked yes)
			(layer "F.Fab")
			(hide yes)
			(effects
				(font
					(size 1.016 1.016)
					(thickness 0.1524)
				)
			)
		)
		(duplicate_pad_numbers_are_jumpers no)
		(fp_line
			(start 2.286 -4.8768)
			(end -2.286 -4.8768)
			(stroke
				(width 0.1524)
				(type default)
			)
			(layer "F.SilkS")
		)
		(fp_line
			(start -2.286 -4.8768)
			(end -2.286 -2.032)
			(stroke
				(width 0.1524)
				(type default)
			)
			(layer "F.SilkS")
		)
		(fp_line
			(start 2.1082 -4.699)
			(end -2.1082 -4.699)
			(stroke
				(width 0.508)
				(type default)
			)
			(layer "F.SilkS")
		)
		(fp_line
			(start 2.286 -2.032)
			(end 2.286 -4.8768)
			(stroke
				(width 0.1524)
				(type default)
			)
			(layer "F.SilkS")
		)
		(fp_line
			(start 2.286 2.032)
			(end 2.286 4.8768)
			(stroke
				(width 0.1524)
				(type default)
			)
			(layer "F.SilkS")
		)
		(fp_line
			(start 2.286 4.8768)
			(end -2.286 4.8768)
			(stroke
				(width 0.1524)
				(type default)
			)
			(layer "F.SilkS")
		)
		(fp_line
			(start -2.286 4.8768)
			(end -2.286 2.032)
			(stroke
				(width 0.1524)
				(type default)
			)
			(layer "F.SilkS")
		)
		(fp_rect
			(start -2.1463 3.6449)
			(end 2.1463 -3.6449)
			(stroke
				(width 0)
				(type default)
			)
			(fill no)
			(layer "F.CrtYd")
		)
		(fp_poly
			(pts
				(xy -2.54 4.953) (xy -2.54 4.2926) (xy -3.81 4.2926) (xy -3.81 -4.2926) (xy -2.54 -4.2926) (xy -2.54 -4.953)
				(xy 2.54 -4.953) (xy 2.54 -4.2926) (xy 3.81 -4.2926) (xy 3.81 -1.6256) (xy 2.1463 -1.6256) (xy 2.1463 -3.6449)
				(xy -2.1463 -3.6449) (xy -2.1463 3.6449) (xy 2.1463 3.6449) (xy 2.1463 -1.6129) (xy 3.81 -1.6129)
				(xy 3.81 4.2926) (xy 2.54 4.2926) (xy 2.54 4.953)
			)
			(stroke
				(width 0)
				(type default)
			)
			(fill no)
			(layer "F.CrtYd")
		)
		(fp_rect
			(start 2.54 4.2926)
			(end 3.81 -4.2926)
			(stroke
				(width 0)
				(type default)
			)
			(fill no)
			(layer "F.Fab")
		)
		(fp_rect
			(start -3.81 4.2926)
			(end -2.54 -4.2926)
			(stroke
				(width 0)
				(type default)
			)
			(fill no)
			(layer "F.Fab")
		)
		(fp_rect
			(start -2.54 4.953)
			(end 2.54 -4.953)
			(stroke
				(width 0)
				(type default)
			)
			(fill no)
			(layer "F.Fab")
		)
		(pad "1" smd rect
			(at 0 -3.1496 90)
			(size 2.413 2.286)
			(layers "F.Cu" "F.Mask" "F.Paste")
			(net "P12VL")
		)
		(pad "2" smd rect
			(at 0 3.1496 90)
			(size 2.413 2.286)
			(layers "F.Cu" "F.Mask" "F.Paste")
			(net "GND")
		)
		(zone
			(layer "F.Cu")
			(hatch none 0.5)
			(connect_pads
				(clearance 0)
			)
			(min_thickness 0.25)
			(keepout
				(tracks allowed)
				(vias not_allowed)
				(pads allowed)
				(copperpour not_allowed)
				(footprints allowed)
			)
			(placement
				(enabled no)
				(sheetname "")
			)
			(fill
				(thermal_gap 0.5)
				(thermal_bridge_width 0.5)
				(island_removal_mode 0)
			)
			(polygon
				(pts
					(xy 42.2021 -92.1131) (xy 39.2938 -92.1131) (xy 39.2938 -89.0905) (xy 42.1894 -89.0905) (xy 42.5196 -89.0905)
					(xy 42.5196 -92.1131)
				)
			)
		)
		(zone
			(layer "F.Cu")
			(hatch none 0.5)
			(connect_pads
				(clearance 0)
			)
			(min_thickness 0.25)
			(keepout
				(tracks allowed)
				(vias not_allowed)
				(pads allowed)
				(copperpour not_allowed)
				(footprints allowed)
			)
			(placement
				(enabled no)
				(sheetname "")
			)
			(fill
				(thermal_gap 0.5)
				(thermal_bridge_width 0.5)
				(island_removal_mode 0)
			)
			(polygon
				(pts
					(xy 48.4886 -89.0905) (xy 48.4886 -92.1131) (xy 45.593 -92.1131) (xy 45.2628 -92.1131) (xy 45.2628 -89.0905)
					(xy 45.593 -89.0905)
				)
			)
		)
	)
	(footprint ""
		(layer "F.Cu")
		(at 28.1686 -224.3074)
		(property "Reference" "R140"
			(at 0 0 0)
			(layer "F.SilkS")
			(hide yes)
			(effects
				(font
					(size 1.27 1.27)
				)
			)
		)
		(property "Value" "0R2J-2-GP"
			(at 0.064008 -3.993896 0)
			(unlocked yes)
			(layer "F.Fab")
			(hide yes)
			(effects
				(font
					(size 1.016 1.016)
					(thickness 0.1524)
				)
			)
		)
		(property "Device Type" "R402H16"
			(at 0.064008 -5.517896 0)
			(unlocked yes)
			(layer "F.Fab")
			(hide yes)
			(effects
				(font
					(size 1.016 1.016)
					(thickness 0.1524)
				)
			)
		)
		(duplicate_pad_numbers_are_jumpers no)
		(fp_line
			(start -0.508 -0.9398)
			(end -0.508 0.9398)
			(stroke
				(width 0.1524)
				(type default)
			)
			(layer "F.SilkS")
		)
		(fp_line
			(start 0.508 -0.9398)
			(end -0.508 -0.9398)
			(stroke
				(width 0.1524)
				(type default)
			)
			(layer "F.SilkS")
		)
		(fp_rect
			(start -0.508 0.9398)
			(end 0.508 -0.9398)
			(stroke
				(width 0)
				(type default)
			)
			(fill no)
			(layer "F.CrtYd")
		)
		(fp_rect
			(start -0.508 0.9398)
			(end 0.508 -0.9398)
			(stroke
				(width 0)
				(type default)
			)
			(fill no)
			(layer "F.Fab")
		)
		(pad "1" smd custom
			(at 0 -0.4445)
			(size 0.1397 0.1397)
			(layers "F.Cu" "F.Mask" "F.Paste")
			(net "PWM_OUT_FAN2_NET")
			(options
				(clearance outline)
				(anchor circle)
			)
			(primitives
				(gr_poly
					(pts
						(arc
							(start -0.1778 -0.2794)
							(mid -0.249642 -0.249642)
							(end -0.2794 -0.1778)
						)
						(arc
							(start -0.2794 0.1778)
							(mid -0.249642 0.249642)
							(end -0.1778 0.2794)
						)
						(arc
							(start 0.1778 0.2794)
							(mid 0.249642 0.249642)
							(end 0.2794 0.1778)
						)
						(arc
							(start 0.2794 -0.1778)
							(mid 0.249642 -0.249642)
							(end 0.1778 -0.2794)
						)
					)
					(width 0)
					(fill yes)
				)
			)
		)
		(pad "2" smd custom
			(at 0 0.4445)
			(size 0.1397 0.1397)
			(layers "F.Cu" "F.Mask" "F.Paste")
			(net "PWM_OUT_FAN2")
			(options
				(clearance outline)
				(anchor circle)
			)
			(primitives
				(gr_poly
					(pts
						(arc
							(start -0.1778 -0.2794)
							(mid -0.249642 -0.249642)
							(end -0.2794 -0.1778)
						)
						(arc
							(start -0.2794 0.1778)
							(mid -0.249642 0.249642)
							(end -0.1778 0.2794)
						)
						(arc
							(start 0.1778 0.2794)
							(mid 0.249642 0.249642)
							(end 0.2794 0.1778)
						)
						(arc
							(start 0.2794 -0.1778)
							(mid 0.249642 -0.249642)
							(end 0.1778 -0.2794)
						)
					)
					(width 0)
					(fill yes)
				)
			)
		)
	)
	(footprint ""
		(layer "F.Cu")
		(at 19.1262 -241.1984 90)
		(property "Reference" "PL7"
			(at 0 0 90)
			(layer "F.SilkS")
			(hide yes)
			(effects
				(font
					(size 1.27 1.27)
				)
			)
		)
		(property "Value" "IND-22UH-169-GP"
			(at -4.7498 0.5588 90)
			(unlocked yes)
			(layer "F.Fab")
			(hide yes)
			(effects
				(font
					(size 1.016 1.016)
					(thickness 0.1524)
				)
			)
		)
		(property "Device Type" "L6362-D620H119"
			(at -4.7498 -0.9652 90)
			(unlocked yes)
			(layer "F.Fab")
			(hide yes)
			(effects
				(font
					(size 1.016 1.016)
					(thickness 0.1524)
				)
			)
		)
		(duplicate_pad_numbers_are_jumpers no)
		(fp_line
			(start 1.667256 -3.8989)
			(end 3.3528 -2.213356)
			(stroke
				(width 0.1524)
				(type default)
			)
			(layer "F.SilkS")
		)
		(fp_line
			(start -1.667256 -3.8989)
			(end 1.667256 -3.8989)
			(stroke
				(width 0.1524)
				(type default)
			)
			(layer "F.SilkS")
		)
		(fp_line
			(start 3.3528 -2.213356)
			(end 3.3528 2.213356)
			(stroke
				(width 0.1524)
				(type default)
			)
			(layer "F.SilkS")
		)
		(fp_line
			(start -3.3528 -2.213356)
			(end -1.667256 -3.8989)
			(stroke
				(width 0.1524)
				(type default)
			)
			(layer "F.SilkS")
		)
		(fp_line
			(start 3.3528 2.213356)
			(end 1.667256 3.8989)
			(stroke
				(width 0.1524)
				(type default)
			)
			(layer "F.SilkS")
		)
		(fp_line
			(start -3.3528 2.213356)
			(end -3.3528 -2.213356)
			(stroke
				(width 0.1524)
				(type default)
			)
			(layer "F.SilkS")
		)
		(fp_line
			(start 1.667256 3.8989)
			(end -1.667256 3.8989)
			(stroke
				(width 0.1524)
				(type default)
			)
			(layer "F.SilkS")
		)
		(fp_line
			(start -1.667256 3.8989)
			(end -3.3528 2.213356)
			(stroke
				(width 0.1524)
				(type default)
			)
			(layer "F.SilkS")
		)
		(fp_poly
			(pts
				(xy 2.0574 3.1496) (xy -2.0574 3.1496) (xy -3.0988 2.1082) (xy -3.0988 -2.1082) (xy -2.0574 -3.1496)
				(xy 2.0574 -3.1496) (xy 3.0988 -2.1082) (xy 3.0988 2.1082)
			)
			(stroke
				(width 0)
				(type default)
			)
			(fill no)
			(layer "F.CrtYd")
		)
		(fp_poly
			(pts
				(xy 3.6068 2.318512) (xy 1.950212 3.9751) (xy -1.950212 3.9751) (xy -3.6068 2.318512) (xy -3.6068 -2.318512)
				(xy -1.950212 -3.9751) (xy 1.950212 -3.9751) (xy 3.6068 -2.318512) (xy 3.6068 -1.9177) (xy 3.0988 -1.9177)
				(xy 3.0988 -2.1082) (xy 2.0574 -3.1496) (xy -2.0574 -3.1496) (xy -3.0988 -2.1082) (xy -3.0988 2.1082)
				(xy -2.0574 3.1496) (xy 2.0574 3.1496) (xy 3.0988 2.1082) (xy 3.0988 -1.905) (xy 3.6068 -1.905)
			)
			(stroke
				(width 0)
				(type default)
			)
			(fill no)
			(layer "F.CrtYd")
		)
		(fp_poly
			(pts
				(xy -1.950212 3.9751) (xy -3.6068 2.318512) (xy -3.6068 -2.318512) (xy -1.950212 -3.9751) (xy 1.950212 -3.9751)
				(xy 3.6068 -2.318512) (xy 3.6068 2.318512) (xy 1.950212 3.9751)
			)
			(stroke
				(width 0)
				(type default)
			)
			(fill no)
			(layer "F.Fab")
		)
		(pad "1" smd rect
			(at 0 -2.895346 90)
			(size 2.2606 1.4986)
			(layers "F.Cu" "F.Mask" "F.Paste")
			(net "P3V3_LX")
		)
		(pad "2" smd rect
			(at 0 2.895346 90)
			(size 2.2606 1.4986)
			(layers "F.Cu" "F.Mask" "F.Paste")
			(net "P3V3_LX_COPPER")
		)
	)
	(footprint ""
		(layer "F.Cu")
		(at 11.811 -426.847 90)
		(property "Reference" "PD2"
			(at 0 0 90)
			(layer "F.SilkS")
			(hide yes)
			(effects
				(font
					(size 1.27 1.27)
				)
			)
		)
		(property "Value" "SMCJ15A-1-GP"
			(at -4.7244 1.5748 90)
			(unlocked yes)
			(layer "F.Fab")
			(hide yes)
			(effects
				(font
					(size 1.016 1.016)
					(thickness 0.1524)
				)
			)
		)
		(property "Device Type" "TVS794591-114297H104"
			(at -4.7244 0.0508 90)
			(unlocked yes)
			(layer "F.Fab")
			(hide yes)
			(effects
				(font
					(size 1.016 1.016)
					(thickness 0.1524)
				)
			)
		)
		(duplicate_pad_numbers_are_jumpers no)
		(fp_line
			(start 3.2004 -4.8641)
			(end -3.2004 -4.8641)
			(stroke
				(width 0.1524)
				(type default)
			)
			(layer "F.SilkS")
		)
		(fp_line
			(start -3.2004 -4.8641)
			(end -3.2004 4.8641)
			(stroke
				(width 0.1524)
				(type default)
			)
			(layer "F.SilkS")
		)
		(fp_line
			(start 3.2004 4.8641)
			(end 3.2004 -4.8641)
			(stroke
				(width 0.1524)
				(type default)
			)
			(layer "F.SilkS")
		)
		(fp_line
			(start -3.2004 4.8641)
			(end 3.2004 4.8641)
			(stroke
				(width 0.1524)
				(type default)
			)
			(layer "F.SilkS")
		)
		(fp_line
			(start 3.2004 5.0419)
			(end -3.2004 5.0419)
			(stroke
				(width 0.508)
				(type default)
			)
			(layer "F.SilkS")
		)
		(fp_rect
			(start -2.9464 3.9751)
			(end 2.9464 -3.9751)
			(stroke
				(width 0)
				(type default)
			)
			(fill no)
			(layer "F.CrtYd")
		)
		(fp_poly
			(pts
				(xy -3.4544 4.9403) (xy -3.4544 -4.9403) (xy 3.4544 -4.9403) (xy 3.4544 3.9624) (xy 2.9464 3.9624)
				(xy 2.9464 -3.9751) (xy -2.9464 -3.9751) (xy -2.9464 3.9751) (xy 3.4544 3.9751) (xy 3.4544 4.9403)
			)
			(stroke
				(width 0)
				(type default)
			)
			(fill no)
			(layer "F.CrtYd")
		)
		(fp_rect
			(start -3.4544 4.9403)
			(end 3.4544 -4.9403)
			(stroke
				(width 0)
				(type default)
			)
			(fill no)
			(layer "F.Fab")
		)
		(pad "A" smd rect
			(at 0 -3.591814 90)
			(size 3.2258 2.032)
			(layers "F.Cu" "F.Mask" "F.Paste")
			(net "GND")
		)
		(pad "K" smd rect
			(at 0 3.591814 90)
			(size 3.2258 2.032)
			(layers "F.Cu" "F.Mask" "F.Paste")
			(net "P12V_AUX")
		)
	)
	(footprint ""
		(layer "F.Cu")
		(at 6.1214 -174.7774 180)
		(property "Reference" "C53"
			(at 0 0 180)
			(layer "F.SilkS")
			(hide yes)
			(effects
				(font
					(size 1.27 1.27)
				)
			)
		)
		(property "Value" "SC1U16V3KX-5GP"
			(at 0 -2.8194 180)
			(unlocked yes)
			(layer "F.Fab")
			(hide yes)
			(effects
				(font
					(size 1.016 1.016)
					(thickness 0.1524)
				)
			)
		)
		(property "Device Type" "C603H36"
			(at 0 -4.3434 180)
			(unlocked yes)
			(layer "F.Fab")
			(hide yes)
			(effects
				(font
					(size 1.016 1.016)
					(thickness 0.1524)
				)
			)
		)
		(duplicate_pad_numbers_are_jumpers no)
		(fp_line
			(start 0.508 0)
			(end -0.508 0)
			(stroke
				(width 0.2032)
				(type default)
			)
			(layer "F.SilkS")
		)
		(fp_rect
			(start -0.5842 1.3335)
			(end 0.5842 -1.3335)
			(stroke
				(width 0)
				(type default)
			)
			(fill no)
			(layer "F.CrtYd")
		)
		(fp_rect
			(start -0.5842 1.3335)
			(end 0.5842 -1.3335)
			(stroke
				(width 0)
				(type default)
			)
			(fill no)
			(layer "F.Fab")
		)
		(pad "1" smd custom
			(at 0 -0.762 180)
			(size 0.2159 0.2159)
			(layers "F.Cu" "F.Mask" "F.Paste")
			(net "P3V3")
			(options
				(clearance outline)
				(anchor circle)
			)
			(primitives
				(gr_poly
					(pts
						(arc
							(start -0.3302 -0.4318)
							(mid -0.402042 -0.402042)
							(end -0.4318 -0.3302)
						)
						(arc
							(start -0.4318 0.3302)
							(mid -0.402042 0.402042)
							(end -0.3302 0.4318)
						)
						(arc
							(start 0.3302 0.4318)
							(mid 0.402042 0.402042)
							(end 0.4318 0.3302)
						)
						(arc
							(start 0.4318 -0.3302)
							(mid 0.402042 -0.402042)
							(end 0.3302 -0.4318)
						)
					)
					(width 0)
					(fill yes)
				)
			)
		)
		(pad "2" smd custom
			(at 0 0.762 180)
			(size 0.2159 0.2159)
			(layers "F.Cu" "F.Mask" "F.Paste")
			(net "GND")
			(options
				(clearance outline)
				(anchor circle)
			)
			(primitives
				(gr_poly
					(pts
						(arc
							(start -0.3302 -0.4318)
							(mid -0.402042 -0.402042)
							(end -0.4318 -0.3302)
						)
						(arc
							(start -0.4318 0.3302)
							(mid -0.402042 0.402042)
							(end -0.3302 0.4318)
						)
						(arc
							(start 0.3302 0.4318)
							(mid 0.402042 0.402042)
							(end 0.4318 0.3302)
						)
						(arc
							(start 0.4318 -0.3302)
							(mid 0.402042 -0.402042)
							(end 0.3302 -0.4318)
						)
					)
					(width 0)
					(fill yes)
				)
			)
		)
	)
	(footprint ""
		(layer "F.Cu")
		(at 14.8844 -39.4462 90)
		(property "Reference" "R120"
			(at 0 0 90)
			(layer "F.SilkS")
			(hide yes)
			(effects
				(font
					(size 1.27 1.27)
				)
			)
		)
		(property "Value" "470R2F-GP"
			(at 0.064008 -3.993896 90)
			(unlocked yes)
			(layer "F.Fab")
			(hide yes)
			(effects
				(font
					(size 1.016 1.016)
					(thickness 0.1524)
				)
			)
		)
		(property "Device Type" "R402H16"
			(at 0.064008 -5.517896 90)
			(unlocked yes)
			(layer "F.Fab")
			(hide yes)
			(effects
				(font
					(size 1.016 1.016)
					(thickness 0.1524)
				)
			)
		)
		(duplicate_pad_numbers_are_jumpers no)
		(fp_line
			(start 0.508 -0.9398)
			(end -0.508 -0.9398)
			(stroke
				(width 0.1524)
				(type default)
			)
			(layer "F.SilkS")
		)
		(fp_line
			(start -0.508 -0.9398)
			(end -0.508 0.9398)
			(stroke
				(width 0.1524)
				(type default)
			)
			(layer "F.SilkS")
		)
		(fp_rect
			(start -0.508 0.9398)
			(end 0.508 -0.9398)
			(stroke
				(width 0)
				(type default)
			)
			(fill no)
			(layer "F.CrtYd")
		)
		(fp_rect
			(start -0.508 0.9398)
			(end 0.508 -0.9398)
			(stroke
				(width 0)
				(type default)
			)
			(fill no)
			(layer "F.Fab")
		)
		(pad "1" smd custom
			(at 0 -0.4445 90)
			(size 0.1397 0.1397)
			(layers "F.Cu" "F.Mask" "F.Paste")
			(net "SEB_PEER_2B_HB")
			(options
				(clearance outline)
				(anchor circle)
			)
			(primitives
				(gr_poly
					(pts
						(arc
							(start -0.1778 -0.2794)
							(mid -0.249642 -0.249642)
							(end -0.2794 -0.1778)
						)
						(arc
							(start -0.2794 0.1778)
							(mid -0.249642 0.249642)
							(end -0.1778 0.2794)
						)
						(arc
							(start 0.1778 0.2794)
							(mid 0.249642 0.249642)
							(end 0.2794 0.1778)
						)
						(arc
							(start 0.2794 -0.1778)
							(mid 0.249642 -0.249642)
							(end 0.1778 -0.2794)
						)
					)
					(width 0)
					(fill yes)
				)
			)
		)
		(pad "2" smd custom
			(at 0 0.4445 90)
			(size 0.1397 0.1397)
			(layers "F.Cu" "F.Mask" "F.Paste")
			(net "GND")
			(options
				(clearance outline)
				(anchor circle)
			)
			(primitives
				(gr_poly
					(pts
						(arc
							(start -0.1778 -0.2794)
							(mid -0.249642 -0.249642)
							(end -0.2794 -0.1778)
						)
						(arc
							(start -0.2794 0.1778)
							(mid -0.249642 0.249642)
							(end -0.1778 0.2794)
						)
						(arc
							(start 0.1778 0.2794)
							(mid 0.249642 0.249642)
							(end 0.2794 0.1778)
						)
						(arc
							(start 0.2794 -0.1778)
							(mid 0.249642 -0.249642)
							(end 0.1778 -0.2794)
						)
					)
					(width 0)
					(fill yes)
				)
			)
		)
	)
	(footprint ""
		(layer "F.Cu")
		(at 37.032692 -289.281362 180)
		(property "Reference" "TC17"
			(at 0 0 180)
			(layer "F.SilkS")
			(hide yes)
			(effects
				(font
					(size 1.27 1.27)
				)
			)
		)
		(property "Value" "ST15U25VDM-1-GP"
			(at 0 -9.6012 180)
			(unlocked yes)
			(layer "F.Fab")
			(hide yes)
			(effects
				(font
					(size 1.016 1.016)
					(thickness 0.1524)
				)
			)
		)
		(property "Device Type" "CT7343H79"
			(at 0 -11.1252 180)
			(unlocked yes)
			(layer "F.Fab")
			(hide yes)
			(effects
				(font
					(size 1.016 1.016)
					(thickness 0.1524)
				)
			)
		)
		(duplicate_pad_numbers_are_jumpers no)
		(fp_line
			(start 2.286 4.8768)
			(end -2.286 4.8768)
			(stroke
				(width 0.1524)
				(type default)
			)
			(layer "F.SilkS")
		)
		(fp_line
			(start 2.286 2.032)
			(end 2.286 4.8768)
			(stroke
				(width 0.1524)
				(type default)
			)
			(layer "F.SilkS")
		)
		(fp_line
			(start 2.286 -2.032)
			(end 2.286 -4.8768)
			(stroke
				(width 0.1524)
				(type default)
			)
			(layer "F.SilkS")
		)
		(fp_line
			(start 2.286 -4.8768)
			(end -2.286 -4.8768)
			(stroke
				(width 0.1524)
				(type default)
			)
			(layer "F.SilkS")
		)
		(fp_line
			(start 2.1082 -4.699)
			(end -2.1082 -4.699)
			(stroke
				(width 0.508)
				(type default)
			)
			(layer "F.SilkS")
		)
		(fp_line
			(start -2.286 4.8768)
			(end -2.286 2.032)
			(stroke
				(width 0.1524)
				(type default)
			)
			(layer "F.SilkS")
		)
		(fp_line
			(start -2.286 -4.8768)
			(end -2.286 -2.032)
			(stroke
				(width 0.1524)
				(type default)
			)
			(layer "F.SilkS")
		)
		(fp_rect
			(start -2.1463 3.6449)
			(end 2.1463 -3.6449)
			(stroke
				(width 0)
				(type default)
			)
			(fill no)
			(layer "F.CrtYd")
		)
		(fp_poly
			(pts
				(xy -2.54 4.953) (xy -2.54 4.2926) (xy -3.81 4.2926) (xy -3.81 -4.2926) (xy -2.54 -4.2926) (xy -2.54 -4.953)
				(xy 2.54 -4.953) (xy 2.54 -4.2926) (xy 3.81 -4.2926) (xy 3.81 -1.6256) (xy 2.1463 -1.6256) (xy 2.1463 -3.6449)
				(xy -2.1463 -3.6449) (xy -2.1463 3.6449) (xy 2.1463 3.6449) (xy 2.1463 -1.6129) (xy 3.81 -1.6129)
				(xy 3.81 4.2926) (xy 2.54 4.2926) (xy 2.54 4.953)
			)
			(stroke
				(width 0)
				(type default)
			)
			(fill no)
			(layer "F.CrtYd")
		)
		(fp_rect
			(start 2.54 4.2926)
			(end 3.81 -4.2926)
			(stroke
				(width 0)
				(type default)
			)
			(fill no)
			(layer "F.Fab")
		)
		(fp_rect
			(start -2.54 4.953)
			(end 2.54 -4.953)
			(stroke
				(width 0)
				(type default)
			)
			(fill no)
			(layer "F.Fab")
		)
		(fp_rect
			(start -3.81 4.2926)
			(end -2.54 -4.2926)
			(stroke
				(width 0)
				(type default)
			)
			(fill no)
			(layer "F.Fab")
		)
		(pad "1" smd rect
			(at 0 -3.1496 180)
			(size 2.413 2.286)
			(layers "F.Cu" "F.Mask" "F.Paste")
			(net "P12V")
		)
		(pad "2" smd rect
			(at 0 3.1496 180)
			(size 2.413 2.286)
			(layers "F.Cu" "F.Mask" "F.Paste")
			(net "GND")
		)
		(zone
			(layer "F.Cu")
			(hatch none 0.5)
			(connect_pads
				(clearance 0)
			)
			(min_thickness 0.25)
			(keepout
				(tracks allowed)
				(vias not_allowed)
				(pads allowed)
				(copperpour not_allowed)
				(footprints allowed)
			)
			(placement
				(enabled no)
				(sheetname "")
			)
			(fill
				(thermal_gap 0.5)
				(thermal_bridge_width 0.5)
				(island_removal_mode 0)
			)
			(polygon
				(pts
					(xy 35.521392 -287.592262) (xy 35.521392 -284.683962) (xy 38.543992 -284.683962) (xy 38.543992 -287.579562)
					(xy 38.543992 -287.909762) (xy 35.521392 -287.909762)
				)
			)
		)
		(zone
			(layer "F.Cu")
			(hatch none 0.5)
			(connect_pads
				(clearance 0)
			)
			(min_thickness 0.25)
			(keepout
				(tracks allowed)
				(vias not_allowed)
				(pads allowed)
				(copperpour not_allowed)
				(footprints allowed)
			)
			(placement
				(enabled no)
				(sheetname "")
			)
			(fill
				(thermal_gap 0.5)
				(thermal_bridge_width 0.5)
				(island_removal_mode 0)
			)
			(polygon
				(pts
					(xy 38.543992 -293.878762) (xy 35.521392 -293.878762) (xy 35.521392 -290.983162) (xy 35.521392 -290.652962)
					(xy 38.543992 -290.652962) (xy 38.543992 -290.983162)
				)
			)
		)
	)
	(footprint ""
		(layer "F.Cu")
		(at 17.9832 -248.5644 180)
		(property "Reference" "PR52"
			(at 0 0 180)
			(layer "F.SilkS")
			(hide yes)
			(effects
				(font
					(size 1.27 1.27)
				)
			)
		)
		(property "Value" "47KR3F-GP"
			(at -0.0254 -2.5146 180)
			(unlocked yes)
			(layer "F.Fab")
			(hide yes)
			(effects
				(font
					(size 1.016 1.016)
					(thickness 0.1524)
				)
			)
		)
		(property "Device Type" "R603H22"
			(at -0.0254 -4.0386 180)
			(unlocked yes)
			(layer "F.Fab")
			(hide yes)
			(effects
				(font
					(size 1.016 1.016)
					(thickness 0.1524)
				)
			)
		)
		(duplicate_pad_numbers_are_jumpers no)
		(fp_line
			(start 0.2032 0)
			(end 0.4826 0)
			(stroke
				(width 0.2032)
				(type default)
			)
			(layer "F.SilkS")
		)
		(fp_line
			(start -0.4826 0)
			(end -0.2032 0)
			(stroke
				(width 0.2032)
				(type default)
			)
			(layer "F.SilkS")
		)
		(fp_rect
			(start -0.5842 1.3335)
			(end 0.5842 -1.3335)
			(stroke
				(width 0)
				(type default)
			)
			(fill no)
			(layer "F.CrtYd")
		)
		(fp_rect
			(start -0.5842 1.3335)
			(end 0.5842 -1.3335)
			(stroke
				(width 0)
				(type default)
			)
			(fill no)
			(layer "F.Fab")
		)
		(pad "1" smd custom
			(at 0 -0.762 180)
			(size 0.2159 0.2159)
			(layers "F.Cu" "F.Mask" "F.Paste")
			(net "P3V3_IN")
			(options
				(clearance outline)
				(anchor circle)
			)
			(primitives
				(gr_poly
					(pts
						(arc
							(start -0.3302 -0.4318)
							(mid -0.402042 -0.402042)
							(end -0.4318 -0.3302)
						)
						(arc
							(start -0.4318 0.3302)
							(mid -0.402042 0.402042)
							(end -0.3302 0.4318)
						)
						(arc
							(start 0.3302 0.4318)
							(mid 0.402042 0.402042)
							(end 0.4318 0.3302)
						)
						(arc
							(start 0.4318 -0.3302)
							(mid 0.402042 -0.402042)
							(end 0.3302 -0.4318)
						)
					)
					(width 0)
					(fill yes)
				)
			)
		)
		(pad "2" smd custom
			(at 0 0.762 180)
			(size 0.2159 0.2159)
			(layers "F.Cu" "F.Mask" "F.Paste")
			(net "P3V3_EN")
			(options
				(clearance outline)
				(anchor circle)
			)
			(primitives
				(gr_poly
					(pts
						(arc
							(start -0.3302 -0.4318)
							(mid -0.402042 -0.402042)
							(end -0.4318 -0.3302)
						)
						(arc
							(start -0.4318 0.3302)
							(mid -0.402042 0.402042)
							(end -0.3302 0.4318)
						)
						(arc
							(start 0.3302 0.4318)
							(mid 0.402042 0.402042)
							(end 0.4318 0.3302)
						)
						(arc
							(start 0.4318 -0.3302)
							(mid 0.402042 -0.402042)
							(end 0.3302 -0.4318)
						)
					)
					(width 0)
					(fill yes)
				)
			)
		)
	)
	(footprint ""
		(layer "F.Cu")
		(at 21.489162 -13.843508 90)
		(property "Reference" "D3"
			(at 0 0 90)
			(layer "F.SilkS")
			(hide yes)
			(effects
				(font
					(size 1.27 1.27)
				)
			)
		)
		(property "Value" "BAS16H-GP"
			(at 0 -5.5372 90)
			(unlocked yes)
			(layer "F.Fab")
			(hide yes)
			(effects
				(font
					(size 1.016 1.016)
					(thickness 0.1524)
				)
			)
		)
		(property "Device Type" "SOD123AKH48"
			(at 0 -7.0612 90)
			(unlocked yes)
			(layer "F.Fab")
			(hide yes)
			(effects
				(font
					(size 1.016 1.016)
					(thickness 0.1524)
				)
			)
		)
		(duplicate_pad_numbers_are_jumpers no)
		(fp_line
			(start 1.016 -2.667)
			(end -1.016 -2.667)
			(stroke
				(width 0.1524)
				(type default)
			)
			(layer "F.SilkS")
		)
		(fp_line
			(start -1.016 -2.667)
			(end -1.016 2.667)
			(stroke
				(width 0.1524)
				(type default)
			)
			(layer "F.SilkS")
		)
		(fp_line
			(start 1.016 2.667)
			(end 1.016 -2.667)
			(stroke
				(width 0.1524)
				(type default)
			)
			(layer "F.SilkS")
		)
		(fp_line
			(start -1.016 2.667)
			(end 1.016 2.667)
			(stroke
				(width 0.1524)
				(type default)
			)
			(layer "F.SilkS")
		)
		(fp_line
			(start 0.889 2.921)
			(end -0.889 2.921)
			(stroke
				(width 0.508)
				(type default)
			)
			(layer "F.SilkS")
		)
		(fp_rect
			(start -1.143 3.175)
			(end 1.143 -2.794)
			(stroke
				(width 0)
				(type default)
			)
			(fill no)
			(layer "F.CrtYd")
		)
		(fp_poly
			(pts
				(xy -1.143 -2.794) (xy 1.143 -2.794) (xy 1.143 3.175) (xy -1.143 3.175)
			)
			(stroke
				(width 0)
				(type default)
			)
			(fill no)
			(layer "F.Fab")
		)
		(pad "A" smd rect
			(at 0 -1.6891 90)
			(size 0.889 1.397)
			(layers "F.Cu" "F.Mask" "F.Paste")
			(net "FAN_TACH11")
		)
		(pad "K" smd rect
			(at 0 1.6891 90)
			(size 0.889 1.397)
			(layers "F.Cu" "F.Mask" "F.Paste")
			(net "P12V")
		)
	)
	(footprint ""
		(layer "F.Cu")
		(at 12.2682 -445.516 180)
		(property "Reference" "R97"
			(at 0 0 180)
			(layer "F.SilkS")
			(hide yes)
			(effects
				(font
					(size 1.27 1.27)
				)
			)
		)
		(property "Value" "4K7R2F-GP"
			(at 0.064008 -3.993896 180)
			(unlocked yes)
			(layer "F.Fab")
			(hide yes)
			(effects
				(font
					(size 1.016 1.016)
					(thickness 0.1524)
				)
			)
		)
		(property "Device Type" "R402H16"
			(at 0.064008 -5.517896 180)
			(unlocked yes)
			(layer "F.Fab")
			(hide yes)
			(effects
				(font
					(size 1.016 1.016)
					(thickness 0.1524)
				)
			)
		)
		(duplicate_pad_numbers_are_jumpers no)
		(fp_line
			(start 0.508 -0.9398)
			(end -0.508 -0.9398)
			(stroke
				(width 0.1524)
				(type default)
			)
			(layer "F.SilkS")
		)
		(fp_line
			(start -0.508 -0.9398)
			(end -0.508 0.9398)
			(stroke
				(width 0.1524)
				(type default)
			)
			(layer "F.SilkS")
		)
		(fp_rect
			(start -0.508 0.9398)
			(end 0.508 -0.9398)
			(stroke
				(width 0)
				(type default)
			)
			(fill no)
			(layer "F.CrtYd")
		)
		(fp_rect
			(start -0.508 0.9398)
			(end 0.508 -0.9398)
			(stroke
				(width 0)
				(type default)
			)
			(fill no)
			(layer "F.Fab")
		)
		(pad "1" smd custom
			(at 0 -0.4445 180)
			(size 0.1397 0.1397)
			(layers "F.Cu" "F.Mask" "F.Paste")
			(net "P12V")
			(options
				(clearance outline)
				(anchor circle)
			)
			(primitives
				(gr_poly
					(pts
						(arc
							(start -0.1778 -0.2794)
							(mid -0.249642 -0.249642)
							(end -0.2794 -0.1778)
						)
						(arc
							(start -0.2794 0.1778)
							(mid -0.249642 0.249642)
							(end -0.1778 0.2794)
						)
						(arc
							(start 0.1778 0.2794)
							(mid 0.249642 0.249642)
							(end 0.2794 0.1778)
						)
						(arc
							(start 0.2794 -0.1778)
							(mid 0.249642 -0.249642)
							(end 0.1778 -0.2794)
						)
					)
					(width 0)
					(fill yes)
				)
			)
		)
		(pad "2" smd custom
			(at 0 0.4445 180)
			(size 0.1397 0.1397)
			(layers "F.Cu" "F.Mask" "F.Paste")
			(net "FAN_TACH2")
			(options
				(clearance outline)
				(anchor circle)
			)
			(primitives
				(gr_poly
					(pts
						(arc
							(start -0.1778 -0.2794)
							(mid -0.249642 -0.249642)
							(end -0.2794 -0.1778)
						)
						(arc
							(start -0.2794 0.1778)
							(mid -0.249642 0.249642)
							(end -0.1778 0.2794)
						)
						(arc
							(start 0.1778 0.2794)
							(mid 0.249642 0.249642)
							(end 0.2794 0.1778)
						)
						(arc
							(start 0.2794 -0.1778)
							(mid 0.249642 -0.249642)
							(end 0.1778 -0.2794)
						)
					)
					(width 0)
					(fill yes)
				)
			)
		)
	)
	(footprint ""
		(layer "F.Cu")
		(at 26.035 -268.8336 90)
		(property "Reference" "C40"
			(at 0 0 90)
			(layer "F.SilkS")
			(hide yes)
			(effects
				(font
					(size 1.27 1.27)
				)
			)
		)
		(property "Value" "SC1U25V3KX-1-GP"
			(at 0 -2.8194 90)
			(unlocked yes)
			(layer "F.Fab")
			(hide yes)
			(effects
				(font
					(size 1.016 1.016)
					(thickness 0.1524)
				)
			)
		)
		(property "Device Type" "C603H36"
			(at 0 -4.3434 90)
			(unlocked yes)
			(layer "F.Fab")
			(hide yes)
			(effects
				(font
					(size 1.016 1.016)
					(thickness 0.1524)
				)
			)
		)
		(duplicate_pad_numbers_are_jumpers no)
		(fp_line
			(start 0.508 0)
			(end -0.508 0)
			(stroke
				(width 0.2032)
				(type default)
			)
			(layer "F.SilkS")
		)
		(fp_rect
			(start -0.5842 1.3335)
			(end 0.5842 -1.3335)
			(stroke
				(width 0)
				(type default)
			)
			(fill no)
			(layer "F.CrtYd")
		)
		(fp_rect
			(start -0.5842 1.3335)
			(end 0.5842 -1.3335)
			(stroke
				(width 0)
				(type default)
			)
			(fill no)
			(layer "F.Fab")
		)
		(pad "1" smd custom
			(at 0 -0.762 90)
			(size 0.2159 0.2159)
			(layers "F.Cu" "F.Mask" "F.Paste")
			(net "P12V")
			(options
				(clearance outline)
				(anchor circle)
			)
			(primitives
				(gr_poly
					(pts
						(arc
							(start -0.3302 -0.4318)
							(mid -0.402042 -0.402042)
							(end -0.4318 -0.3302)
						)
						(arc
							(start -0.4318 0.3302)
							(mid -0.402042 0.402042)
							(end -0.3302 0.4318)
						)
						(arc
							(start 0.3302 0.4318)
							(mid 0.402042 0.402042)
							(end 0.4318 0.3302)
						)
						(arc
							(start 0.4318 -0.3302)
							(mid 0.402042 -0.402042)
							(end 0.3302 -0.4318)
						)
					)
					(width 0)
					(fill yes)
				)
			)
		)
		(pad "2" smd custom
			(at 0 0.762 90)
			(size 0.2159 0.2159)
			(layers "F.Cu" "F.Mask" "F.Paste")
			(net "GND")
			(options
				(clearance outline)
				(anchor circle)
			)
			(primitives
				(gr_poly
					(pts
						(arc
							(start -0.3302 -0.4318)
							(mid -0.402042 -0.402042)
							(end -0.4318 -0.3302)
						)
						(arc
							(start -0.4318 0.3302)
							(mid -0.402042 0.402042)
							(end -0.3302 0.4318)
						)
						(arc
							(start 0.3302 0.4318)
							(mid 0.402042 0.402042)
							(end 0.4318 0.3302)
						)
						(arc
							(start 0.4318 -0.3302)
							(mid 0.402042 -0.402042)
							(end 0.3302 -0.4318)
						)
					)
					(width 0)
					(fill yes)
				)
			)
		)
	)
	(footprint ""
		(layer "F.Cu")
		(at 37.973 -180.34)
		(property "Reference" "R261"
			(at 0 0 0)
			(layer "F.SilkS")
			(hide yes)
			(effects
				(font
					(size 1.27 1.27)
				)
			)
		)
		(property "Value" "10KR2J-3-GP"
			(at 0.064008 -3.993896 0)
			(unlocked yes)
			(layer "F.Fab")
			(hide yes)
			(effects
				(font
					(size 1.016 1.016)
					(thickness 0.1524)
				)
			)
		)
		(property "Device Type" "R402H16"
			(at 0.064008 -5.517896 0)
			(unlocked yes)
			(layer "F.Fab")
			(hide yes)
			(effects
				(font
					(size 1.016 1.016)
					(thickness 0.1524)
				)
			)
		)
		(duplicate_pad_numbers_are_jumpers no)
		(fp_line
			(start -0.508 -0.9398)
			(end -0.508 0.9398)
			(stroke
				(width 0.1524)
				(type default)
			)
			(layer "F.SilkS")
		)
		(fp_line
			(start 0.508 -0.9398)
			(end -0.508 -0.9398)
			(stroke
				(width 0.1524)
				(type default)
			)
			(layer "F.SilkS")
		)
		(fp_rect
			(start -0.508 0.9398)
			(end 0.508 -0.9398)
			(stroke
				(width 0)
				(type default)
			)
			(fill no)
			(layer "F.CrtYd")
		)
		(fp_rect
			(start -0.508 0.9398)
			(end 0.508 -0.9398)
			(stroke
				(width 0)
				(type default)
			)
			(fill no)
			(layer "F.Fab")
		)
		(pad "1" smd custom
			(at 0 -0.4445)
			(size 0.1397 0.1397)
			(layers "F.Cu" "F.Mask" "F.Paste")
			(net "D_LATCH_CLR")
			(options
				(clearance outline)
				(anchor circle)
			)
			(primitives
				(gr_poly
					(pts
						(arc
							(start -0.1778 -0.2794)
							(mid -0.249642 -0.249642)
							(end -0.2794 -0.1778)
						)
						(arc
							(start -0.2794 0.1778)
							(mid -0.249642 0.249642)
							(end -0.1778 0.2794)
						)
						(arc
							(start 0.1778 0.2794)
							(mid 0.249642 0.249642)
							(end 0.2794 0.1778)
						)
						(arc
							(start 0.2794 -0.1778)
							(mid 0.249642 -0.249642)
							(end 0.1778 -0.2794)
						)
					)
					(width 0)
					(fill yes)
				)
			)
		)
		(pad "2" smd custom
			(at 0 0.4445)
			(size 0.1397 0.1397)
			(layers "F.Cu" "F.Mask" "F.Paste")
			(net "P3V3_AUX")
			(options
				(clearance outline)
				(anchor circle)
			)
			(primitives
				(gr_poly
					(pts
						(arc
							(start -0.1778 -0.2794)
							(mid -0.249642 -0.249642)
							(end -0.2794 -0.1778)
						)
						(arc
							(start -0.2794 0.1778)
							(mid -0.249642 0.249642)
							(end -0.1778 0.2794)
						)
						(arc
							(start 0.1778 0.2794)
							(mid 0.249642 0.249642)
							(end 0.2794 0.1778)
						)
						(arc
							(start 0.2794 -0.1778)
							(mid 0.249642 -0.249642)
							(end 0.1778 -0.2794)
						)
					)
					(width 0)
					(fill yes)
				)
			)
		)
	)
	(footprint ""
		(layer "F.Cu")
		(at 38.227 -178.054 180)
		(property "Reference" "C254"
			(at 0 0 180)
			(layer "F.SilkS")
			(hide yes)
			(effects
				(font
					(size 1.27 1.27)
				)
			)
		)
		(property "Value" "SCD1U16V2KX-3GP"
			(at 1.1811 -2.7051 180)
			(unlocked yes)
			(layer "F.Fab")
			(hide yes)
			(effects
				(font
					(size 1.016 1.016)
					(thickness 0.1524)
				)
			)
		)
		(property "Device Type" "C402H22"
			(at 1.1811 -4.2291 180)
			(unlocked yes)
			(layer "F.Fab")
			(hide yes)
			(effects
				(font
					(size 1.016 1.016)
					(thickness 0.1524)
				)
			)
		)
		(duplicate_pad_numbers_are_jumpers no)
		(fp_rect
			(start -0.4318 0.9525)
			(end 0.4318 -0.9525)
			(stroke
				(width 0)
				(type default)
			)
			(fill no)
			(layer "F.CrtYd")
		)
		(fp_rect
			(start -0.4318 0.9525)
			(end 0.4318 -0.9525)
			(stroke
				(width 0)
				(type default)
			)
			(fill no)
			(layer "F.Fab")
		)
		(pad "1" smd custom
			(at 0 -0.4445 180)
			(size 0.1524 0.1524)
			(layers "F.Cu" "F.Mask" "F.Paste")
			(net "P3V3_AUX")
			(options
				(clearance outline)
				(anchor circle)
			)
			(primitives
				(gr_poly
					(pts
						(arc
							(start 0.3048 -0.2032)
							(mid 0.275042 -0.275042)
							(end 0.2032 -0.3048)
						)
						(arc
							(start -0.2032 -0.3048)
							(mid -0.275042 -0.275042)
							(end -0.3048 -0.2032)
						)
						(arc
							(start -0.3048 0.2032)
							(mid -0.275042 0.275042)
							(end -0.2032 0.3048)
						)
						(arc
							(start 0.2032 0.3048)
							(mid 0.275042 0.275042)
							(end 0.3048 0.2032)
						)
					)
					(width 0)
					(fill yes)
				)
			)
		)
		(pad "2" smd custom
			(at 0 0.4445 180)
			(size 0.1524 0.1524)
			(layers "F.Cu" "F.Mask" "F.Paste")
			(net "GND")
			(options
				(clearance outline)
				(anchor circle)
			)
			(primitives
				(gr_poly
					(pts
						(arc
							(start 0.3048 -0.2032)
							(mid 0.275042 -0.275042)
							(end 0.2032 -0.3048)
						)
						(arc
							(start -0.2032 -0.3048)
							(mid -0.275042 -0.275042)
							(end -0.3048 -0.2032)
						)
						(arc
							(start -0.3048 0.2032)
							(mid -0.275042 0.275042)
							(end -0.2032 0.3048)
						)
						(arc
							(start 0.2032 0.3048)
							(mid 0.275042 0.275042)
							(end 0.3048 0.2032)
						)
					)
					(width 0)
					(fill yes)
				)
			)
		)
	)
	(footprint ""
		(layer "F.Cu")
		(at 40.851074 -362.859574 180)
		(property "Reference" "PR41"
			(at 0 0 180)
			(layer "F.SilkS")
			(hide yes)
			(effects
				(font
					(size 1.27 1.27)
				)
			)
		)
		(property "Value" "1KR2F-3-GP"
			(at 0.064008 -3.993896 180)
			(unlocked yes)
			(layer "F.Fab")
			(hide yes)
			(effects
				(font
					(size 1.016 1.016)
					(thickness 0.1524)
				)
			)
		)
		(property "Device Type" "R402H16"
			(at 0.064008 -5.517896 180)
			(unlocked yes)
			(layer "F.Fab")
			(hide yes)
			(effects
				(font
					(size 1.016 1.016)
					(thickness 0.1524)
				)
			)
		)
		(duplicate_pad_numbers_are_jumpers no)
		(fp_line
			(start 0.508 -0.9398)
			(end -0.508 -0.9398)
			(stroke
				(width 0.1524)
				(type default)
			)
			(layer "F.SilkS")
		)
		(fp_line
			(start -0.508 -0.9398)
			(end -0.508 0.9398)
			(stroke
				(width 0.1524)
				(type default)
			)
			(layer "F.SilkS")
		)
		(fp_rect
			(start -0.508 0.9398)
			(end 0.508 -0.9398)
			(stroke
				(width 0)
				(type default)
			)
			(fill no)
			(layer "F.CrtYd")
		)
		(fp_rect
			(start -0.508 0.9398)
			(end 0.508 -0.9398)
			(stroke
				(width 0)
				(type default)
			)
			(fill no)
			(layer "F.Fab")
		)
		(pad "1" smd custom
			(at 0 -0.4445 180)
			(size 0.1397 0.1397)
			(layers "F.Cu" "F.Mask" "F.Paste")
			(net "TEMP_ALM#_JP_1")
			(options
				(clearance outline)
				(anchor circle)
			)
			(primitives
				(gr_poly
					(pts
						(arc
							(start -0.1778 -0.2794)
							(mid -0.249642 -0.249642)
							(end -0.2794 -0.1778)
						)
						(arc
							(start -0.2794 0.1778)
							(mid -0.249642 0.249642)
							(end -0.1778 0.2794)
						)
						(arc
							(start 0.1778 0.2794)
							(mid 0.249642 0.249642)
							(end 0.2794 0.1778)
						)
						(arc
							(start 0.2794 -0.1778)
							(mid 0.249642 -0.249642)
							(end 0.1778 -0.2794)
						)
					)
					(width 0)
					(fill yes)
				)
			)
		)
		(pad "2" smd custom
			(at 0 0.4445 180)
			(size 0.1397 0.1397)
			(layers "F.Cu" "F.Mask" "F.Paste")
			(net "ADM1276_LATCH#")
			(options
				(clearance outline)
				(anchor circle)
			)
			(primitives
				(gr_poly
					(pts
						(arc
							(start -0.1778 -0.2794)
							(mid -0.249642 -0.249642)
							(end -0.2794 -0.1778)
						)
						(arc
							(start -0.2794 0.1778)
							(mid -0.249642 0.249642)
							(end -0.1778 0.2794)
						)
						(arc
							(start 0.1778 0.2794)
							(mid 0.249642 0.249642)
							(end 0.2794 0.1778)
						)
						(arc
							(start 0.2794 -0.1778)
							(mid 0.249642 -0.249642)
							(end 0.1778 -0.2794)
						)
					)
					(width 0)
					(fill yes)
				)
			)
		)
	)
	(footprint ""
		(layer "F.Cu")
		(at 29.6672 -149.071584 180)
		(property "Reference" "R16"
			(at 0 0 180)
			(layer "F.SilkS")
			(hide yes)
			(effects
				(font
					(size 1.27 1.27)
				)
			)
		)
		(property "Value" "110KR2F-L-GP"
			(at 0.064008 -3.993896 180)
			(unlocked yes)
			(layer "F.Fab")
			(hide yes)
			(effects
				(font
					(size 1.016 1.016)
					(thickness 0.1524)
				)
			)
		)
		(property "Device Type" "R402H16"
			(at 0.064008 -5.517896 180)
			(unlocked yes)
			(layer "F.Fab")
			(hide yes)
			(effects
				(font
					(size 1.016 1.016)
					(thickness 0.1524)
				)
			)
		)
		(duplicate_pad_numbers_are_jumpers no)
		(fp_line
			(start 0.508 -0.9398)
			(end -0.508 -0.9398)
			(stroke
				(width 0.1524)
				(type default)
			)
			(layer "F.SilkS")
		)
		(fp_line
			(start -0.508 -0.9398)
			(end -0.508 0.9398)
			(stroke
				(width 0.1524)
				(type default)
			)
			(layer "F.SilkS")
		)
		(fp_rect
			(start -0.508 0.9398)
			(end 0.508 -0.9398)
			(stroke
				(width 0)
				(type default)
			)
			(fill no)
			(layer "F.CrtYd")
		)
		(fp_rect
			(start -0.508 0.9398)
			(end 0.508 -0.9398)
			(stroke
				(width 0)
				(type default)
			)
			(fill no)
			(layer "F.Fab")
		)
		(pad "1" smd custom
			(at 0 -0.4445 180)
			(size 0.1397 0.1397)
			(layers "F.Cu" "F.Mask" "F.Paste")
			(net "P12VL")
			(options
				(clearance outline)
				(anchor circle)
			)
			(primitives
				(gr_poly
					(pts
						(arc
							(start -0.1778 -0.2794)
							(mid -0.249642 -0.249642)
							(end -0.2794 -0.1778)
						)
						(arc
							(start -0.2794 0.1778)
							(mid -0.249642 0.249642)
							(end -0.1778 0.2794)
						)
						(arc
							(start 0.1778 0.2794)
							(mid 0.249642 0.249642)
							(end 0.2794 0.1778)
						)
						(arc
							(start 0.2794 -0.1778)
							(mid 0.249642 -0.249642)
							(end 0.1778 -0.2794)
						)
					)
					(width 0)
					(fill yes)
				)
			)
		)
		(pad "2" smd custom
			(at 0 0.4445 180)
			(size 0.1397 0.1397)
			(layers "F.Cu" "F.Mask" "F.Paste")
			(net "NCT7904_VSEN6")
			(options
				(clearance outline)
				(anchor circle)
			)
			(primitives
				(gr_poly
					(pts
						(arc
							(start -0.1778 -0.2794)
							(mid -0.249642 -0.249642)
							(end -0.2794 -0.1778)
						)
						(arc
							(start -0.2794 0.1778)
							(mid -0.249642 0.249642)
							(end -0.1778 0.2794)
						)
						(arc
							(start 0.1778 0.2794)
							(mid 0.249642 0.249642)
							(end 0.2794 0.1778)
						)
						(arc
							(start 0.2794 -0.1778)
							(mid 0.249642 -0.249642)
							(end 0.1778 -0.2794)
						)
					)
					(width 0)
					(fill yes)
				)
			)
		)
	)
	(footprint ""
		(layer "F.Cu")
		(at 37.338 -144.272 -90)
		(property "Reference" "PR111"
			(at 0 0 270)
			(layer "F.SilkS")
			(hide yes)
			(effects
				(font
					(size 1.27 1.27)
				)
			)
		)
		(property "Value" "178KR2F-GP"
			(at 0.064008 -3.993896 270)
			(unlocked yes)
			(layer "F.Fab")
			(hide yes)
			(effects
				(font
					(size 1.016 1.016)
					(thickness 0.1524)
				)
			)
		)
		(property "Device Type" "R402H16"
			(at 0.064008 -5.517896 270)
			(unlocked yes)
			(layer "F.Fab")
			(hide yes)
			(effects
				(font
					(size 1.016 1.016)
					(thickness 0.1524)
				)
			)
		)
		(duplicate_pad_numbers_are_jumpers no)
		(fp_line
			(start -0.508 -0.9398)
			(end -0.508 0.9398)
			(stroke
				(width 0.1524)
				(type default)
			)
			(layer "F.SilkS")
		)
		(fp_line
			(start 0.508 -0.9398)
			(end -0.508 -0.9398)
			(stroke
				(width 0.1524)
				(type default)
			)
			(layer "F.SilkS")
		)
		(fp_rect
			(start -0.508 0.9398)
			(end 0.508 -0.9398)
			(stroke
				(width 0)
				(type default)
			)
			(fill no)
			(layer "F.CrtYd")
		)
		(fp_rect
			(start -0.508 0.9398)
			(end 0.508 -0.9398)
			(stroke
				(width 0)
				(type default)
			)
			(fill no)
			(layer "F.Fab")
		)
		(pad "1" smd custom
			(at 0 -0.4445 270)
			(size 0.1397 0.1397)
			(layers "F.Cu" "F.Mask" "F.Paste")
			(net "P12VL_2490_VREF")
			(options
				(clearance outline)
				(anchor circle)
			)
			(primitives
				(gr_poly
					(pts
						(arc
							(start -0.1778 -0.2794)
							(mid -0.249642 -0.249642)
							(end -0.2794 -0.1778)
						)
						(arc
							(start -0.2794 0.1778)
							(mid -0.249642 0.249642)
							(end -0.1778 0.2794)
						)
						(arc
							(start 0.1778 0.2794)
							(mid 0.249642 0.249642)
							(end 0.2794 0.1778)
						)
						(arc
							(start 0.2794 -0.1778)
							(mid 0.249642 -0.249642)
							(end 0.1778 -0.2794)
						)
					)
					(width 0)
					(fill yes)
				)
			)
		)
		(pad "2" smd custom
			(at 0 0.4445 270)
			(size 0.1397 0.1397)
			(layers "F.Cu" "F.Mask" "F.Paste")
			(net "P12VL_2490_PROG")
			(options
				(clearance outline)
				(anchor circle)
			)
			(primitives
				(gr_poly
					(pts
						(arc
							(start -0.1778 -0.2794)
							(mid -0.249642 -0.249642)
							(end -0.2794 -0.1778)
						)
						(arc
							(start -0.2794 0.1778)
							(mid -0.249642 0.249642)
							(end -0.1778 0.2794)
						)
						(arc
							(start 0.1778 0.2794)
							(mid 0.249642 0.249642)
							(end 0.2794 0.1778)
						)
						(arc
							(start 0.2794 -0.1778)
							(mid 0.249642 -0.249642)
							(end 0.1778 -0.2794)
						)
					)
					(width 0)
					(fill yes)
				)
			)
		)
	)
	(footprint ""
		(layer "F.Cu")
		(at 24.4602 -142.367)
		(property "Reference" "PC96"
			(at 0 0 0)
			(layer "F.SilkS")
			(hide yes)
			(effects
				(font
					(size 1.27 1.27)
				)
			)
		)
		(property "Value" "SCD1U50V3KX-GP"
			(at 0 -2.8194 0)
			(unlocked yes)
			(layer "F.Fab")
			(hide yes)
			(effects
				(font
					(size 1.016 1.016)
					(thickness 0.1524)
				)
			)
		)
		(property "Device Type" "C603H36"
			(at 0 -4.3434 0)
			(unlocked yes)
			(layer "F.Fab")
			(hide yes)
			(effects
				(font
					(size 1.016 1.016)
					(thickness 0.1524)
				)
			)
		)
		(duplicate_pad_numbers_are_jumpers no)
		(fp_line
			(start 0.508 0)
			(end -0.508 0)
			(stroke
				(width 0.2032)
				(type default)
			)
			(layer "F.SilkS")
		)
		(fp_rect
			(start -0.5842 1.3335)
			(end 0.5842 -1.3335)
			(stroke
				(width 0)
				(type default)
			)
			(fill no)
			(layer "F.CrtYd")
		)
		(fp_rect
			(start -0.5842 1.3335)
			(end 0.5842 -1.3335)
			(stroke
				(width 0)
				(type default)
			)
			(fill no)
			(layer "F.Fab")
		)
		(pad "1" smd custom
			(at 0 -0.762)
			(size 0.2159 0.2159)
			(layers "F.Cu" "F.Mask" "F.Paste")
			(net "P12VU_2490_EN_2")
			(options
				(clearance outline)
				(anchor circle)
			)
			(primitives
				(gr_poly
					(pts
						(arc
							(start -0.3302 -0.4318)
							(mid -0.402042 -0.402042)
							(end -0.4318 -0.3302)
						)
						(arc
							(start -0.4318 0.3302)
							(mid -0.402042 0.402042)
							(end -0.3302 0.4318)
						)
						(arc
							(start 0.3302 0.4318)
							(mid 0.402042 0.402042)
							(end 0.4318 0.3302)
						)
						(arc
							(start 0.4318 -0.3302)
							(mid 0.402042 -0.402042)
							(end 0.3302 -0.4318)
						)
					)
					(width 0)
					(fill yes)
				)
			)
		)
		(pad "2" smd custom
			(at 0 0.762)
			(size 0.2159 0.2159)
			(layers "F.Cu" "F.Mask" "F.Paste")
			(net "GND")
			(options
				(clearance outline)
				(anchor circle)
			)
			(primitives
				(gr_poly
					(pts
						(arc
							(start -0.3302 -0.4318)
							(mid -0.402042 -0.402042)
							(end -0.4318 -0.3302)
						)
						(arc
							(start -0.4318 0.3302)
							(mid -0.402042 0.402042)
							(end -0.3302 0.4318)
						)
						(arc
							(start 0.3302 0.4318)
							(mid 0.402042 0.402042)
							(end 0.4318 0.3302)
						)
						(arc
							(start 0.4318 -0.3302)
							(mid 0.402042 -0.402042)
							(end 0.3302 -0.4318)
						)
					)
					(width 0)
					(fill yes)
				)
			)
		)
	)
	(footprint ""
		(layer "F.Cu")
		(at 33.401 -362.7882 -90)
		(property "Reference" "PR39"
			(at 0 0 270)
			(layer "F.SilkS")
			(hide yes)
			(effects
				(font
					(size 1.27 1.27)
				)
			)
		)
		(property "Value" "5K1R2F-2-GP"
			(at 0.064008 -3.993896 270)
			(unlocked yes)
			(layer "F.Fab")
			(hide yes)
			(effects
				(font
					(size 1.016 1.016)
					(thickness 0.1524)
				)
			)
		)
		(property "Device Type" "R402H16"
			(at 0.064008 -5.517896 270)
			(unlocked yes)
			(layer "F.Fab")
			(hide yes)
			(effects
				(font
					(size 1.016 1.016)
					(thickness 0.1524)
				)
			)
		)
		(duplicate_pad_numbers_are_jumpers no)
		(fp_line
			(start -0.508 -0.9398)
			(end -0.508 0.9398)
			(stroke
				(width 0.1524)
				(type default)
			)
			(layer "F.SilkS")
		)
		(fp_line
			(start 0.508 -0.9398)
			(end -0.508 -0.9398)
			(stroke
				(width 0.1524)
				(type default)
			)
			(layer "F.SilkS")
		)
		(fp_rect
			(start -0.508 0.9398)
			(end 0.508 -0.9398)
			(stroke
				(width 0)
				(type default)
			)
			(fill no)
			(layer "F.CrtYd")
		)
		(fp_rect
			(start -0.508 0.9398)
			(end 0.508 -0.9398)
			(stroke
				(width 0)
				(type default)
			)
			(fill no)
			(layer "F.Fab")
		)
		(pad "1" smd custom
			(at 0 -0.4445 270)
			(size 0.1397 0.1397)
			(layers "F.Cu" "F.Mask" "F.Paste")
			(net "TEMP_ALM#_REVERSE_R")
			(options
				(clearance outline)
				(anchor circle)
			)
			(primitives
				(gr_poly
					(pts
						(arc
							(start -0.1778 -0.2794)
							(mid -0.249642 -0.249642)
							(end -0.2794 -0.1778)
						)
						(arc
							(start -0.2794 0.1778)
							(mid -0.249642 0.249642)
							(end -0.1778 0.2794)
						)
						(arc
							(start 0.1778 0.2794)
							(mid 0.249642 0.249642)
							(end 0.2794 0.1778)
						)
						(arc
							(start 0.2794 -0.1778)
							(mid 0.249642 -0.249642)
							(end 0.1778 -0.2794)
						)
					)
					(width 0)
					(fill yes)
				)
			)
		)
		(pad "2" smd custom
			(at 0 0.4445 270)
			(size 0.1397 0.1397)
			(layers "F.Cu" "F.Mask" "F.Paste")
			(net "GND")
			(options
				(clearance outline)
				(anchor circle)
			)
			(primitives
				(gr_poly
					(pts
						(arc
							(start -0.1778 -0.2794)
							(mid -0.249642 -0.249642)
							(end -0.2794 -0.1778)
						)
						(arc
							(start -0.2794 0.1778)
							(mid -0.249642 0.249642)
							(end -0.1778 0.2794)
						)
						(arc
							(start 0.1778 0.2794)
							(mid 0.249642 0.249642)
							(end 0.2794 0.1778)
						)
						(arc
							(start 0.2794 -0.1778)
							(mid 0.249642 -0.249642)
							(end 0.1778 -0.2794)
						)
					)
					(width 0)
					(fill yes)
				)
			)
		)
	)
	(footprint ""
		(layer "F.Cu")
		(at 37.338 -184.531 180)
		(property "Reference" "PC1262"
			(at 0 0 180)
			(layer "F.SilkS")
			(hide yes)
			(effects
				(font
					(size 1.27 1.27)
				)
			)
		)
		(property "Value" "SC10U16V6KX-2GP"
			(at -0.0762 -5.1308 180)
			(unlocked yes)
			(layer "F.Fab")
			(hide yes)
			(effects
				(font
					(size 1.016 1.016)
					(thickness 0.1524)
				)
			)
		)
		(property "Device Type" "C1206H71"
			(at -0.127 -6.6548 180)
			(unlocked yes)
			(layer "F.Fab")
			(hide yes)
			(effects
				(font
					(size 1.016 1.016)
					(thickness 0.1524)
				)
			)
		)
		(duplicate_pad_numbers_are_jumpers no)
		(fp_line
			(start 1.016 2.2352)
			(end -1.016 2.2352)
			(stroke
				(width 0.1524)
				(type default)
			)
			(layer "F.SilkS")
		)
		(fp_line
			(start 1.016 0.8382)
			(end 1.016 2.2352)
			(stroke
				(width 0.1524)
				(type default)
			)
			(layer "F.SilkS")
		)
		(fp_line
			(start 1.016 -2.2352)
			(end 1.016 -0.8382)
			(stroke
				(width 0.1524)
				(type default)
			)
			(layer "F.SilkS")
		)
		(fp_line
			(start -1.016 2.2352)
			(end -1.016 0.8382)
			(stroke
				(width 0.1524)
				(type default)
			)
			(layer "F.SilkS")
		)
		(fp_line
			(start -1.016 -0.8382)
			(end -1.016 -2.2352)
			(stroke
				(width 0.1524)
				(type default)
			)
			(layer "F.SilkS")
		)
		(fp_line
			(start -1.016 -2.2352)
			(end 1.016 -2.2352)
			(stroke
				(width 0.1524)
				(type default)
			)
			(layer "F.SilkS")
		)
		(fp_rect
			(start -1.0922 2.3114)
			(end 1.0922 -2.3114)
			(stroke
				(width 0)
				(type default)
			)
			(fill no)
			(layer "F.CrtYd")
		)
		(fp_poly
			(pts
				(xy 1.0922 -2.3114) (xy 1.0922 2.3114) (xy -1.0922 2.3114) (xy -1.0922 -2.3114)
			)
			(stroke
				(width 0)
				(type default)
			)
			(fill no)
			(layer "F.Fab")
		)
		(pad "1" smd rect
			(at 0 -1.397 180)
			(size 1.651 1.27)
			(layers "F.Cu" "F.Mask" "F.Paste")
			(net "P3V3_AUX")
		)
		(pad "2" smd rect
			(at 0 1.397 180)
			(size 1.651 1.27)
			(layers "F.Cu" "F.Mask" "F.Paste")
			(net "GND")
		)
	)
	(footprint ""
		(layer "F.Cu")
		(at 12.446 -394.081 -90)
		(property "Reference" "TC12"
			(at 0 0 270)
			(layer "F.SilkS")
			(hide yes)
			(effects
				(font
					(size 1.27 1.27)
				)
			)
		)
		(property "Value" "ST15U25VDM-1-GP"
			(at 0 -9.6012 270)
			(unlocked yes)
			(layer "F.Fab")
			(hide yes)
			(effects
				(font
					(size 1.016 1.016)
					(thickness 0.1524)
				)
			)
		)
		(property "Device Type" "CT7343H79"
			(at 0 -11.1252 270)
			(unlocked yes)
			(layer "F.Fab")
			(hide yes)
			(effects
				(font
					(size 1.016 1.016)
					(thickness 0.1524)
				)
			)
		)
		(duplicate_pad_numbers_are_jumpers no)
		(fp_line
			(start -2.286 4.8768)
			(end -2.286 2.032)
			(stroke
				(width 0.1524)
				(type default)
			)
			(layer "F.SilkS")
		)
		(fp_line
			(start 2.286 4.8768)
			(end -2.286 4.8768)
			(stroke
				(width 0.1524)
				(type default)
			)
			(layer "F.SilkS")
		)
		(fp_line
			(start 2.286 2.032)
			(end 2.286 4.8768)
			(stroke
				(width 0.1524)
				(type default)
			)
			(layer "F.SilkS")
		)
		(fp_line
			(start 2.286 -2.032)
			(end 2.286 -4.8768)
			(stroke
				(width 0.1524)
				(type default)
			)
			(layer "F.SilkS")
		)
		(fp_line
			(start 2.1082 -4.699)
			(end -2.1082 -4.699)
			(stroke
				(width 0.508)
				(type default)
			)
			(layer "F.SilkS")
		)
		(fp_line
			(start -2.286 -4.8768)
			(end -2.286 -2.032)
			(stroke
				(width 0.1524)
				(type default)
			)
			(layer "F.SilkS")
		)
		(fp_line
			(start 2.286 -4.8768)
			(end -2.286 -4.8768)
			(stroke
				(width 0.1524)
				(type default)
			)
			(layer "F.SilkS")
		)
		(fp_rect
			(start -2.1463 3.6449)
			(end 2.1463 -3.6449)
			(stroke
				(width 0)
				(type default)
			)
			(fill no)
			(layer "F.CrtYd")
		)
		(fp_poly
			(pts
				(xy -2.54 4.953) (xy -2.54 4.2926) (xy -3.81 4.2926) (xy -3.81 -4.2926) (xy -2.54 -4.2926) (xy -2.54 -4.953)
				(xy 2.54 -4.953) (xy 2.54 -4.2926) (xy 3.81 -4.2926) (xy 3.81 -1.6256) (xy 2.1463 -1.6256) (xy 2.1463 -3.6449)
				(xy -2.1463 -3.6449) (xy -2.1463 3.6449) (xy 2.1463 3.6449) (xy 2.1463 -1.6129) (xy 3.81 -1.6129)
				(xy 3.81 4.2926) (xy 2.54 4.2926) (xy 2.54 4.953)
			)
			(stroke
				(width 0)
				(type default)
			)
			(fill no)
			(layer "F.CrtYd")
		)
		(fp_rect
			(start -2.54 4.953)
			(end 2.54 -4.953)
			(stroke
				(width 0)
				(type default)
			)
			(fill no)
			(layer "F.Fab")
		)
		(fp_rect
			(start -3.81 4.2926)
			(end -2.54 -4.2926)
			(stroke
				(width 0)
				(type default)
			)
			(fill no)
			(layer "F.Fab")
		)
		(fp_rect
			(start 2.54 4.2926)
			(end 3.81 -4.2926)
			(stroke
				(width 0)
				(type default)
			)
			(fill no)
			(layer "F.Fab")
		)
		(pad "1" smd rect
			(at 0 -3.1496 270)
			(size 2.413 2.286)
			(layers "F.Cu" "F.Mask" "F.Paste")
			(net "P12V")
		)
		(pad "2" smd rect
			(at 0 3.1496 270)
			(size 2.413 2.286)
			(layers "F.Cu" "F.Mask" "F.Paste")
			(net "GND")
		)
		(zone
			(layer "F.Cu")
			(hatch none 0.5)
			(connect_pads
				(clearance 0)
			)
			(min_thickness 0.25)
			(keepout
				(tracks allowed)
				(vias not_allowed)
				(pads allowed)
				(copperpour not_allowed)
				(footprints allowed)
			)
			(placement
				(enabled no)
				(sheetname "")
			)
			(fill
				(thermal_gap 0.5)
				(thermal_bridge_width 0.5)
				(island_removal_mode 0)
			)
			(polygon
				(pts
					(xy 7.8486 -395.5923) (xy 7.8486 -392.5697) (xy 10.7442 -392.5697) (xy 11.0744 -392.5697) (xy 11.0744 -395.5923)
					(xy 10.7442 -395.5923)
				)
			)
		)
		(zone
			(layer "F.Cu")
			(hatch none 0.5)
			(connect_pads
				(clearance 0)
			)
			(min_thickness 0.25)
			(keepout
				(tracks allowed)
				(vias not_allowed)
				(pads allowed)
				(copperpour not_allowed)
				(footprints allowed)
			)
			(placement
				(enabled no)
				(sheetname "")
			)
			(fill
				(thermal_gap 0.5)
				(thermal_bridge_width 0.5)
				(island_removal_mode 0)
			)
			(polygon
				(pts
					(xy 14.1351 -392.5697) (xy 17.0434 -392.5697) (xy 17.0434 -395.5923) (xy 14.1478 -395.5923) (xy 13.8176 -395.5923)
					(xy 13.8176 -392.5697)
				)
			)
		)
	)
	(footprint ""
		(layer "F.Cu")
		(at 45.522134 -155.83789 -90)
		(property "Reference" "L2"
			(at 0 0 270)
			(layer "F.SilkS")
			(hide yes)
			(effects
				(font
					(size 1.27 1.27)
				)
			)
		)
		(property "Value" "FCM1608CF-121T03-GP"
			(at -0.0254 -2.8956 270)
			(unlocked yes)
			(layer "F.Fab")
			(hide yes)
			(effects
				(font
					(size 1.016 1.016)
					(thickness 0.1524)
				)
			)
		)
		(property "Device Type" "L1608-UH38"
			(at -0.0254 -4.4196 270)
			(unlocked yes)
			(layer "F.Fab")
			(hide yes)
			(effects
				(font
					(size 1.016 1.016)
					(thickness 0.1524)
				)
			)
		)
		(duplicate_pad_numbers_are_jumpers no)
		(fp_line
			(start 0.254 0)
			(end -0.254 0)
			(stroke
				(width 0.2032)
				(type default)
			)
			(layer "F.SilkS")
		)
		(fp_rect
			(start -0.5842 1.3335)
			(end 0.5842 -1.3335)
			(stroke
				(width 0)
				(type default)
			)
			(fill no)
			(layer "F.CrtYd")
		)
		(fp_rect
			(start -0.5842 1.3335)
			(end 0.5842 -1.3335)
			(stroke
				(width 0)
				(type default)
			)
			(fill no)
			(layer "F.Fab")
		)
		(pad "1" smd custom
			(at 0 -0.762 270)
			(size 0.2159 0.2159)
			(layers "F.Cu" "F.Mask" "F.Paste")
			(net "P3V3")
			(options
				(clearance outline)
				(anchor circle)
			)
			(primitives
				(gr_poly
					(pts
						(arc
							(start -0.3302 -0.4318)
							(mid -0.402042 -0.402042)
							(end -0.4318 -0.3302)
						)
						(arc
							(start -0.4318 0.3302)
							(mid -0.402042 0.402042)
							(end -0.3302 0.4318)
						)
						(arc
							(start 0.3302 0.4318)
							(mid 0.402042 0.402042)
							(end 0.4318 0.3302)
						)
						(arc
							(start 0.4318 -0.3302)
							(mid 0.402042 -0.402042)
							(end 0.3302 -0.4318)
						)
					)
					(width 0)
					(fill yes)
				)
			)
		)
		(pad "2" smd custom
			(at 0 0.762 270)
			(size 0.2159 0.2159)
			(layers "F.Cu" "F.Mask" "F.Paste")
			(net "NCT7904_3VSB")
			(options
				(clearance outline)
				(anchor circle)
			)
			(primitives
				(gr_poly
					(pts
						(arc
							(start -0.3302 -0.4318)
							(mid -0.402042 -0.402042)
							(end -0.4318 -0.3302)
						)
						(arc
							(start -0.4318 0.3302)
							(mid -0.402042 0.402042)
							(end -0.3302 0.4318)
						)
						(arc
							(start 0.3302 0.4318)
							(mid 0.402042 0.402042)
							(end 0.4318 0.3302)
						)
						(arc
							(start 0.4318 -0.3302)
							(mid 0.402042 -0.402042)
							(end 0.3302 -0.4318)
						)
					)
					(width 0)
					(fill yes)
				)
			)
		)
	)
	(footprint ""
		(layer "F.Cu")
		(at 14.8844 -45.5422 90)
		(property "Reference" "R114"
			(at 0 0 90)
			(layer "F.SilkS")
			(hide yes)
			(effects
				(font
					(size 1.27 1.27)
				)
			)
		)
		(property "Value" "470R2F-GP"
			(at 0.064008 -3.993896 90)
			(unlocked yes)
			(layer "F.Fab")
			(hide yes)
			(effects
				(font
					(size 1.016 1.016)
					(thickness 0.1524)
				)
			)
		)
		(property "Device Type" "R402H16"
			(at 0.064008 -5.517896 90)
			(unlocked yes)
			(layer "F.Fab")
			(hide yes)
			(effects
				(font
					(size 1.016 1.016)
					(thickness 0.1524)
				)
			)
		)
		(duplicate_pad_numbers_are_jumpers no)
		(fp_line
			(start 0.508 -0.9398)
			(end -0.508 -0.9398)
			(stroke
				(width 0.1524)
				(type default)
			)
			(layer "F.SilkS")
		)
		(fp_line
			(start -0.508 -0.9398)
			(end -0.508 0.9398)
			(stroke
				(width 0.1524)
				(type default)
			)
			(layer "F.SilkS")
		)
		(fp_rect
			(start -0.508 0.9398)
			(end 0.508 -0.9398)
			(stroke
				(width 0)
				(type default)
			)
			(fill no)
			(layer "F.CrtYd")
		)
		(fp_rect
			(start -0.508 0.9398)
			(end 0.508 -0.9398)
			(stroke
				(width 0)
				(type default)
			)
			(fill no)
			(layer "F.Fab")
		)
		(pad "1" smd custom
			(at 0 -0.4445 90)
			(size 0.1397 0.1397)
			(layers "F.Cu" "F.Mask" "F.Paste")
			(net "SEB_PEER_1A_HB")
			(options
				(clearance outline)
				(anchor circle)
			)
			(primitives
				(gr_poly
					(pts
						(arc
							(start -0.1778 -0.2794)
							(mid -0.249642 -0.249642)
							(end -0.2794 -0.1778)
						)
						(arc
							(start -0.2794 0.1778)
							(mid -0.249642 0.249642)
							(end -0.1778 0.2794)
						)
						(arc
							(start 0.1778 0.2794)
							(mid 0.249642 0.249642)
							(end 0.2794 0.1778)
						)
						(arc
							(start 0.2794 -0.1778)
							(mid 0.249642 -0.249642)
							(end 0.1778 -0.2794)
						)
					)
					(width 0)
					(fill yes)
				)
			)
		)
		(pad "2" smd custom
			(at 0 0.4445 90)
			(size 0.1397 0.1397)
			(layers "F.Cu" "F.Mask" "F.Paste")
			(net "GND")
			(options
				(clearance outline)
				(anchor circle)
			)
			(primitives
				(gr_poly
					(pts
						(arc
							(start -0.1778 -0.2794)
							(mid -0.249642 -0.249642)
							(end -0.2794 -0.1778)
						)
						(arc
							(start -0.2794 0.1778)
							(mid -0.249642 0.249642)
							(end -0.1778 0.2794)
						)
						(arc
							(start 0.1778 0.2794)
							(mid 0.249642 0.249642)
							(end 0.2794 0.1778)
						)
						(arc
							(start 0.2794 -0.1778)
							(mid 0.249642 -0.249642)
							(end 0.1778 -0.2794)
						)
					)
					(width 0)
					(fill yes)
				)
			)
		)
	)
	(footprint ""
		(layer "F.Cu")
		(at 30.36189 -159.849566 180)
		(property "Reference" "U1"
			(at 0 0 180)
			(layer "F.SilkS")
			(hide yes)
			(effects
				(font
					(size 1.27 1.27)
				)
			)
		)
		(property "Value" "NCT7904D-GP"
			(at -4.064 -8.5852 180)
			(unlocked yes)
			(layer "F.Fab")
			(hide yes)
			(effects
				(font
					(size 1.016 1.016)
					(thickness 0.1524)
				)
			)
		)
		(property "Device Type" "LQFP48H63"
			(at -4.064 -10.3632 180)
			(unlocked yes)
			(layer "F.Fab")
			(hide yes)
			(effects
				(font
					(size 1.016 1.016)
					(thickness 0.1524)
				)
			)
		)
		(duplicate_pad_numbers_are_jumpers no)
		(fp_line
			(start 5.5118 5.5118)
			(end 5.5118 3.0226)
			(stroke
				(width 0.1524)
				(type default)
			)
			(layer "F.SilkS")
		)
		(fp_line
			(start 5.5118 -3.0734)
			(end 5.4864 -3.0734)
			(stroke
				(width 0.1524)
				(type default)
			)
			(layer "F.SilkS")
		)
		(fp_line
			(start 5.5118 -5.5118)
			(end 5.5118 -3.0734)
			(stroke
				(width 0.1524)
				(type default)
			)
			(layer "F.SilkS")
		)
		(fp_line
			(start 5.4864 -3.0734)
			(end 3.048 -5.5118)
			(stroke
				(width 0.1524)
				(type default)
			)
			(layer "F.SilkS")
		)
		(fp_line
			(start 5.1562 1.24968)
			(end 5.9182 1.24968)
			(stroke
				(width 0.1524)
				(type default)
			)
			(layer "F.SilkS")
		)
		(fp_line
			(start 5.1562 -1.24968)
			(end 5.6642 -1.24968)
			(stroke
				(width 0.1524)
				(type default)
			)
			(layer "F.SilkS")
		)
		(fp_line
			(start 3.048 -5.5118)
			(end 5.5118 -5.5118)
			(stroke
				(width 0.1524)
				(type default)
			)
			(layer "F.SilkS")
		)
		(fp_line
			(start 2.9718 5.5118)
			(end 5.5118 5.5118)
			(stroke
				(width 0.1524)
				(type default)
			)
			(layer "F.SilkS")
		)
		(fp_line
			(start 2.25044 5.1562)
			(end 2.25044 5.6642)
			(stroke
				(width 0.1524)
				(type default)
			)
			(layer "F.SilkS")
		)
		(fp_line
			(start 0.75057 -5.1562)
			(end 0.75057 -5.6642)
			(stroke
				(width 0.1524)
				(type default)
			)
			(layer "F.SilkS")
		)
		(fp_line
			(start -0.25019 5.1562)
			(end -0.25019 5.9182)
			(stroke
				(width 0.1524)
				(type default)
			)
			(layer "F.SilkS")
		)
		(fp_line
			(start -1.75006 -5.1562)
			(end -1.75006 -5.9182)
			(stroke
				(width 0.1524)
				(type default)
			)
			(layer "F.SilkS")
		)
		(fp_line
			(start -2.74955 5.1562)
			(end -2.74955 5.6642)
			(stroke
				(width 0.1524)
				(type default)
			)
			(layer "F.SilkS")
		)
		(fp_line
			(start -3.0988 -5.5118)
			(end -5.5118 -5.5118)
			(stroke
				(width 0.1524)
				(type default)
			)
			(layer "F.SilkS")
		)
		(fp_line
			(start -5.1562 0.75057)
			(end -5.9182 0.75057)
			(stroke
				(width 0.1524)
				(type default)
			)
			(layer "F.SilkS")
		)
		(fp_line
			(start -5.1562 -1.75006)
			(end -5.6642 -1.75006)
			(stroke
				(width 0.1524)
				(type default)
			)
			(layer "F.SilkS")
		)
		(fp_line
			(start -5.5118 5.5118)
			(end -2.9972 5.5118)
			(stroke
				(width 0.1524)
				(type default)
			)
			(layer "F.SilkS")
		)
		(fp_line
			(start -5.5118 2.9718)
			(end -5.5118 5.5118)
			(stroke
				(width 0.1524)
				(type default)
			)
			(layer "F.SilkS")
		)
		(fp_line
			(start -5.5118 -5.5118)
			(end -5.5118 -2.9464)
			(stroke
				(width 0.1524)
				(type default)
			)
			(layer "F.SilkS")
		)
		(fp_poly
			(pts
				(xy 5.5118 -3.048) (xy 3.048 -5.5118) (xy 5.5118 -5.5118)
			)
			(stroke
				(width 0)
				(type default)
			)
			(fill no)
			(layer "F.SilkS")
		)
		(fp_poly
			(pts
				(xy 3.0734 -5.5118) (xy 5.5118 -5.5118) (xy 5.5118 -3.1496) (xy 5.4356 -3.1496)
			)
			(stroke
				(width 0)
				(type default)
			)
			(fill yes)
			(layer "F.SilkS")
		)
		(fp_rect
			(start -5.5118 5.5118)
			(end 5.5118 -5.5118)
			(stroke
				(width 0)
				(type default)
			)
			(fill no)
			(layer "F.CrtYd")
		)
		(fp_rect
			(start -5.5118 5.5118)
			(end 5.5118 -5.5118)
			(stroke
				(width 0)
				(type default)
			)
			(fill no)
			(layer "F.Fab")
		)
		(pad "1" smd rect
			(at 2.74955 -4.2418 180)
			(size 0.3048 1.524)
			(layers "F.Cu" "F.Mask" "F.Paste")
			(net "NCT7904_VREF")
		)
		(pad "2" smd rect
			(at 2.25044 -4.2418 180)
			(size 0.3048 1.524)
			(layers "F.Cu" "F.Mask" "F.Paste")
			(net "NCT7904_D1+")
		)
		(pad "3" smd rect
			(at 1.75006 -4.2418 180)
			(size 0.3048 1.524)
			(layers "F.Cu" "F.Mask" "F.Paste")
			(net "NCT7904_D1-")
		)
		(pad "4" smd rect
			(at 1.24968 -4.2418 180)
			(size 0.3048 1.524)
			(layers "F.Cu" "F.Mask" "F.Paste")
			(net "NCT7904_D2+")
		)
		(pad "5" smd rect
			(at 0.75057 -4.2418 180)
			(size 0.3048 1.524)
			(layers "F.Cu" "F.Mask" "F.Paste")
			(net "NCT7904_D2-")
		)
		(pad "6" smd rect
			(at 0.25019 -4.2418 180)
			(size 0.3048 1.524)
			(layers "F.Cu" "F.Mask" "F.Paste")
			(net "NCT7904_VSEN6")
		)
		(pad "7" smd rect
			(at -0.25019 -4.2418 180)
			(size 0.3048 1.524)
			(layers "F.Cu" "F.Mask" "F.Paste")
			(net "NCT7904_VSEN7")
		)
		(pad "8" smd rect
			(at -0.75057 -4.2418 180)
			(size 0.3048 1.524)
			(layers "F.Cu" "F.Mask" "F.Paste")
			(net "NCT7904_VSEN8")
		)
		(pad "9" smd rect
			(at -1.24968 -4.2418 180)
			(size 0.3048 1.524)
			(layers "F.Cu" "F.Mask" "F.Paste")
			(net "NCT7904_VSEN9")
		)
		(pad "10" smd rect
			(at -1.75006 -4.2418 180)
			(size 0.3048 1.524)
			(layers "F.Cu" "F.Mask" "F.Paste")
			(net "NCT7904_VSEN10")
		)
		(pad "11" smd rect
			(at -2.25044 -4.2418 180)
			(size 0.3048 1.524)
			(layers "F.Cu" "F.Mask" "F.Paste")
			(net "NCT7904_VSEN11")
		)
		(pad "12" smd rect
			(at -2.74955 -4.2418 180)
			(size 0.3048 1.524)
			(layers "F.Cu" "F.Mask" "F.Paste")
			(net "NCT7904_VSEN12")
		)
		(pad "13" smd rect
			(at -4.2418 -2.74955 180)
			(size 1.524 0.3048)
			(layers "F.Cu" "F.Mask" "F.Paste")
			(net "NCT7904_VSEN13")
		)
		(pad "14" smd rect
			(at -4.2418 -2.25044 180)
			(size 1.524 0.3048)
			(layers "F.Cu" "F.Mask" "F.Paste")
			(net "NCT7904_VSEN14")
		)
		(pad "15" smd rect
			(at -4.2418 -1.75006 180)
			(size 1.524 0.3048)
			(layers "F.Cu" "F.Mask" "F.Paste")
			(net "NCT7904_3VDD")
		)
		(pad "16" smd rect
			(at -4.2418 -1.24968 180)
			(size 1.524 0.3048)
			(layers "F.Cu" "F.Mask" "F.Paste")
			(net "NCT7904_3VSB")
		)
		(pad "17" smd rect
			(at -4.2418 -0.75057 180)
			(size 1.524 0.3048)
			(layers "F.Cu" "F.Mask" "F.Paste")
			(net "NCT7904_SMI")
		)
		(pad "18" smd rect
			(at -4.2418 -0.25019 180)
			(size 1.524 0.3048)
			(layers "F.Cu" "F.Mask" "F.Paste")
			(net "NCT7904_PROCHOT")
		)
		(pad "19" smd rect
			(at -4.2418 0.25019 180)
			(size 1.524 0.3048)
			(layers "F.Cu" "F.Mask" "F.Paste")
			(net "NCT7904_VSEN1")
		)
		(pad "20" smd rect
			(at -4.2418 0.75057 180)
			(size 1.524 0.3048)
			(layers "F.Cu" "F.Mask" "F.Paste")
			(net "NCT7904_PECI")
		)
		(pad "21" smd rect
			(at -4.2418 1.24968 180)
			(size 1.524 0.3048)
			(layers "F.Cu" "F.Mask" "F.Paste")
			(net "NCT7904_THERMTRIP")
		)
		(pad "22" smd rect
			(at -4.2418 1.75006 180)
			(size 1.524 0.3048)
			(layers "F.Cu" "F.Mask" "F.Paste")
			(net "NCT7904_CLKIN")
		)
		(pad "23" smd rect
			(at -4.2418 2.25044 180)
			(size 1.524 0.3048)
			(layers "F.Cu" "F.Mask" "F.Paste")
			(net "I2C_C_SCL_NCT7904")
		)
		(pad "24" smd rect
			(at -4.2418 2.74955 180)
			(size 1.524 0.3048)
			(layers "F.Cu" "F.Mask" "F.Paste")
			(net "I2C_C_SDA_NCT7904")
		)
		(pad "25" smd rect
			(at -2.74955 4.2418 180)
			(size 0.3048 1.524)
			(layers "F.Cu" "F.Mask" "F.Paste")
			(net "FANIN_1")
		)
		(pad "26" smd rect
			(at -2.25044 4.2418 180)
			(size 0.3048 1.524)
			(layers "F.Cu" "F.Mask" "F.Paste")
			(net "FANIN_2")
		)
		(pad "27" smd rect
			(at -1.75006 4.2418 180)
			(size 0.3048 1.524)
			(layers "F.Cu" "F.Mask" "F.Paste")
			(net "NCT7904_ADR")
		)
		(pad "28" smd rect
			(at -1.24968 4.2418 180)
			(size 0.3048 1.524)
			(layers "F.Cu" "F.Mask" "F.Paste")
			(net "NCT7904_RSTOUT")
		)
		(pad "29" smd rect
			(at -0.75057 4.2418 180)
			(size 0.3048 1.524)
			(layers "F.Cu" "F.Mask" "F.Paste")
			(net "FANIN_11")
		)
		(pad "30" smd rect
			(at -0.25019 4.2418 180)
			(size 0.3048 1.524)
			(layers "F.Cu" "F.Mask" "F.Paste")
			(net "NCT7904D_PWM1")
		)
		(pad "31" smd rect
			(at 0.25019 4.2418 180)
			(size 0.3048 1.524)
			(layers "F.Cu" "F.Mask" "F.Paste")
			(net "FANIN_12")
		)
		(pad "32" smd rect
			(at 0.75057 4.2418 180)
			(size 0.3048 1.524)
			(layers "F.Cu" "F.Mask" "F.Paste")
			(net "NCT7904D_PWM2")
		)
		(pad "33" smd rect
			(at 1.24968 4.2418 180)
			(size 0.3048 1.524)
			(layers "F.Cu" "F.Mask" "F.Paste")
			(net "FANIN_9")
		)
		(pad "34" smd rect
			(at 1.75006 4.2418 180)
			(size 0.3048 1.524)
			(layers "F.Cu" "F.Mask" "F.Paste")
			(net "NCT7904D_PWM3")
		)
		(pad "35" smd rect
			(at 2.25044 4.2418 180)
			(size 0.3048 1.524)
			(layers "F.Cu" "F.Mask" "F.Paste")
			(net "FANIN_10")
		)
		(pad "36" smd rect
			(at 2.74955 4.2418 180)
			(size 0.3048 1.524)
			(layers "F.Cu" "F.Mask" "F.Paste")
			(net "NCT7904D_PWM4")
		)
		(pad "37" smd rect
			(at 4.2418 2.74955 180)
			(size 1.524 0.3048)
			(layers "F.Cu" "F.Mask" "F.Paste")
			(net "FANIN_7")
		)
		(pad "38" smd rect
			(at 4.2418 2.25044 180)
			(size 1.524 0.3048)
			(layers "F.Cu" "F.Mask" "F.Paste")
			(net "FANIN_8")
		)
		(pad "39" smd rect
			(at 4.2418 1.75006 180)
			(size 1.524 0.3048)
			(layers "F.Cu" "F.Mask" "F.Paste")
			(net "FANIN_5")
		)
		(pad "40" smd rect
			(at 4.2418 1.24968 180)
			(size 1.524 0.3048)
			(layers "F.Cu" "F.Mask" "F.Paste")
			(net "FANIN_6")
		)
		(pad "41" smd rect
			(at 4.2418 0.75057 180)
			(size 1.524 0.3048)
			(layers "F.Cu" "F.Mask" "F.Paste")
			(net "FANIN_3")
		)
		(pad "42" smd rect
			(at 4.2418 0.25019 180)
			(size 1.524 0.3048)
			(layers "F.Cu" "F.Mask" "F.Paste")
			(net "FANIN_4")
		)
		(pad "43" smd rect
			(at 4.2418 -0.25019 180)
			(size 1.524 0.3048)
			(layers "F.Cu" "F.Mask" "F.Paste")
			(net "NCT7904_GND")
		)
		(pad "44" smd rect
			(at 4.2418 -0.75057 180)
			(size 1.524 0.3048)
			(layers "F.Cu" "F.Mask" "F.Paste")
			(net "NCT7904_TMPALM")
		)
		(pad "45" smd rect
			(at 4.2418 -1.24968 180)
			(size 1.524 0.3048)
			(layers "F.Cu" "F.Mask" "F.Paste")
			(net "NCT7904_LED")
		)
		(pad "46" smd rect
			(at 4.2418 -1.75006 180)
			(size 1.524 0.3048)
			(layers "F.Cu" "F.Mask" "F.Paste")
			(net "NCT7904_RESET")
		)
		(pad "47" smd rect
			(at 4.2418 -2.25044 180)
			(size 1.524 0.3048)
			(layers "F.Cu" "F.Mask" "F.Paste")
			(net "NCT7904_CASEOPEN")
		)
		(pad "48" smd rect
			(at 4.2418 -2.74955 180)
			(size 1.524 0.3048)
			(layers "F.Cu" "F.Mask" "F.Paste")
			(net "NCT7904_3VSB")
		)
	)
	(footprint ""
		(layer "F.Cu")
		(at 19.9644 -145.4912 180)
		(property "Reference" "PR114"
			(at 0 0 180)
			(layer "F.SilkS")
			(hide yes)
			(effects
				(font
					(size 1.27 1.27)
				)
			)
		)
		(property "Value" "20KR2F-L-GP"
			(at 0.064008 -3.993896 180)
			(unlocked yes)
			(layer "F.Fab")
			(hide yes)
			(effects
				(font
					(size 1.016 1.016)
					(thickness 0.1524)
				)
			)
		)
		(property "Device Type" "R402H16"
			(at 0.064008 -5.517896 180)
			(unlocked yes)
			(layer "F.Fab")
			(hide yes)
			(effects
				(font
					(size 1.016 1.016)
					(thickness 0.1524)
				)
			)
		)
		(duplicate_pad_numbers_are_jumpers no)
		(fp_line
			(start 0.508 -0.9398)
			(end -0.508 -0.9398)
			(stroke
				(width 0.1524)
				(type default)
			)
			(layer "F.SilkS")
		)
		(fp_line
			(start -0.508 -0.9398)
			(end -0.508 0.9398)
			(stroke
				(width 0.1524)
				(type default)
			)
			(layer "F.SilkS")
		)
		(fp_rect
			(start -0.508 0.9398)
			(end 0.508 -0.9398)
			(stroke
				(width 0)
				(type default)
			)
			(fill no)
			(layer "F.CrtYd")
		)
		(fp_rect
			(start -0.508 0.9398)
			(end 0.508 -0.9398)
			(stroke
				(width 0)
				(type default)
			)
			(fill no)
			(layer "F.Fab")
		)
		(pad "1" smd custom
			(at 0 -0.4445 180)
			(size 0.1397 0.1397)
			(layers "F.Cu" "F.Mask" "F.Paste")
			(net "P12VU_2490_PROG")
			(options
				(clearance outline)
				(anchor circle)
			)
			(primitives
				(gr_poly
					(pts
						(arc
							(start -0.1778 -0.2794)
							(mid -0.249642 -0.249642)
							(end -0.2794 -0.1778)
						)
						(arc
							(start -0.2794 0.1778)
							(mid -0.249642 0.249642)
							(end -0.1778 0.2794)
						)
						(arc
							(start 0.1778 0.2794)
							(mid 0.249642 0.249642)
							(end 0.2794 0.1778)
						)
						(arc
							(start 0.2794 -0.1778)
							(mid 0.249642 -0.249642)
							(end 0.1778 -0.2794)
						)
					)
					(width 0)
					(fill yes)
				)
			)
		)
		(pad "2" smd custom
			(at 0 0.4445 180)
			(size 0.1397 0.1397)
			(layers "F.Cu" "F.Mask" "F.Paste")
			(net "GND")
			(options
				(clearance outline)
				(anchor circle)
			)
			(primitives
				(gr_poly
					(pts
						(arc
							(start -0.1778 -0.2794)
							(mid -0.249642 -0.249642)
							(end -0.2794 -0.1778)
						)
						(arc
							(start -0.2794 0.1778)
							(mid -0.249642 0.249642)
							(end -0.1778 0.2794)
						)
						(arc
							(start 0.1778 0.2794)
							(mid 0.249642 0.249642)
							(end 0.2794 0.1778)
						)
						(arc
							(start 0.2794 -0.1778)
							(mid 0.249642 -0.249642)
							(end 0.1778 -0.2794)
						)
					)
					(width 0)
					(fill yes)
				)
			)
		)
	)
	(footprint ""
		(layer "F.Cu")
		(at 19.5834 -266.7254)
		(property "Reference" "F4"
			(at 0 0 0)
			(layer "F.SilkS")
			(hide yes)
			(effects
				(font
					(size 1.27 1.27)
				)
			)
		)
		(property "Value" "FUSE-3A15V-GP"
			(at 0.2286 -10.5918 0)
			(unlocked yes)
			(layer "F.Fab")
			(hide yes)
			(effects
				(font
					(size 1.016 1.016)
					(thickness 0.1524)
				)
			)
		)
		(property "Device Type" "FUSE-7452-UH50"
			(at 0.2286 -12.4968 0)
			(unlocked yes)
			(layer "F.Fab")
			(hide yes)
			(effects
				(font
					(size 1.016 1.016)
					(thickness 0.1524)
				)
			)
		)
		(duplicate_pad_numbers_are_jumpers no)
		(fp_line
			(start -4.9276 -2.921)
			(end 4.9276 -2.921)
			(stroke
				(width 0.1524)
				(type default)
			)
			(layer "F.SilkS")
		)
		(fp_line
			(start -4.9276 2.921)
			(end -4.9276 -2.921)
			(stroke
				(width 0.1524)
				(type default)
			)
			(layer "F.SilkS")
		)
		(fp_line
			(start 4.9276 -2.921)
			(end 4.9276 2.921)
			(stroke
				(width 0.1524)
				(type default)
			)
			(layer "F.SilkS")
		)
		(fp_line
			(start 4.9276 2.921)
			(end -4.9276 2.921)
			(stroke
				(width 0.1524)
				(type default)
			)
			(layer "F.SilkS")
		)
		(fp_poly
			(pts
				(xy -5.08 3.0988) (xy 5.08 3.0988) (xy 5.08 -3.0988) (xy -5.08 -3.0988)
			)
			(stroke
				(width 0)
				(type default)
			)
			(fill no)
			(layer "F.CrtYd")
		)
		(fp_poly
			(pts
				(xy -5.08 -3.0988) (xy 5.08 -3.0988) (xy 5.08 3.0988) (xy -5.08 3.0988)
			)
			(stroke
				(width 0)
				(type default)
			)
			(fill no)
			(layer "F.Fab")
		)
		(pad "1" smd rect
			(at -3.4036 0)
			(size 2.2098 5.2832)
			(layers "F.Cu" "F.Mask" "F.Paste")
			(net "P12V_FAN3")
		)
		(pad "2" smd rect
			(at 3.4036 0)
			(size 2.2098 5.2832)
			(layers "F.Cu" "F.Mask" "F.Paste")
			(net "P12V")
		)
	)
	(footprint ""
		(layer "F.Cu")
		(at 33.909 -374.396)
		(property "Reference" "PC6"
			(at 0 0 0)
			(layer "F.SilkS")
			(hide yes)
			(effects
				(font
					(size 1.27 1.27)
				)
			)
		)
		(property "Value" "SCD022U50V3KX-2-GP"
			(at 0 -2.8194 0)
			(unlocked yes)
			(layer "F.Fab")
			(hide yes)
			(effects
				(font
					(size 1.016 1.016)
					(thickness 0.1524)
				)
			)
		)
		(property "Device Type" "C603"
			(at 0 -4.3434 0)
			(unlocked yes)
			(layer "F.Fab")
			(hide yes)
			(effects
				(font
					(size 1.016 1.016)
					(thickness 0.1524)
				)
			)
		)
		(duplicate_pad_numbers_are_jumpers no)
		(fp_line
			(start 0.508 0)
			(end -0.508 0)
			(stroke
				(width 0.2032)
				(type default)
			)
			(layer "F.SilkS")
		)
		(fp_rect
			(start -0.5842 1.3335)
			(end 0.5842 -1.3335)
			(stroke
				(width 0)
				(type default)
			)
			(fill no)
			(layer "F.CrtYd")
		)
		(fp_rect
			(start -0.5842 1.3335)
			(end 0.5842 -1.3335)
			(stroke
				(width 0)
				(type default)
			)
			(fill no)
			(layer "F.Fab")
		)
		(pad "1" smd custom
			(at 0 -0.762)
			(size 0.2159 0.2159)
			(layers "F.Cu" "F.Mask" "F.Paste")
			(net "ADM1276_GATE_RC")
			(options
				(clearance outline)
				(anchor circle)
			)
			(primitives
				(gr_poly
					(pts
						(arc
							(start -0.3302 -0.4318)
							(mid -0.402042 -0.402042)
							(end -0.4318 -0.3302)
						)
						(arc
							(start -0.4318 0.3302)
							(mid -0.402042 0.402042)
							(end -0.3302 0.4318)
						)
						(arc
							(start 0.3302 0.4318)
							(mid 0.402042 0.402042)
							(end 0.4318 0.3302)
						)
						(arc
							(start 0.4318 -0.3302)
							(mid 0.402042 -0.402042)
							(end 0.3302 -0.4318)
						)
					)
					(width 0)
					(fill yes)
				)
			)
		)
		(pad "2" smd custom
			(at 0 0.762)
			(size 0.2159 0.2159)
			(layers "F.Cu" "F.Mask" "F.Paste")
			(net "GND")
			(options
				(clearance outline)
				(anchor circle)
			)
			(primitives
				(gr_poly
					(pts
						(arc
							(start -0.3302 -0.4318)
							(mid -0.402042 -0.402042)
							(end -0.4318 -0.3302)
						)
						(arc
							(start -0.4318 0.3302)
							(mid -0.402042 0.402042)
							(end -0.3302 0.4318)
						)
						(arc
							(start 0.3302 0.4318)
							(mid 0.402042 0.402042)
							(end 0.4318 0.3302)
						)
						(arc
							(start 0.4318 -0.3302)
							(mid 0.402042 -0.402042)
							(end 0.3302 -0.4318)
						)
					)
					(width 0)
					(fill yes)
				)
			)
		)
	)
	(footprint ""
		(layer "F.Cu")
		(at 14.3764 -49.0982)
		(property "Reference" "R186"
			(at 0 0 0)
			(layer "F.SilkS")
			(hide yes)
			(effects
				(font
					(size 1.27 1.27)
				)
			)
		)
		(property "Value" "0R2J-2-GP"
			(at 0.064008 -3.993896 0)
			(unlocked yes)
			(layer "F.Fab")
			(hide yes)
			(effects
				(font
					(size 1.016 1.016)
					(thickness 0.1524)
				)
			)
		)
		(property "Device Type" "R402H16"
			(at 0.064008 -5.517896 0)
			(unlocked yes)
			(layer "F.Fab")
			(hide yes)
			(effects
				(font
					(size 1.016 1.016)
					(thickness 0.1524)
				)
			)
		)
		(duplicate_pad_numbers_are_jumpers no)
		(fp_line
			(start -0.508 -0.9398)
			(end -0.508 0.9398)
			(stroke
				(width 0.1524)
				(type default)
			)
			(layer "F.SilkS")
		)
		(fp_line
			(start 0.508 -0.9398)
			(end -0.508 -0.9398)
			(stroke
				(width 0.1524)
				(type default)
			)
			(layer "F.SilkS")
		)
		(fp_rect
			(start -0.508 0.9398)
			(end 0.508 -0.9398)
			(stroke
				(width 0)
				(type default)
			)
			(fill no)
			(layer "F.CrtYd")
		)
		(fp_rect
			(start -0.508 0.9398)
			(end 0.508 -0.9398)
			(stroke
				(width 0)
				(type default)
			)
			(fill no)
			(layer "F.Fab")
		)
		(pad "1" smd custom
			(at 0 -0.4445)
			(size 0.1397 0.1397)
			(layers "F.Cu" "F.Mask" "F.Paste")
			(net "SD_LATCH_RELEASE_U")
			(options
				(clearance outline)
				(anchor circle)
			)
			(primitives
				(gr_poly
					(pts
						(arc
							(start -0.1778 -0.2794)
							(mid -0.249642 -0.249642)
							(end -0.2794 -0.1778)
						)
						(arc
							(start -0.2794 0.1778)
							(mid -0.249642 0.249642)
							(end -0.1778 0.2794)
						)
						(arc
							(start 0.1778 0.2794)
							(mid 0.249642 0.249642)
							(end 0.2794 0.1778)
						)
						(arc
							(start 0.2794 -0.1778)
							(mid 0.249642 -0.249642)
							(end 0.1778 -0.2794)
						)
					)
					(width 0)
					(fill yes)
				)
			)
		)
		(pad "2" smd custom
			(at 0 0.4445)
			(size 0.1397 0.1397)
			(layers "F.Cu" "F.Mask" "F.Paste")
			(net "D_LATCH_PRE#")
			(options
				(clearance outline)
				(anchor circle)
			)
			(primitives
				(gr_poly
					(pts
						(arc
							(start -0.1778 -0.2794)
							(mid -0.249642 -0.249642)
							(end -0.2794 -0.1778)
						)
						(arc
							(start -0.2794 0.1778)
							(mid -0.249642 0.249642)
							(end -0.1778 0.2794)
						)
						(arc
							(start 0.1778 0.2794)
							(mid 0.249642 0.249642)
							(end 0.2794 0.1778)
						)
						(arc
							(start 0.2794 -0.1778)
							(mid 0.249642 -0.249642)
							(end 0.1778 -0.2794)
						)
					)
					(width 0)
					(fill yes)
				)
			)
		)
	)
	(footprint ""
		(layer "F.Cu")
		(at 28.582366 -242.327176)
		(property "Reference" "R42"
			(at 0 0 0)
			(layer "F.SilkS")
			(hide yes)
			(effects
				(font
					(size 1.27 1.27)
				)
			)
		)
		(property "Value" "4K7R2J-2-GP"
			(at 0.064008 -3.993896 0)
			(unlocked yes)
			(layer "F.Fab")
			(hide yes)
			(effects
				(font
					(size 1.016 1.016)
					(thickness 0.1524)
				)
			)
		)
		(property "Device Type" "R402H16"
			(at 0.064008 -5.517896 0)
			(unlocked yes)
			(layer "F.Fab")
			(hide yes)
			(effects
				(font
					(size 1.016 1.016)
					(thickness 0.1524)
				)
			)
		)
		(duplicate_pad_numbers_are_jumpers no)
		(fp_line
			(start -0.508 -0.9398)
			(end -0.508 0.9398)
			(stroke
				(width 0.1524)
				(type default)
			)
			(layer "F.SilkS")
		)
		(fp_line
			(start 0.508 -0.9398)
			(end -0.508 -0.9398)
			(stroke
				(width 0.1524)
				(type default)
			)
			(layer "F.SilkS")
		)
		(fp_rect
			(start -0.508 0.9398)
			(end 0.508 -0.9398)
			(stroke
				(width 0)
				(type default)
			)
			(fill no)
			(layer "F.CrtYd")
		)
		(fp_rect
			(start -0.508 0.9398)
			(end 0.508 -0.9398)
			(stroke
				(width 0)
				(type default)
			)
			(fill no)
			(layer "F.Fab")
		)
		(pad "1" smd custom
			(at 0 -0.4445)
			(size 0.1397 0.1397)
			(layers "F.Cu" "F.Mask" "F.Paste")
			(net "FCB_EEPROM_A0")
			(options
				(clearance outline)
				(anchor circle)
			)
			(primitives
				(gr_poly
					(pts
						(arc
							(start -0.1778 -0.2794)
							(mid -0.249642 -0.249642)
							(end -0.2794 -0.1778)
						)
						(arc
							(start -0.2794 0.1778)
							(mid -0.249642 0.249642)
							(end -0.1778 0.2794)
						)
						(arc
							(start 0.1778 0.2794)
							(mid 0.249642 0.249642)
							(end 0.2794 0.1778)
						)
						(arc
							(start 0.2794 -0.1778)
							(mid 0.249642 -0.249642)
							(end 0.1778 -0.2794)
						)
					)
					(width 0)
					(fill yes)
				)
			)
		)
		(pad "2" smd custom
			(at 0 0.4445)
			(size 0.1397 0.1397)
			(layers "F.Cu" "F.Mask" "F.Paste")
			(net "GND")
			(options
				(clearance outline)
				(anchor circle)
			)
			(primitives
				(gr_poly
					(pts
						(arc
							(start -0.1778 -0.2794)
							(mid -0.249642 -0.249642)
							(end -0.2794 -0.1778)
						)
						(arc
							(start -0.2794 0.1778)
							(mid -0.249642 0.249642)
							(end -0.1778 0.2794)
						)
						(arc
							(start 0.1778 0.2794)
							(mid 0.249642 0.249642)
							(end 0.2794 0.1778)
						)
						(arc
							(start 0.2794 -0.1778)
							(mid 0.249642 -0.249642)
							(end 0.1778 -0.2794)
						)
					)
					(width 0)
					(fill yes)
				)
			)
		)
	)
	(footprint ""
		(layer "F.Cu")
		(at 32.424624 -175.80991 90)
		(property "Reference" "R19"
			(at 0 0 90)
			(layer "F.SilkS")
			(hide yes)
			(effects
				(font
					(size 1.27 1.27)
				)
			)
		)
		(property "Value" "100KR2F-L1-GP"
			(at 0.064008 -3.993896 90)
			(unlocked yes)
			(layer "F.Fab")
			(hide yes)
			(effects
				(font
					(size 1.016 1.016)
					(thickness 0.1524)
				)
			)
		)
		(property "Device Type" "R402H16"
			(at 0.064008 -5.517896 90)
			(unlocked yes)
			(layer "F.Fab")
			(hide yes)
			(effects
				(font
					(size 1.016 1.016)
					(thickness 0.1524)
				)
			)
		)
		(duplicate_pad_numbers_are_jumpers no)
		(fp_line
			(start 0.508 -0.9398)
			(end -0.508 -0.9398)
			(stroke
				(width 0.1524)
				(type default)
			)
			(layer "F.SilkS")
		)
		(fp_line
			(start -0.508 -0.9398)
			(end -0.508 0.9398)
			(stroke
				(width 0.1524)
				(type default)
			)
			(layer "F.SilkS")
		)
		(fp_rect
			(start -0.508 0.9398)
			(end 0.508 -0.9398)
			(stroke
				(width 0)
				(type default)
			)
			(fill no)
			(layer "F.CrtYd")
		)
		(fp_rect
			(start -0.508 0.9398)
			(end 0.508 -0.9398)
			(stroke
				(width 0)
				(type default)
			)
			(fill no)
			(layer "F.Fab")
		)
		(pad "1" smd custom
			(at 0 -0.4445 90)
			(size 0.1397 0.1397)
			(layers "F.Cu" "F.Mask" "F.Paste")
			(net "PWM_EXP_2A")
			(options
				(clearance outline)
				(anchor circle)
			)
			(primitives
				(gr_poly
					(pts
						(arc
							(start -0.1778 -0.2794)
							(mid -0.249642 -0.249642)
							(end -0.2794 -0.1778)
						)
						(arc
							(start -0.2794 0.1778)
							(mid -0.249642 0.249642)
							(end -0.1778 0.2794)
						)
						(arc
							(start 0.1778 0.2794)
							(mid 0.249642 0.249642)
							(end 0.2794 0.1778)
						)
						(arc
							(start 0.2794 -0.1778)
							(mid 0.249642 -0.249642)
							(end 0.1778 -0.2794)
						)
					)
					(width 0)
					(fill yes)
				)
			)
		)
		(pad "2" smd custom
			(at 0 0.4445 90)
			(size 0.1397 0.1397)
			(layers "F.Cu" "F.Mask" "F.Paste")
			(net "GND")
			(options
				(clearance outline)
				(anchor circle)
			)
			(primitives
				(gr_poly
					(pts
						(arc
							(start -0.1778 -0.2794)
							(mid -0.249642 -0.249642)
							(end -0.2794 -0.1778)
						)
						(arc
							(start -0.2794 0.1778)
							(mid -0.249642 0.249642)
							(end -0.1778 0.2794)
						)
						(arc
							(start 0.1778 0.2794)
							(mid 0.249642 0.249642)
							(end 0.2794 0.1778)
						)
						(arc
							(start 0.2794 -0.1778)
							(mid 0.249642 -0.249642)
							(end 0.1778 -0.2794)
						)
					)
					(width 0)
					(fill yes)
				)
			)
		)
	)
	(footprint ""
		(layer "F.Cu")
		(at 14.8844 -42.4942 -90)
		(property "Reference" "R173"
			(at 0 0 270)
			(layer "F.SilkS")
			(hide yes)
			(effects
				(font
					(size 1.27 1.27)
				)
			)
		)
		(property "Value" "0R2J-2-GP"
			(at 0.064008 -3.993896 270)
			(unlocked yes)
			(layer "F.Fab")
			(hide yes)
			(effects
				(font
					(size 1.016 1.016)
					(thickness 0.1524)
				)
			)
		)
		(property "Device Type" "R402H16"
			(at 0.064008 -5.517896 270)
			(unlocked yes)
			(layer "F.Fab")
			(hide yes)
			(effects
				(font
					(size 1.016 1.016)
					(thickness 0.1524)
				)
			)
		)
		(duplicate_pad_numbers_are_jumpers no)
		(fp_line
			(start -0.508 -0.9398)
			(end -0.508 0.9398)
			(stroke
				(width 0.1524)
				(type default)
			)
			(layer "F.SilkS")
		)
		(fp_line
			(start 0.508 -0.9398)
			(end -0.508 -0.9398)
			(stroke
				(width 0.1524)
				(type default)
			)
			(layer "F.SilkS")
		)
		(fp_rect
			(start -0.508 0.9398)
			(end 0.508 -0.9398)
			(stroke
				(width 0)
				(type default)
			)
			(fill no)
			(layer "F.CrtYd")
		)
		(fp_rect
			(start -0.508 0.9398)
			(end 0.508 -0.9398)
			(stroke
				(width 0)
				(type default)
			)
			(fill no)
			(layer "F.Fab")
		)
		(pad "1" smd custom
			(at 0 -0.4445 270)
			(size 0.1397 0.1397)
			(layers "F.Cu" "F.Mask" "F.Paste")
			(net "SELF_2B_HB")
			(options
				(clearance outline)
				(anchor circle)
			)
			(primitives
				(gr_poly
					(pts
						(arc
							(start -0.1778 -0.2794)
							(mid -0.249642 -0.249642)
							(end -0.2794 -0.1778)
						)
						(arc
							(start -0.2794 0.1778)
							(mid -0.249642 0.249642)
							(end -0.1778 0.2794)
						)
						(arc
							(start 0.1778 0.2794)
							(mid 0.249642 0.249642)
							(end 0.2794 0.1778)
						)
						(arc
							(start 0.2794 -0.1778)
							(mid 0.249642 -0.249642)
							(end 0.1778 -0.2794)
						)
					)
					(width 0)
					(fill yes)
				)
			)
		)
		(pad "2" smd custom
			(at 0 0.4445 270)
			(size 0.1397 0.1397)
			(layers "F.Cu" "F.Mask" "F.Paste")
			(net "SEB_PEER_1B_HB")
			(options
				(clearance outline)
				(anchor circle)
			)
			(primitives
				(gr_poly
					(pts
						(arc
							(start -0.1778 -0.2794)
							(mid -0.249642 -0.249642)
							(end -0.2794 -0.1778)
						)
						(arc
							(start -0.2794 0.1778)
							(mid -0.249642 0.249642)
							(end -0.1778 0.2794)
						)
						(arc
							(start 0.1778 0.2794)
							(mid 0.249642 0.249642)
							(end 0.2794 0.1778)
						)
						(arc
							(start 0.2794 -0.1778)
							(mid 0.249642 -0.249642)
							(end 0.1778 -0.2794)
						)
					)
					(width 0)
					(fill yes)
				)
			)
		)
	)
	(footprint ""
		(layer "F.Cu")
		(at 7.949946 -411.465014 -90)
		(property "Reference" "LED2"
			(at 0 0 270)
			(layer "F.SilkS")
			(hide yes)
			(effects
				(font
					(size 1.27 1.27)
				)
			)
		)
		(property "Value" "LED-RB-6-GP"
			(at -4.6736 3.8354 270)
			(unlocked yes)
			(layer "F.Fab")
			(hide yes)
			(effects
				(font
					(size 1.016 1.016)
					(thickness 0.1524)
				)
			)
		)
		(property "Device Type" "LED-100-3P-067106H325"
			(at -4.6736 2.3114 270)
			(unlocked yes)
			(layer "F.Fab")
			(hide yes)
			(effects
				(font
					(size 1.016 1.016)
					(thickness 0.1524)
				)
			)
		)
		(duplicate_pad_numbers_are_jumpers no)
		(fp_line
			(start -1.7526 10.414)
			(end -1.7526 6.6548)
			(stroke
				(width 0.1524)
				(type default)
			)
			(layer "F.SilkS")
		)
		(fp_line
			(start 1.7526 10.414)
			(end -1.7526 10.414)
			(stroke
				(width 0.1524)
				(type default)
			)
			(layer "F.SilkS")
		)
		(fp_line
			(start -3.6068 6.6548)
			(end -3.6068 -0.889)
			(stroke
				(width 0.1524)
				(type default)
			)
			(layer "F.SilkS")
		)
		(fp_line
			(start -1.7526 6.6548)
			(end -3.6068 6.6548)
			(stroke
				(width 0.1524)
				(type default)
			)
			(layer "F.SilkS")
		)
		(fp_line
			(start 1.7526 6.6548)
			(end 1.7526 10.414)
			(stroke
				(width 0.1524)
				(type default)
			)
			(layer "F.SilkS")
		)
		(fp_line
			(start 3.6068 6.6548)
			(end 1.7526 6.6548)
			(stroke
				(width 0.1524)
				(type default)
			)
			(layer "F.SilkS")
		)
		(fp_line
			(start -3.6068 -0.889)
			(end 3.6068 -0.889)
			(stroke
				(width 0.1524)
				(type default)
			)
			(layer "F.SilkS")
		)
		(fp_line
			(start 3.6068 -0.889)
			(end 3.6068 6.6548)
			(stroke
				(width 0.1524)
				(type default)
			)
			(layer "F.SilkS")
		)
		(fp_circle
			(center -2.54 0)
			(end -2.54 -0.9906)
			(stroke
				(width 0.3048)
				(type default)
			)
			(fill no)
			(layer "F.SilkS")
		)
		(fp_circle
			(center 0 0)
			(end 0 -0.9906)
			(stroke
				(width 0.3048)
				(type default)
			)
			(fill no)
			(layer "F.SilkS")
		)
		(fp_circle
			(center 2.54 0)
			(end 2.54 -0.9906)
			(stroke
				(width 0.3048)
				(type default)
			)
			(fill no)
			(layer "F.SilkS")
		)
		(fp_poly
			(pts
				(xy -1.4986 10.1473) (xy -1.4986 6.4008) (xy -3.3528 6.4008) (xy -3.3528 -0.3937) (xy 3.3528 -0.3937)
				(xy 3.3528 6.4008) (xy 1.4986 6.4008) (xy 1.4986 10.1473)
			)
			(stroke
				(width 0)
				(type default)
			)
			(fill no)
			(layer "F.CrtYd")
		)
		(fp_poly
			(pts
				(xy -2.0066 10.668) (xy 2.0066 10.668) (xy 2.0066 6.9088) (xy 3.8608 6.9088) (xy 3.8608 2.2098)
				(xy 3.3528 2.2098) (xy 3.3528 6.4008) (xy 1.4986 6.4008) (xy 1.4986 10.1473) (xy -1.4986 10.1473)
				(xy -1.4986 6.4008) (xy -3.3528 6.4008) (xy -3.3528 -0.3937) (xy 3.3528 -0.3937) (xy 3.3528 2.1971)
				(xy 3.8608 2.1971) (xy 3.8608 -1.143) (xy -3.8608 -1.143) (xy -3.8608 6.9088) (xy -2.0066 6.9088)
			)
			(stroke
				(width 0)
				(type default)
			)
			(fill no)
			(layer "F.CrtYd")
		)
		(fp_poly
			(pts
				(xy -2.0066 10.668) (xy -2.0066 6.9088) (xy -3.8608 6.9088) (xy -3.8608 -1.143) (xy 3.8608 -1.143)
				(xy 3.8608 6.9088) (xy 2.0066 6.9088) (xy 2.0066 10.668)
			)
			(stroke
				(width 0)
				(type default)
			)
			(fill no)
			(layer "F.Fab")
		)
		(pad "1" thru_hole circle
			(at 2.54 0 270)
			(size 1.27 1.27)
			(drill 0.889)
			(layers "*.Cu" "*.Mask")
			(remove_unused_layers no)
			(net "LED_DR_LED1_BLUE")
			(clearance 0.1651)
			(thermal_gap 0.1651)
		)
		(pad "2" thru_hole circle
			(at 0 0 270)
			(size 1.27 1.27)
			(drill 0.889)
			(layers "*.Cu" "*.Mask")
			(remove_unused_layers no)
			(net "LED_DR_LED1_K")
			(clearance 0.1651)
			(thermal_gap 0.1651)
		)
		(pad "3" thru_hole circle
			(at -2.54 0 270)
			(size 1.27 1.27)
			(drill 0.889)
			(layers "*.Cu" "*.Mask")
			(remove_unused_layers no)
			(net "LED_DR_LED1")
			(clearance 0.1651)
			(thermal_gap 0.1651)
		)
	)
	(footprint ""
		(layer "F.Cu")
		(at 28.8544 -357.6828 90)
		(property "Reference" "R366"
			(at 0 0 90)
			(layer "F.SilkS")
			(hide yes)
			(effects
				(font
					(size 1.27 1.27)
				)
			)
		)
		(property "Value" "10KR2F-2-GP"
			(at 0.064008 -3.993896 90)
			(unlocked yes)
			(layer "F.Fab")
			(hide yes)
			(effects
				(font
					(size 1.016 1.016)
					(thickness 0.1524)
				)
			)
		)
		(property "Device Type" "R402H16"
			(at 0.064008 -5.517896 90)
			(unlocked yes)
			(layer "F.Fab")
			(hide yes)
			(effects
				(font
					(size 1.016 1.016)
					(thickness 0.1524)
				)
			)
		)
		(duplicate_pad_numbers_are_jumpers no)
		(fp_line
			(start 0.508 -0.9398)
			(end -0.508 -0.9398)
			(stroke
				(width 0.1524)
				(type default)
			)
			(layer "F.SilkS")
		)
		(fp_line
			(start -0.508 -0.9398)
			(end -0.508 0.9398)
			(stroke
				(width 0.1524)
				(type default)
			)
			(layer "F.SilkS")
		)
		(fp_rect
			(start -0.508 0.9398)
			(end 0.508 -0.9398)
			(stroke
				(width 0)
				(type default)
			)
			(fill no)
			(layer "F.CrtYd")
		)
		(fp_rect
			(start -0.508 0.9398)
			(end 0.508 -0.9398)
			(stroke
				(width 0)
				(type default)
			)
			(fill no)
			(layer "F.Fab")
		)
		(pad "1" smd custom
			(at 0 -0.4445 90)
			(size 0.1397 0.1397)
			(layers "F.Cu" "F.Mask" "F.Paste")
			(net "P3V3")
			(options
				(clearance outline)
				(anchor circle)
			)
			(primitives
				(gr_poly
					(pts
						(arc
							(start -0.1778 -0.2794)
							(mid -0.249642 -0.249642)
							(end -0.2794 -0.1778)
						)
						(arc
							(start -0.2794 0.1778)
							(mid -0.249642 0.249642)
							(end -0.1778 0.2794)
						)
						(arc
							(start 0.1778 0.2794)
							(mid 0.249642 0.249642)
							(end 0.2794 0.1778)
						)
						(arc
							(start 0.2794 -0.1778)
							(mid 0.249642 -0.249642)
							(end 0.1778 -0.2794)
						)
					)
					(width 0)
					(fill yes)
				)
			)
		)
		(pad "2" smd custom
			(at 0 0.4445 90)
			(size 0.1397 0.1397)
			(layers "F.Cu" "F.Mask" "F.Paste")
			(net "TEMP_ALM#")
			(options
				(clearance outline)
				(anchor circle)
			)
			(primitives
				(gr_poly
					(pts
						(arc
							(start -0.1778 -0.2794)
							(mid -0.249642 -0.249642)
							(end -0.2794 -0.1778)
						)
						(arc
							(start -0.2794 0.1778)
							(mid -0.249642 0.249642)
							(end -0.1778 0.2794)
						)
						(arc
							(start 0.1778 0.2794)
							(mid 0.249642 0.249642)
							(end 0.2794 0.1778)
						)
						(arc
							(start 0.2794 -0.1778)
							(mid 0.249642 -0.249642)
							(end 0.1778 -0.2794)
						)
					)
					(width 0)
					(fill yes)
				)
			)
		)
	)
	(footprint ""
		(layer "F.Cu")
		(at 7.3152 -78.5114)
		(property "Reference" "Q4"
			(at 0 0 0)
			(layer "F.SilkS")
			(hide yes)
			(effects
				(font
					(size 1.27 1.27)
				)
			)
		)
		(property "Value" "PMBS3904-1-GP"
			(at 0 -9.0932 0)
			(unlocked yes)
			(layer "F.Fab")
			(hide yes)
			(effects
				(font
					(size 1.016 1.016)
					(thickness 0.1524)
				)
			)
		)
		(property "Device Type" "SOT-23-10H44"
			(at 0 -10.6172 0)
			(unlocked yes)
			(layer "F.Fab")
			(hide yes)
			(effects
				(font
					(size 1.016 1.016)
					(thickness 0.1524)
				)
			)
		)
		(duplicate_pad_numbers_are_jumpers no)
		(fp_line
			(start -1.7526 1.8796)
			(end -1.7526 0.9906)
			(stroke
				(width 0.3302)
				(type default)
			)
			(layer "F.SilkS")
		)
		(fp_line
			(start -1.651 -1.778)
			(end -1.651 1.778)
			(stroke
				(width 0.1524)
				(type default)
			)
			(layer "F.SilkS")
		)
		(fp_line
			(start -1.651 1.778)
			(end 1.651 1.778)
			(stroke
				(width 0.1524)
				(type default)
			)
			(layer "F.SilkS")
		)
		(fp_line
			(start -1.279398 2.152142)
			(end -0.9906 1.86309)
			(stroke
				(width 0.0127)
				(type default)
			)
			(layer "F.SilkS")
		)
		(fp_line
			(start -1.279144 2.15265)
			(end -0.701294 2.15265)
			(stroke
				(width 0.0127)
				(type default)
			)
			(layer "F.SilkS")
		)
		(fp_line
			(start -1.260856 2.1336)
			(end -0.720344 2.1336)
			(stroke
				(width 0.0127)
				(type default)
			)
			(layer "F.SilkS")
		)
		(fp_line
			(start -1.251458 2.124202)
			(end -0.729996 2.124202)
			(stroke
				(width 0.0127)
				(type default)
			)
			(layer "F.SilkS")
		)
		(fp_line
			(start -1.241806 2.11455)
			(end -0.739394 2.11455)
			(stroke
				(width 0.0127)
				(type default)
			)
			(layer "F.SilkS")
		)
		(fp_line
			(start -1.232408 2.105152)
			(end -0.749046 2.105152)
			(stroke
				(width 0.0127)
				(type default)
			)
			(layer "F.SilkS")
		)
		(fp_line
			(start -1.222756 2.0955)
			(end -0.758444 2.0955)
			(stroke
				(width 0.0127)
				(type default)
			)
			(layer "F.SilkS")
		)
		(fp_line
			(start -1.213358 2.086102)
			(end -0.768096 2.086102)
			(stroke
				(width 0.0127)
				(type default)
			)
			(layer "F.SilkS")
		)
		(fp_line
			(start -1.203706 2.07645)
			(end -0.777494 2.07645)
			(stroke
				(width 0.0127)
				(type default)
			)
			(layer "F.SilkS")
		)
		(fp_line
			(start -1.194308 2.067052)
			(end -0.787146 2.067052)
			(stroke
				(width 0.0127)
				(type default)
			)
			(layer "F.SilkS")
		)
		(fp_line
			(start -1.184656 2.0574)
			(end -0.796544 2.0574)
			(stroke
				(width 0.0127)
				(type default)
			)
			(layer "F.SilkS")
		)
		(fp_line
			(start -1.175258 2.048002)
			(end -0.806196 2.048002)
			(stroke
				(width 0.0127)
				(type default)
			)
			(layer "F.SilkS")
		)
		(fp_line
			(start -1.165606 2.03835)
			(end -0.815594 2.03835)
			(stroke
				(width 0.0127)
				(type default)
			)
			(layer "F.SilkS")
		)
		(fp_line
			(start -1.156208 2.028952)
			(end -0.825246 2.028952)
			(stroke
				(width 0.0127)
				(type default)
			)
			(layer "F.SilkS")
		)
		(fp_line
			(start -1.146556 2.0193)
			(end -0.834644 2.0193)
			(stroke
				(width 0.0127)
				(type default)
			)
			(layer "F.SilkS")
		)
		(fp_line
			(start -1.137158 2.009902)
			(end -0.844296 2.009902)
			(stroke
				(width 0.0127)
				(type default)
			)
			(layer "F.SilkS")
		)
		(fp_line
			(start -1.127506 2.00025)
			(end -0.853694 2.00025)
			(stroke
				(width 0.0127)
				(type default)
			)
			(layer "F.SilkS")
		)
		(fp_line
			(start -1.118108 1.990852)
			(end -0.863346 1.990852)
			(stroke
				(width 0.0127)
				(type default)
			)
			(layer "F.SilkS")
		)
		(fp_line
			(start -1.108456 1.9812)
			(end -0.872744 1.9812)
			(stroke
				(width 0.0127)
				(type default)
			)
			(layer "F.SilkS")
		)
		(fp_line
			(start -1.099058 1.971802)
			(end -0.882396 1.971802)
			(stroke
				(width 0.0127)
				(type default)
			)
			(layer "F.SilkS")
		)
		(fp_line
			(start -1.089406 1.96215)
			(end -0.891794 1.96215)
			(stroke
				(width 0.0127)
				(type default)
			)
			(layer "F.SilkS")
		)
		(fp_line
			(start -1.080008 1.952752)
			(end -0.901446 1.952752)
			(stroke
				(width 0.0127)
				(type default)
			)
			(layer "F.SilkS")
		)
		(fp_line
			(start -1.070356 1.9431)
			(end -0.910844 1.9431)
			(stroke
				(width 0.0127)
				(type default)
			)
			(layer "F.SilkS")
		)
		(fp_line
			(start -1.060958 1.933702)
			(end -0.920496 1.933702)
			(stroke
				(width 0.0127)
				(type default)
			)
			(layer "F.SilkS")
		)
		(fp_line
			(start -1.051306 1.92405)
			(end -0.929894 1.92405)
			(stroke
				(width 0.0127)
				(type default)
			)
			(layer "F.SilkS")
		)
		(fp_line
			(start -1.041908 1.914652)
			(end -0.939546 1.914652)
			(stroke
				(width 0.0127)
				(type default)
			)
			(layer "F.SilkS")
		)
		(fp_line
			(start -1.032256 1.905)
			(end -0.948944 1.905)
			(stroke
				(width 0.0127)
				(type default)
			)
			(layer "F.SilkS")
		)
		(fp_line
			(start -1.022858 1.895602)
			(end -0.958596 1.895602)
			(stroke
				(width 0.0127)
				(type default)
			)
			(layer "F.SilkS")
		)
		(fp_line
			(start -1.013206 1.88595)
			(end -0.967994 1.88595)
			(stroke
				(width 0.0127)
				(type default)
			)
			(layer "F.SilkS")
		)
		(fp_line
			(start -1.003808 1.876552)
			(end -0.977646 1.876552)
			(stroke
				(width 0.0127)
				(type default)
			)
			(layer "F.SilkS")
		)
		(fp_line
			(start -0.994156 1.8669)
			(end -0.987044 1.8669)
			(stroke
				(width 0.0127)
				(type default)
			)
			(layer "F.SilkS")
		)
		(fp_line
			(start -0.9906 1.86309)
			(end -0.701294 2.15265)
			(stroke
				(width 0.0127)
				(type default)
			)
			(layer "F.SilkS")
		)
		(fp_line
			(start -0.719074 2.145538)
			(end -1.265936 2.14122)
			(stroke
				(width 0.0127)
				(type default)
			)
			(layer "F.SilkS")
		)
		(fp_line
			(start -0.71628 2.15265)
			(end -1.26492 2.15265)
			(stroke
				(width 0.0127)
				(type default)
			)
			(layer "F.SilkS")
		)
		(fp_line
			(start -0.635 1.8796)
			(end -1.7526 1.8796)
			(stroke
				(width 0.3302)
				(type default)
			)
			(layer "F.SilkS")
		)
		(fp_line
			(start 1.651 -1.778)
			(end -1.651 -1.778)
			(stroke
				(width 0.1524)
				(type default)
			)
			(layer "F.SilkS")
		)
		(fp_line
			(start 1.651 1.778)
			(end 1.651 -1.778)
			(stroke
				(width 0.1524)
				(type default)
			)
			(layer "F.SilkS")
		)
		(fp_poly
			(pts
				(xy -1.285748 2.159) (xy -1.285748 1.8796) (xy -1.778 1.8796) (xy -1.778 -1.8796) (xy 1.778 -1.8796)
				(xy 1.778 1.8796) (xy -0.694944 1.8796) (xy -0.694944 2.159)
			)
			(stroke
				(width 0)
				(type default)
			)
			(fill no)
			(layer "F.CrtYd")
		)
		(fp_poly
			(pts
				(xy -1.285748 2.159) (xy -1.285748 1.8796) (xy -1.778 1.8796) (xy -1.778 -1.8796) (xy 1.778 -1.8796)
				(xy 1.778 1.8796) (xy -0.694944 1.8796) (xy -0.694944 2.159)
			)
			(stroke
				(width 0)
				(type default)
			)
			(fill no)
			(layer "F.Fab")
		)
		(pad "1" smd rect
			(at -0.98425 0.9525)
			(size 0.762 1.143)
			(layers "F.Cu" "F.Mask" "F.Paste")
			(net "LED_DR_LED4_B")
		)
		(pad "2" smd rect
			(at 0.98425 0.9525)
			(size 0.762 1.143)
			(layers "F.Cu" "F.Mask" "F.Paste")
			(net "GND")
		)
		(pad "3" smd rect
			(at 0 -0.9525)
			(size 0.762 1.143)
			(layers "F.Cu" "F.Mask" "F.Paste")
			(net "LED_DR_LED4_BLUE")
		)
	)
	(footprint ""
		(layer "F.Cu")
		(at 43.3324 -134.8232)
		(property "Reference" "PR96"
			(at 0 0 0)
			(layer "F.SilkS")
			(hide yes)
			(effects
				(font
					(size 1.27 1.27)
				)
			)
		)
		(property "Value" "0R2J-2-GP"
			(at 0.064008 -3.993896 0)
			(unlocked yes)
			(layer "F.Fab")
			(hide yes)
			(effects
				(font
					(size 1.016 1.016)
					(thickness 0.1524)
				)
			)
		)
		(property "Device Type" "R402H16"
			(at 0.064008 -5.517896 0)
			(unlocked yes)
			(layer "F.Fab")
			(hide yes)
			(effects
				(font
					(size 1.016 1.016)
					(thickness 0.1524)
				)
			)
		)
		(duplicate_pad_numbers_are_jumpers no)
		(fp_line
			(start -0.508 -0.9398)
			(end -0.508 0.9398)
			(stroke
				(width 0.1524)
				(type default)
			)
			(layer "F.SilkS")
		)
		(fp_line
			(start 0.508 -0.9398)
			(end -0.508 -0.9398)
			(stroke
				(width 0.1524)
				(type default)
			)
			(layer "F.SilkS")
		)
		(fp_rect
			(start -0.508 0.9398)
			(end 0.508 -0.9398)
			(stroke
				(width 0)
				(type default)
			)
			(fill no)
			(layer "F.CrtYd")
		)
		(fp_rect
			(start -0.508 0.9398)
			(end 0.508 -0.9398)
			(stroke
				(width 0)
				(type default)
			)
			(fill no)
			(layer "F.Fab")
		)
		(pad "1" smd custom
			(at 0 -0.4445)
			(size 0.1397 0.1397)
			(layers "F.Cu" "F.Mask" "F.Paste")
			(net "P12VL_2490_VCC")
			(options
				(clearance outline)
				(anchor circle)
			)
			(primitives
				(gr_poly
					(pts
						(arc
							(start -0.1778 -0.2794)
							(mid -0.249642 -0.249642)
							(end -0.2794 -0.1778)
						)
						(arc
							(start -0.2794 0.1778)
							(mid -0.249642 0.249642)
							(end -0.1778 0.2794)
						)
						(arc
							(start 0.1778 0.2794)
							(mid 0.249642 0.249642)
							(end 0.2794 0.1778)
						)
						(arc
							(start 0.2794 -0.1778)
							(mid 0.249642 -0.249642)
							(end 0.1778 -0.2794)
						)
					)
					(width 0)
					(fill yes)
				)
			)
		)
		(pad "2" smd custom
			(at 0 0.4445)
			(size 0.1397 0.1397)
			(layers "F.Cu" "F.Mask" "F.Paste")
			(net "P12V")
			(options
				(clearance outline)
				(anchor circle)
			)
			(primitives
				(gr_poly
					(pts
						(arc
							(start -0.1778 -0.2794)
							(mid -0.249642 -0.249642)
							(end -0.2794 -0.1778)
						)
						(arc
							(start -0.2794 0.1778)
							(mid -0.249642 0.249642)
							(end -0.1778 0.2794)
						)
						(arc
							(start 0.1778 0.2794)
							(mid 0.249642 0.249642)
							(end 0.2794 0.1778)
						)
						(arc
							(start 0.2794 -0.1778)
							(mid 0.249642 -0.249642)
							(end 0.1778 -0.2794)
						)
					)
					(width 0)
					(fill yes)
				)
			)
		)
	)
	(footprint ""
		(layer "F.Cu")
		(at 19.939 -18.161 90)
		(property "Reference" "R71"
			(at 0 0 90)
			(layer "F.SilkS")
			(hide yes)
			(effects
				(font
					(size 1.27 1.27)
				)
			)
		)
		(property "Value" "27KR3F-GP"
			(at -0.0254 -2.5146 90)
			(unlocked yes)
			(layer "F.Fab")
			(hide yes)
			(effects
				(font
					(size 1.016 1.016)
					(thickness 0.1524)
				)
			)
		)
		(property "Device Type" "R603H22"
			(at -0.0254 -4.0386 90)
			(unlocked yes)
			(layer "F.Fab")
			(hide yes)
			(effects
				(font
					(size 1.016 1.016)
					(thickness 0.1524)
				)
			)
		)
		(duplicate_pad_numbers_are_jumpers no)
		(fp_line
			(start 0.2032 0)
			(end 0.4826 0)
			(stroke
				(width 0.2032)
				(type default)
			)
			(layer "F.SilkS")
		)
		(fp_line
			(start -0.4826 0)
			(end -0.2032 0)
			(stroke
				(width 0.2032)
				(type default)
			)
			(layer "F.SilkS")
		)
		(fp_rect
			(start -0.5842 1.3335)
			(end 0.5842 -1.3335)
			(stroke
				(width 0)
				(type default)
			)
			(fill no)
			(layer "F.CrtYd")
		)
		(fp_rect
			(start -0.5842 1.3335)
			(end 0.5842 -1.3335)
			(stroke
				(width 0)
				(type default)
			)
			(fill no)
			(layer "F.Fab")
		)
		(pad "1" smd custom
			(at 0 -0.762 90)
			(size 0.2159 0.2159)
			(layers "F.Cu" "F.Mask" "F.Paste")
			(net "FAN_TACH12")
			(options
				(clearance outline)
				(anchor circle)
			)
			(primitives
				(gr_poly
					(pts
						(arc
							(start -0.3302 -0.4318)
							(mid -0.402042 -0.402042)
							(end -0.4318 -0.3302)
						)
						(arc
							(start -0.4318 0.3302)
							(mid -0.402042 0.402042)
							(end -0.3302 0.4318)
						)
						(arc
							(start 0.3302 0.4318)
							(mid 0.402042 0.402042)
							(end 0.4318 0.3302)
						)
						(arc
							(start 0.4318 -0.3302)
							(mid 0.402042 -0.402042)
							(end 0.3302 -0.4318)
						)
					)
					(width 0)
					(fill yes)
				)
			)
		)
		(pad "2" smd custom
			(at 0 0.762 90)
			(size 0.2159 0.2159)
			(layers "F.Cu" "F.Mask" "F.Paste")
			(net "FANIN_12")
			(options
				(clearance outline)
				(anchor circle)
			)
			(primitives
				(gr_poly
					(pts
						(arc
							(start -0.3302 -0.4318)
							(mid -0.402042 -0.402042)
							(end -0.4318 -0.3302)
						)
						(arc
							(start -0.4318 0.3302)
							(mid -0.402042 0.402042)
							(end -0.3302 0.4318)
						)
						(arc
							(start 0.3302 0.4318)
							(mid 0.402042 0.402042)
							(end 0.4318 0.3302)
						)
						(arc
							(start 0.4318 -0.3302)
							(mid 0.402042 -0.402042)
							(end 0.3302 -0.4318)
						)
					)
					(width 0)
					(fill yes)
				)
			)
		)
	)
	(footprint ""
		(layer "F.Cu")
		(at 15.5956 -171.4754)
		(property "Reference" "R52"
			(at 0 0 0)
			(layer "F.SilkS")
			(hide yes)
			(effects
				(font
					(size 1.27 1.27)
				)
			)
		)
		(property "Value" "4K7R2F-GP"
			(at 0.064008 -3.993896 0)
			(unlocked yes)
			(layer "F.Fab")
			(hide yes)
			(effects
				(font
					(size 1.016 1.016)
					(thickness 0.1524)
				)
			)
		)
		(property "Device Type" "R402H16"
			(at 0.064008 -5.517896 0)
			(unlocked yes)
			(layer "F.Fab")
			(hide yes)
			(effects
				(font
					(size 1.016 1.016)
					(thickness 0.1524)
				)
			)
		)
		(duplicate_pad_numbers_are_jumpers no)
		(fp_line
			(start -0.508 -0.9398)
			(end -0.508 0.9398)
			(stroke
				(width 0.1524)
				(type default)
			)
			(layer "F.SilkS")
		)
		(fp_line
			(start 0.508 -0.9398)
			(end -0.508 -0.9398)
			(stroke
				(width 0.1524)
				(type default)
			)
			(layer "F.SilkS")
		)
		(fp_rect
			(start -0.508 0.9398)
			(end 0.508 -0.9398)
			(stroke
				(width 0)
				(type default)
			)
			(fill no)
			(layer "F.CrtYd")
		)
		(fp_rect
			(start -0.508 0.9398)
			(end 0.508 -0.9398)
			(stroke
				(width 0)
				(type default)
			)
			(fill no)
			(layer "F.Fab")
		)
		(pad "1" smd custom
			(at 0 -0.4445)
			(size 0.1397 0.1397)
			(layers "F.Cu" "F.Mask" "F.Paste")
			(net "P3V3")
			(options
				(clearance outline)
				(anchor circle)
			)
			(primitives
				(gr_poly
					(pts
						(arc
							(start -0.1778 -0.2794)
							(mid -0.249642 -0.249642)
							(end -0.2794 -0.1778)
						)
						(arc
							(start -0.2794 0.1778)
							(mid -0.249642 0.249642)
							(end -0.1778 0.2794)
						)
						(arc
							(start 0.1778 0.2794)
							(mid 0.249642 0.249642)
							(end 0.2794 0.1778)
						)
						(arc
							(start 0.2794 -0.1778)
							(mid 0.249642 -0.249642)
							(end 0.1778 -0.2794)
						)
					)
					(width 0)
					(fill yes)
				)
			)
		)
		(pad "2" smd custom
			(at 0 0.4445)
			(size 0.1397 0.1397)
			(layers "F.Cu" "F.Mask" "F.Paste")
			(net "SEB_PEER_2A_2B_HB_OUT")
			(options
				(clearance outline)
				(anchor circle)
			)
			(primitives
				(gr_poly
					(pts
						(arc
							(start -0.1778 -0.2794)
							(mid -0.249642 -0.249642)
							(end -0.2794 -0.1778)
						)
						(arc
							(start -0.2794 0.1778)
							(mid -0.249642 0.249642)
							(end -0.1778 0.2794)
						)
						(arc
							(start 0.1778 0.2794)
							(mid 0.249642 0.249642)
							(end 0.2794 0.1778)
						)
						(arc
							(start 0.2794 -0.1778)
							(mid 0.249642 -0.249642)
							(end 0.1778 -0.2794)
						)
					)
					(width 0)
					(fill yes)
				)
			)
		)
	)
	(footprint ""
		(layer "F.Cu")
		(at 23.1902 -145.161 180)
		(property "Reference" "PR112"
			(at 0 0 180)
			(layer "F.SilkS")
			(hide yes)
			(effects
				(font
					(size 1.27 1.27)
				)
			)
		)
		(property "Value" "6K81R2F-1-GP"
			(at 0.064008 -3.993896 180)
			(unlocked yes)
			(layer "F.Fab")
			(hide yes)
			(effects
				(font
					(size 1.016 1.016)
					(thickness 0.1524)
				)
			)
		)
		(property "Device Type" "R402H16"
			(at 0.064008 -5.517896 180)
			(unlocked yes)
			(layer "F.Fab")
			(hide yes)
			(effects
				(font
					(size 1.016 1.016)
					(thickness 0.1524)
				)
			)
		)
		(duplicate_pad_numbers_are_jumpers no)
		(fp_line
			(start 0.508 -0.9398)
			(end -0.508 -0.9398)
			(stroke
				(width 0.1524)
				(type default)
			)
			(layer "F.SilkS")
		)
		(fp_line
			(start -0.508 -0.9398)
			(end -0.508 0.9398)
			(stroke
				(width 0.1524)
				(type default)
			)
			(layer "F.SilkS")
		)
		(fp_rect
			(start -0.508 0.9398)
			(end 0.508 -0.9398)
			(stroke
				(width 0)
				(type default)
			)
			(fill no)
			(layer "F.CrtYd")
		)
		(fp_rect
			(start -0.508 0.9398)
			(end 0.508 -0.9398)
			(stroke
				(width 0)
				(type default)
			)
			(fill no)
			(layer "F.Fab")
		)
		(pad "1" smd custom
			(at 0 -0.4445 180)
			(size 0.1397 0.1397)
			(layers "F.Cu" "F.Mask" "F.Paste")
			(net "P12VU_2490_EN_2")
			(options
				(clearance outline)
				(anchor circle)
			)
			(primitives
				(gr_poly
					(pts
						(arc
							(start -0.1778 -0.2794)
							(mid -0.249642 -0.249642)
							(end -0.2794 -0.1778)
						)
						(arc
							(start -0.2794 0.1778)
							(mid -0.249642 0.249642)
							(end -0.1778 0.2794)
						)
						(arc
							(start 0.1778 0.2794)
							(mid 0.249642 0.249642)
							(end 0.2794 0.1778)
						)
						(arc
							(start 0.2794 -0.1778)
							(mid 0.249642 -0.249642)
							(end 0.1778 -0.2794)
						)
					)
					(width 0)
					(fill yes)
				)
			)
		)
		(pad "2" smd custom
			(at 0 0.4445 180)
			(size 0.1397 0.1397)
			(layers "F.Cu" "F.Mask" "F.Paste")
			(net "GND")
			(options
				(clearance outline)
				(anchor circle)
			)
			(primitives
				(gr_poly
					(pts
						(arc
							(start -0.1778 -0.2794)
							(mid -0.249642 -0.249642)
							(end -0.2794 -0.1778)
						)
						(arc
							(start -0.2794 0.1778)
							(mid -0.249642 0.249642)
							(end -0.1778 0.2794)
						)
						(arc
							(start 0.1778 0.2794)
							(mid 0.249642 0.249642)
							(end 0.2794 0.1778)
						)
						(arc
							(start 0.2794 -0.1778)
							(mid 0.249642 -0.249642)
							(end 0.1778 -0.2794)
						)
					)
					(width 0)
					(fill yes)
				)
			)
		)
	)
	(footprint ""
		(layer "F.Cu")
		(at 40.2844 -366.319816)
		(property "Reference" "D18"
			(at 0 0 0)
			(layer "F.SilkS")
			(hide yes)
			(effects
				(font
					(size 1.27 1.27)
				)
			)
		)
		(property "Value" "CH751H-40PT-1GP"
			(at -0.1016 -4.4958 0)
			(unlocked yes)
			(layer "F.Fab")
			(hide yes)
			(effects
				(font
					(size 1.016 1.016)
					(thickness 0.1524)
				)
			)
		)
		(property "Device Type" "SOD80CAKH36"
			(at -0.1016 -6.0198 0)
			(unlocked yes)
			(layer "F.Fab")
			(hide yes)
			(effects
				(font
					(size 1.016 1.016)
					(thickness 0.1524)
				)
			)
		)
		(duplicate_pad_numbers_are_jumpers no)
		(fp_line
			(start -0.8128 -1.8796)
			(end -0.8128 1.8796)
			(stroke
				(width 0.1524)
				(type default)
			)
			(layer "F.SilkS")
		)
		(fp_line
			(start -0.8128 1.8796)
			(end 0.8128 1.8796)
			(stroke
				(width 0.1524)
				(type default)
			)
			(layer "F.SilkS")
		)
		(fp_line
			(start -0.6858 2.0066)
			(end 0.6858 2.0066)
			(stroke
				(width 0.4064)
				(type default)
			)
			(layer "F.SilkS")
		)
		(fp_line
			(start 0.8128 -1.8796)
			(end -0.8128 -1.8796)
			(stroke
				(width 0.1524)
				(type default)
			)
			(layer "F.SilkS")
		)
		(fp_line
			(start 0.8128 1.8796)
			(end 0.8128 -1.8796)
			(stroke
				(width 0.1524)
				(type default)
			)
			(layer "F.SilkS")
		)
		(fp_rect
			(start -0.889 2.2098)
			(end 0.889 -1.9558)
			(stroke
				(width 0)
				(type default)
			)
			(fill no)
			(layer "F.CrtYd")
		)
		(fp_rect
			(start -0.889 2.2098)
			(end 0.889 -1.9558)
			(stroke
				(width 0)
				(type default)
			)
			(fill no)
			(layer "F.Fab")
		)
		(pad "A" smd rect
			(at 0 -1.0668)
			(size 0.762 1.1684)
			(layers "F.Cu" "F.Mask" "F.Paste")
			(net "TEMP_ALM#_REVERSE")
		)
		(pad "K" smd rect
			(at 0 1.0668)
			(size 0.762 1.1684)
			(layers "F.Cu" "F.Mask" "F.Paste")
			(net "TEMP_ALM#_REVERSE_R")
		)
	)
	(footprint ""
		(layer "F.Cu")
		(at 13.1318 -150.622 90)
		(property "Reference" "D2"
			(at 0 0 90)
			(layer "F.SilkS")
			(hide yes)
			(effects
				(font
					(size 1.27 1.27)
				)
			)
		)
		(property "Value" "BAS16H-GP"
			(at 0 -5.5372 90)
			(unlocked yes)
			(layer "F.Fab")
			(hide yes)
			(effects
				(font
					(size 1.016 1.016)
					(thickness 0.1524)
				)
			)
		)
		(property "Device Type" "SOD123AKH48"
			(at 0 -7.0612 90)
			(unlocked yes)
			(layer "F.Fab")
			(hide yes)
			(effects
				(font
					(size 1.016 1.016)
					(thickness 0.1524)
				)
			)
		)
		(duplicate_pad_numbers_are_jumpers no)
		(fp_line
			(start 1.016 -2.667)
			(end -1.016 -2.667)
			(stroke
				(width 0.1524)
				(type default)
			)
			(layer "F.SilkS")
		)
		(fp_line
			(start -1.016 -2.667)
			(end -1.016 2.667)
			(stroke
				(width 0.1524)
				(type default)
			)
			(layer "F.SilkS")
		)
		(fp_line
			(start 1.016 2.667)
			(end 1.016 -2.667)
			(stroke
				(width 0.1524)
				(type default)
			)
			(layer "F.SilkS")
		)
		(fp_line
			(start -1.016 2.667)
			(end 1.016 2.667)
			(stroke
				(width 0.1524)
				(type default)
			)
			(layer "F.SilkS")
		)
		(fp_line
			(start 0.889 2.921)
			(end -0.889 2.921)
			(stroke
				(width 0.508)
				(type default)
			)
			(layer "F.SilkS")
		)
		(fp_rect
			(start -1.143 3.175)
			(end 1.143 -2.794)
			(stroke
				(width 0)
				(type default)
			)
			(fill no)
			(layer "F.CrtYd")
		)
		(fp_poly
			(pts
				(xy -1.143 -2.794) (xy 1.143 -2.794) (xy 1.143 3.175) (xy -1.143 3.175)
			)
			(stroke
				(width 0)
				(type default)
			)
			(fill no)
			(layer "F.Fab")
		)
		(pad "A" smd rect
			(at 0 -1.6891 90)
			(size 0.889 1.397)
			(layers "F.Cu" "F.Mask" "F.Paste")
			(net "FAN_TACH10")
		)
		(pad "K" smd rect
			(at 0 1.6891 90)
			(size 0.889 1.397)
			(layers "F.Cu" "F.Mask" "F.Paste")
			(net "P12V")
		)
	)
	(footprint ""
		(layer "F.Cu")
		(at 29.7942 -167.6908 -90)
		(property "Reference" "R165"
			(at 0 0 270)
			(layer "F.SilkS")
			(hide yes)
			(effects
				(font
					(size 1.27 1.27)
				)
			)
		)
		(property "Value" "0R2J-2-GP"
			(at 0.064008 -3.993896 270)
			(unlocked yes)
			(layer "F.Fab")
			(hide yes)
			(effects
				(font
					(size 1.016 1.016)
					(thickness 0.1524)
				)
			)
		)
		(property "Device Type" "R402H16"
			(at 0.064008 -5.517896 270)
			(unlocked yes)
			(layer "F.Fab")
			(hide yes)
			(effects
				(font
					(size 1.016 1.016)
					(thickness 0.1524)
				)
			)
		)
		(duplicate_pad_numbers_are_jumpers no)
		(fp_line
			(start -0.508 -0.9398)
			(end -0.508 0.9398)
			(stroke
				(width 0.1524)
				(type default)
			)
			(layer "F.SilkS")
		)
		(fp_line
			(start 0.508 -0.9398)
			(end -0.508 -0.9398)
			(stroke
				(width 0.1524)
				(type default)
			)
			(layer "F.SilkS")
		)
		(fp_rect
			(start -0.508 0.9398)
			(end 0.508 -0.9398)
			(stroke
				(width 0)
				(type default)
			)
			(fill no)
			(layer "F.CrtYd")
		)
		(fp_rect
			(start -0.508 0.9398)
			(end 0.508 -0.9398)
			(stroke
				(width 0)
				(type default)
			)
			(fill no)
			(layer "F.Fab")
		)
		(pad "1" smd custom
			(at 0 -0.4445 270)
			(size 0.1397 0.1397)
			(layers "F.Cu" "F.Mask" "F.Paste")
			(net "PWM_BUFFER_IN_FAN1_FAN2")
			(options
				(clearance outline)
				(anchor circle)
			)
			(primitives
				(gr_poly
					(pts
						(arc
							(start -0.1778 -0.2794)
							(mid -0.249642 -0.249642)
							(end -0.2794 -0.1778)
						)
						(arc
							(start -0.2794 0.1778)
							(mid -0.249642 0.249642)
							(end -0.1778 0.2794)
						)
						(arc
							(start 0.1778 0.2794)
							(mid 0.249642 0.249642)
							(end 0.2794 0.1778)
						)
						(arc
							(start 0.2794 -0.1778)
							(mid 0.249642 -0.249642)
							(end 0.1778 -0.2794)
						)
					)
					(width 0)
					(fill yes)
				)
			)
		)
		(pad "2" smd custom
			(at 0 0.4445 270)
			(size 0.1397 0.1397)
			(layers "F.Cu" "F.Mask" "F.Paste")
			(net "PWM_BUFFER_IN_FAN3_FAN4")
			(options
				(clearance outline)
				(anchor circle)
			)
			(primitives
				(gr_poly
					(pts
						(arc
							(start -0.1778 -0.2794)
							(mid -0.249642 -0.249642)
							(end -0.2794 -0.1778)
						)
						(arc
							(start -0.2794 0.1778)
							(mid -0.249642 0.249642)
							(end -0.1778 0.2794)
						)
						(arc
							(start 0.1778 0.2794)
							(mid 0.249642 0.249642)
							(end 0.2794 0.1778)
						)
						(arc
							(start 0.2794 -0.1778)
							(mid 0.249642 -0.249642)
							(end 0.1778 -0.2794)
						)
					)
					(width 0)
					(fill yes)
				)
			)
		)
	)
	(footprint ""
		(layer "F.Cu")
		(at 30.3784 -111.125 90)
		(property "Reference" "PR102"
			(at 0 0 90)
			(layer "F.SilkS")
			(hide yes)
			(effects
				(font
					(size 1.27 1.27)
				)
			)
		)
		(property "Value" "10R2F-L-GP"
			(at 0.064008 -3.993896 90)
			(unlocked yes)
			(layer "F.Fab")
			(hide yes)
			(effects
				(font
					(size 1.016 1.016)
					(thickness 0.1524)
				)
			)
		)
		(property "Device Type" "R402H14"
			(at 0.064008 -5.517896 90)
			(unlocked yes)
			(layer "F.Fab")
			(hide yes)
			(effects
				(font
					(size 1.016 1.016)
					(thickness 0.1524)
				)
			)
		)
		(duplicate_pad_numbers_are_jumpers no)
		(fp_line
			(start 0.508 -0.9398)
			(end -0.508 -0.9398)
			(stroke
				(width 0.1524)
				(type default)
			)
			(layer "F.SilkS")
		)
		(fp_line
			(start -0.508 -0.9398)
			(end -0.508 0.9398)
			(stroke
				(width 0.1524)
				(type default)
			)
			(layer "F.SilkS")
		)
		(fp_rect
			(start -0.508 0.9398)
			(end 0.508 -0.9398)
			(stroke
				(width 0)
				(type default)
			)
			(fill no)
			(layer "F.CrtYd")
		)
		(fp_rect
			(start -0.508 0.9398)
			(end 0.508 -0.9398)
			(stroke
				(width 0)
				(type default)
			)
			(fill no)
			(layer "F.Fab")
		)
		(pad "1" smd custom
			(at 0 -0.4445 90)
			(size 0.1397 0.1397)
			(layers "F.Cu" "F.Mask" "F.Paste")
			(net "P12VU_2490_GATE_DRV")
			(options
				(clearance outline)
				(anchor circle)
			)
			(primitives
				(gr_poly
					(pts
						(arc
							(start -0.1778 -0.2794)
							(mid -0.249642 -0.249642)
							(end -0.2794 -0.1778)
						)
						(arc
							(start -0.2794 0.1778)
							(mid -0.249642 0.249642)
							(end -0.1778 0.2794)
						)
						(arc
							(start 0.1778 0.2794)
							(mid 0.249642 0.249642)
							(end 0.2794 0.1778)
						)
						(arc
							(start 0.2794 -0.1778)
							(mid 0.249642 -0.249642)
							(end 0.1778 -0.2794)
						)
					)
					(width 0)
					(fill yes)
				)
			)
		)
		(pad "2" smd custom
			(at 0 0.4445 90)
			(size 0.1397 0.1397)
			(layers "F.Cu" "F.Mask" "F.Paste")
			(net "P12VU_2490_GATE")
			(options
				(clearance outline)
				(anchor circle)
			)
			(primitives
				(gr_poly
					(pts
						(arc
							(start -0.1778 -0.2794)
							(mid -0.249642 -0.249642)
							(end -0.2794 -0.1778)
						)
						(arc
							(start -0.2794 0.1778)
							(mid -0.249642 0.249642)
							(end -0.1778 0.2794)
						)
						(arc
							(start 0.1778 0.2794)
							(mid 0.249642 0.249642)
							(end 0.2794 0.1778)
						)
						(arc
							(start 0.2794 -0.1778)
							(mid 0.249642 -0.249642)
							(end 0.1778 -0.2794)
						)
					)
					(width 0)
					(fill yes)
				)
			)
		)
	)
	(footprint ""
		(layer "F.Cu")
		(at 13.7922 -66.4464 180)
		(property "Reference" "R151"
			(at 0 0 180)
			(layer "F.SilkS")
			(hide yes)
			(effects
				(font
					(size 1.27 1.27)
				)
			)
		)
		(property "Value" "10R2F-L-GP"
			(at 0.064008 -3.993896 180)
			(unlocked yes)
			(layer "F.Fab")
			(hide yes)
			(effects
				(font
					(size 1.016 1.016)
					(thickness 0.1524)
				)
			)
		)
		(property "Device Type" "R402H14"
			(at 0.064008 -5.517896 180)
			(unlocked yes)
			(layer "F.Fab")
			(hide yes)
			(effects
				(font
					(size 1.016 1.016)
					(thickness 0.1524)
				)
			)
		)
		(duplicate_pad_numbers_are_jumpers no)
		(fp_line
			(start 0.508 -0.9398)
			(end -0.508 -0.9398)
			(stroke
				(width 0.1524)
				(type default)
			)
			(layer "F.SilkS")
		)
		(fp_line
			(start -0.508 -0.9398)
			(end -0.508 0.9398)
			(stroke
				(width 0.1524)
				(type default)
			)
			(layer "F.SilkS")
		)
		(fp_rect
			(start -0.508 0.9398)
			(end 0.508 -0.9398)
			(stroke
				(width 0)
				(type default)
			)
			(fill no)
			(layer "F.CrtYd")
		)
		(fp_rect
			(start -0.508 0.9398)
			(end 0.508 -0.9398)
			(stroke
				(width 0)
				(type default)
			)
			(fill no)
			(layer "F.Fab")
		)
		(pad "1" smd custom
			(at 0 -0.4445 180)
			(size 0.1397 0.1397)
			(layers "F.Cu" "F.Mask" "F.Paste")
			(net "I2C_C_SCL_CONN_R")
			(options
				(clearance outline)
				(anchor circle)
			)
			(primitives
				(gr_poly
					(pts
						(arc
							(start -0.1778 -0.2794)
							(mid -0.249642 -0.249642)
							(end -0.2794 -0.1778)
						)
						(arc
							(start -0.2794 0.1778)
							(mid -0.249642 0.249642)
							(end -0.1778 0.2794)
						)
						(arc
							(start 0.1778 0.2794)
							(mid 0.249642 0.249642)
							(end 0.2794 0.1778)
						)
						(arc
							(start 0.2794 -0.1778)
							(mid 0.249642 -0.249642)
							(end 0.1778 -0.2794)
						)
					)
					(width 0)
					(fill yes)
				)
			)
		)
		(pad "2" smd custom
			(at 0 0.4445 180)
			(size 0.1397 0.1397)
			(layers "F.Cu" "F.Mask" "F.Paste")
			(net "I2C_C_SCL")
			(options
				(clearance outline)
				(anchor circle)
			)
			(primitives
				(gr_poly
					(pts
						(arc
							(start -0.1778 -0.2794)
							(mid -0.249642 -0.249642)
							(end -0.2794 -0.1778)
						)
						(arc
							(start -0.2794 0.1778)
							(mid -0.249642 0.249642)
							(end -0.1778 0.2794)
						)
						(arc
							(start 0.1778 0.2794)
							(mid 0.249642 0.249642)
							(end 0.2794 0.1778)
						)
						(arc
							(start 0.2794 -0.1778)
							(mid 0.249642 -0.249642)
							(end 0.1778 -0.2794)
						)
					)
					(width 0)
					(fill yes)
				)
			)
		)
	)
	(footprint ""
		(layer "F.Cu")
		(at 45.500036 -294.999918)
		(property "Reference" "H6"
			(at 0 0 0)
			(layer "F.SilkS")
			(hide yes)
			(effects
				(font
					(size 1.27 1.27)
				)
			)
		)
		(property "Value" "HOLE315R138"
			(at 0 -7.0612 0)
			(unlocked yes)
			(layer "F.Fab")
			(hide yes)
			(effects
				(font
					(size 1.016 1.016)
					(thickness 0.1524)
				)
			)
		)
		(property "Device Type" "HOLE315R138"
			(at 0 -8.5852 0)
			(unlocked yes)
			(layer "F.Fab")
			(hide yes)
			(effects
				(font
					(size 1.016 1.016)
					(thickness 0.1524)
				)
			)
		)
		(duplicate_pad_numbers_are_jumpers no)
		(fp_poly
			(pts
				(xy 0 4.3053) (xy -0.13462 4.30276) (xy -0.27051 4.29641) (xy -0.40513 4.28625) (xy -0.53975 4.27101)
				(xy -0.6731 4.25196) (xy -0.80645 4.2291) (xy -0.9398 4.20116) (xy -1.07061 4.17068) (xy -1.20142 4.13385)
				(xy -1.33096 4.09448) (xy -1.45796 4.0513) (xy -1.58496 4.00304) (xy -1.70942 3.95097) (xy -1.83261 3.89509)
				(xy -1.95453 3.83667) (xy -2.07391 3.77317) (xy -2.19202 3.70586) (xy -2.30632 3.63474) (xy -2.41935 3.56108)
				(xy -2.53111 3.48361) (xy -2.63906 3.40233) (xy -2.74447 3.31724) (xy -2.84734 3.22961) (xy -2.94767 3.13817)
				(xy -3.04419 3.04419) (xy -3.13817 2.94767) (xy -3.22961 2.84734) (xy -3.31724 2.74447) (xy -3.40233 2.63906)
				(xy -3.48361 2.53111) (xy -3.56108 2.41935) (xy -3.63474 2.30632) (xy -3.70586 2.19202) (xy -3.77317 2.07391)
				(xy -3.83667 1.95453) (xy -3.89509 1.83261) (xy -3.95097 1.70942) (xy -4.00304 1.58496) (xy -4.0513 1.45796)
				(xy -4.09448 1.33096) (xy -4.13385 1.20142) (xy -4.17068 1.07061) (xy -4.20116 0.9398) (xy -4.2291 0.80645)
				(xy -4.25196 0.6731) (xy -4.27101 0.53975) (xy -4.28625 0.40513) (xy -4.29641 0.27051) (xy -4.30276 0.13462)
				(xy -4.3053 0) (xy -4.30276 -0.13462) (xy -4.29641 -0.27051) (xy -4.28625 -0.40513) (xy -4.27101 -0.53975)
				(xy -4.25196 -0.6731) (xy -4.2291 -0.80645) (xy -4.20116 -0.9398) (xy -4.17068 -1.07061) (xy -4.13385 -1.20142)
				(xy -4.09448 -1.33096) (xy -4.0513 -1.45796) (xy -4.00304 -1.58496) (xy -3.95097 -1.70942) (xy -3.89509 -1.83261)
				(xy -3.83667 -1.95453) (xy -3.77317 -2.07391) (xy -3.70586 -2.19202) (xy -3.63474 -2.30632) (xy -3.56108 -2.41935)
				(xy -3.48361 -2.53111) (xy -3.40233 -2.63906) (xy -3.31724 -2.74447) (xy -3.22961 -2.84734) (xy -3.13817 -2.94767)
				(xy -3.04419 -3.04419) (xy -2.94767 -3.13817) (xy -2.84734 -3.22961) (xy -2.74447 -3.31724) (xy -2.63906 -3.40233)
				(xy -2.53111 -3.48361) (xy -2.41935 -3.56108) (xy -2.30632 -3.63474) (xy -2.19202 -3.70586) (xy -2.07391 -3.77317)
				(xy -1.95453 -3.83667) (xy -1.83261 -3.89509) (xy -1.70942 -3.95097) (xy -1.58496 -4.00304) (xy -1.45796 -4.0513)
				(xy -1.33096 -4.09448) (xy -1.20142 -4.13385) (xy -1.07061 -4.17068) (xy -0.9398 -4.20116) (xy -0.80645 -4.2291)
				(xy -0.6731 -4.25196) (xy -0.53975 -4.27101) (xy -0.40513 -4.28625) (xy -0.27051 -4.29641) (xy -0.13462 -4.30276)
				(xy 0 -4.3053) (xy 0.13462 -4.30276) (xy 0.27051 -4.29641) (xy 0.40513 -4.28625) (xy 0.53975 -4.27101)
				(xy 0.6731 -4.25196) (xy 0.80645 -4.2291) (xy 0.9398 -4.20116) (xy 1.07061 -4.17068) (xy 1.20142 -4.13385)
				(xy 1.33096 -4.09448) (xy 1.45796 -4.0513) (xy 1.58496 -4.00304) (xy 1.70942 -3.95097) (xy 1.83261 -3.89509)
				(xy 1.95453 -3.83667) (xy 2.07391 -3.77317) (xy 2.19202 -3.70586) (xy 2.30632 -3.63474) (xy 2.41935 -3.56108)
				(xy 2.53111 -3.48361) (xy 2.63906 -3.40233) (xy 2.74447 -3.31724) (xy 2.84734 -3.22961) (xy 2.94767 -3.13817)
				(xy 3.04419 -3.04419) (xy 3.13817 -2.94767) (xy 3.22961 -2.84734) (xy 3.31724 -2.74447) (xy 3.40233 -2.63906)
				(xy 3.48361 -2.53111) (xy 3.56108 -2.41935) (xy 3.63474 -2.30632) (xy 3.70586 -2.19202) (xy 3.77317 -2.07391)
				(xy 3.83667 -1.95453) (xy 3.89509 -1.83261) (xy 3.95097 -1.70942) (xy 4.00304 -1.58496) (xy 4.0513 -1.45796)
				(xy 4.09448 -1.33096) (xy 4.13385 -1.20142) (xy 4.17068 -1.07061) (xy 4.20116 -0.9398) (xy 4.2291 -0.80645)
				(xy 4.25196 -0.6731) (xy 4.27101 -0.53975) (xy 4.28625 -0.40513) (xy 4.29641 -0.27051) (xy 4.30276 -0.13462)
				(xy 4.3053 0) (xy 4.30276 0.13462) (xy 4.29641 0.27051) (xy 4.28625 0.40513) (xy 4.27101 0.53975)
				(xy 4.25196 0.6731) (xy 4.2291 0.80645) (xy 4.20116 0.9398) (xy 4.17068 1.07061) (xy 4.13385 1.20142)
				(xy 4.09448 1.33096) (xy 4.0513 1.45796) (xy 4.00304 1.58496) (xy 3.95097 1.70942) (xy 3.89509 1.83261)
				(xy 3.83667 1.95453) (xy 3.77317 2.07391) (xy 3.70586 2.19202) (xy 3.63474 2.30632) (xy 3.56108 2.41935)
				(xy 3.48361 2.53111) (xy 3.40233 2.63906) (xy 3.31724 2.74447) (xy 3.22961 2.84734) (xy 3.13817 2.94767)
				(xy 3.04419 3.04419) (xy 2.94767 3.13817) (xy 2.84734 3.22961) (xy 2.74447 3.31724) (xy 2.63906 3.40233)
				(xy 2.53111 3.48361) (xy 2.41935 3.56108) (xy 2.30632 3.63474) (xy 2.19202 3.70586) (xy 2.07391 3.77317)
				(xy 1.95453 3.83667) (xy 1.83261 3.89509) (xy 1.70942 3.95097) (xy 1.58496 4.00304) (xy 1.45796 4.0513)
				(xy 1.33096 4.09448) (xy 1.20142 4.13385) (xy 1.07061 4.17068) (xy 0.9398 4.20116) (xy 0.80645 4.2291)
				(xy 0.6731 4.25196) (xy 0.53975 4.27101) (xy 0.40513 4.28625) (xy 0.27051 4.29641) (xy 0.13462 4.30276)
			)
			(stroke
				(width 0)
				(type default)
			)
			(fill no)
			(layer "F.CrtYd")
		)
		(fp_poly
			(pts
				(xy 0 4.3053) (xy -0.13462 4.30276) (xy -0.27051 4.29641) (xy -0.40513 4.28625) (xy -0.53975 4.27101)
				(xy -0.6731 4.25196) (xy -0.80645 4.2291) (xy -0.9398 4.20116) (xy -1.07061 4.17068) (xy -1.20142 4.13385)
				(xy -1.33096 4.09448) (xy -1.45796 4.0513) (xy -1.58496 4.00304) (xy -1.70942 3.95097) (xy -1.83261 3.89509)
				(xy -1.95453 3.83667) (xy -2.07391 3.77317) (xy -2.19202 3.70586) (xy -2.30632 3.63474) (xy -2.41935 3.56108)
				(xy -2.53111 3.48361) (xy -2.63906 3.40233) (xy -2.74447 3.31724) (xy -2.84734 3.22961) (xy -2.94767 3.13817)
				(xy -3.04419 3.04419) (xy -3.13817 2.94767) (xy -3.22961 2.84734) (xy -3.31724 2.74447) (xy -3.40233 2.63906)
				(xy -3.48361 2.53111) (xy -3.56108 2.41935) (xy -3.63474 2.30632) (xy -3.70586 2.19202) (xy -3.77317 2.07391)
				(xy -3.83667 1.95453) (xy -3.89509 1.83261) (xy -3.95097 1.70942) (xy -4.00304 1.58496) (xy -4.0513 1.45796)
				(xy -4.09448 1.33096) (xy -4.13385 1.20142) (xy -4.17068 1.07061) (xy -4.20116 0.9398) (xy -4.2291 0.80645)
				(xy -4.25196 0.6731) (xy -4.27101 0.53975) (xy -4.28625 0.40513) (xy -4.29641 0.27051) (xy -4.30276 0.13462)
				(xy -4.3053 0) (xy -4.30276 -0.13462) (xy -4.29641 -0.27051) (xy -4.28625 -0.40513) (xy -4.27101 -0.53975)
				(xy -4.25196 -0.6731) (xy -4.2291 -0.80645) (xy -4.20116 -0.9398) (xy -4.17068 -1.07061) (xy -4.13385 -1.20142)
				(xy -4.09448 -1.33096) (xy -4.0513 -1.45796) (xy -4.00304 -1.58496) (xy -3.95097 -1.70942) (xy -3.89509 -1.83261)
				(xy -3.83667 -1.95453) (xy -3.77317 -2.07391) (xy -3.70586 -2.19202) (xy -3.63474 -2.30632) (xy -3.56108 -2.41935)
				(xy -3.48361 -2.53111) (xy -3.40233 -2.63906) (xy -3.31724 -2.74447) (xy -3.22961 -2.84734) (xy -3.13817 -2.94767)
				(xy -3.04419 -3.04419) (xy -2.94767 -3.13817) (xy -2.84734 -3.22961) (xy -2.74447 -3.31724) (xy -2.63906 -3.40233)
				(xy -2.53111 -3.48361) (xy -2.41935 -3.56108) (xy -2.30632 -3.63474) (xy -2.19202 -3.70586) (xy -2.07391 -3.77317)
				(xy -1.95453 -3.83667) (xy -1.83261 -3.89509) (xy -1.70942 -3.95097) (xy -1.58496 -4.00304) (xy -1.45796 -4.0513)
				(xy -1.33096 -4.09448) (xy -1.20142 -4.13385) (xy -1.07061 -4.17068) (xy -0.9398 -4.20116) (xy -0.80645 -4.2291)
				(xy -0.6731 -4.25196) (xy -0.53975 -4.27101) (xy -0.40513 -4.28625) (xy -0.27051 -4.29641) (xy -0.13462 -4.30276)
				(xy 0 -4.3053) (xy 0.13462 -4.30276) (xy 0.27051 -4.29641) (xy 0.40513 -4.28625) (xy 0.53975 -4.27101)
				(xy 0.6731 -4.25196) (xy 0.80645 -4.2291) (xy 0.9398 -4.20116) (xy 1.07061 -4.17068) (xy 1.20142 -4.13385)
				(xy 1.33096 -4.09448) (xy 1.45796 -4.0513) (xy 1.58496 -4.00304) (xy 1.70942 -3.95097) (xy 1.83261 -3.89509)
				(xy 1.95453 -3.83667) (xy 2.07391 -3.77317) (xy 2.19202 -3.70586) (xy 2.30632 -3.63474) (xy 2.41935 -3.56108)
				(xy 2.53111 -3.48361) (xy 2.63906 -3.40233) (xy 2.74447 -3.31724) (xy 2.84734 -3.22961) (xy 2.94767 -3.13817)
				(xy 3.04419 -3.04419) (xy 3.13817 -2.94767) (xy 3.22961 -2.84734) (xy 3.31724 -2.74447) (xy 3.40233 -2.63906)
				(xy 3.48361 -2.53111) (xy 3.56108 -2.41935) (xy 3.63474 -2.30632) (xy 3.70586 -2.19202) (xy 3.77317 -2.07391)
				(xy 3.83667 -1.95453) (xy 3.89509 -1.83261) (xy 3.95097 -1.70942) (xy 4.00304 -1.58496) (xy 4.0513 -1.45796)
				(xy 4.09448 -1.33096) (xy 4.13385 -1.20142) (xy 4.17068 -1.07061) (xy 4.20116 -0.9398) (xy 4.2291 -0.80645)
				(xy 4.25196 -0.6731) (xy 4.27101 -0.53975) (xy 4.28625 -0.40513) (xy 4.29641 -0.27051) (xy 4.30276 -0.13462)
				(xy 4.3053 0) (xy 4.30276 0.13462) (xy 4.29641 0.27051) (xy 4.28625 0.40513) (xy 4.27101 0.53975)
				(xy 4.25196 0.6731) (xy 4.2291 0.80645) (xy 4.20116 0.9398) (xy 4.17068 1.07061) (xy 4.13385 1.20142)
				(xy 4.09448 1.33096) (xy 4.0513 1.45796) (xy 4.00304 1.58496) (xy 3.95097 1.70942) (xy 3.89509 1.83261)
				(xy 3.83667 1.95453) (xy 3.77317 2.07391) (xy 3.70586 2.19202) (xy 3.63474 2.30632) (xy 3.56108 2.41935)
				(xy 3.48361 2.53111) (xy 3.40233 2.63906) (xy 3.31724 2.74447) (xy 3.22961 2.84734) (xy 3.13817 2.94767)
				(xy 3.04419 3.04419) (xy 2.94767 3.13817) (xy 2.84734 3.22961) (xy 2.74447 3.31724) (xy 2.63906 3.40233)
				(xy 2.53111 3.48361) (xy 2.41935 3.56108) (xy 2.30632 3.63474) (xy 2.19202 3.70586) (xy 2.07391 3.77317)
				(xy 1.95453 3.83667) (xy 1.83261 3.89509) (xy 1.70942 3.95097) (xy 1.58496 4.00304) (xy 1.45796 4.0513)
				(xy 1.33096 4.09448) (xy 1.20142 4.13385) (xy 1.07061 4.17068) (xy 0.9398 4.20116) (xy 0.80645 4.2291)
				(xy 0.6731 4.25196) (xy 0.53975 4.27101) (xy 0.40513 4.28625) (xy 0.27051 4.29641) (xy 0.13462 4.30276)
			)
			(stroke
				(width 0)
				(type default)
			)
			(fill no)
			(layer "F.Fab")
		)
		(pad "1" thru_hole circle
			(at 0 0)
			(size 8.001 8.001)
			(drill 3.5052)
			(layers "*.Cu" "*.Mask")
			(remove_unused_layers no)
			(net "GND")
			(clearance -1.7399)
			(thermal_gap 0.3048)
			(padstack
				(mode front_inner_back)
				(layer "Inner"
					(shape circle)
					(size 3.9116 3.9116)
					(clearance 0.3048)
				)
				(layer "B.Cu"
					(shape circle)
					(size 8.001 8.001)
					(clearance -1.7399)
				)
			)
		)
	)
	(footprint ""
		(layer "F.Cu")
		(at 18.1356 -17.768316)
		(property "Reference" "C27"
			(at 0 0 0)
			(layer "F.SilkS")
			(hide yes)
			(effects
				(font
					(size 1.27 1.27)
				)
			)
		)
		(property "Value" "SCD1U16V2KX-3GP"
			(at 1.1811 -2.7051 0)
			(unlocked yes)
			(layer "F.Fab")
			(hide yes)
			(effects
				(font
					(size 1.016 1.016)
					(thickness 0.1524)
				)
			)
		)
		(property "Device Type" "C402H22"
			(at 1.1811 -4.2291 0)
			(unlocked yes)
			(layer "F.Fab")
			(hide yes)
			(effects
				(font
					(size 1.016 1.016)
					(thickness 0.1524)
				)
			)
		)
		(duplicate_pad_numbers_are_jumpers no)
		(fp_rect
			(start -0.4318 0.9525)
			(end 0.4318 -0.9525)
			(stroke
				(width 0)
				(type default)
			)
			(fill no)
			(layer "F.CrtYd")
		)
		(fp_rect
			(start -0.4318 0.9525)
			(end 0.4318 -0.9525)
			(stroke
				(width 0)
				(type default)
			)
			(fill no)
			(layer "F.Fab")
		)
		(pad "1" smd custom
			(at 0 -0.4445)
			(size 0.1524 0.1524)
			(layers "F.Cu" "F.Mask" "F.Paste")
			(net "FAN_TACH12")
			(options
				(clearance outline)
				(anchor circle)
			)
			(primitives
				(gr_poly
					(pts
						(arc
							(start 0.3048 -0.2032)
							(mid 0.275042 -0.275042)
							(end 0.2032 -0.3048)
						)
						(arc
							(start -0.2032 -0.3048)
							(mid -0.275042 -0.275042)
							(end -0.3048 -0.2032)
						)
						(arc
							(start -0.3048 0.2032)
							(mid -0.275042 0.275042)
							(end -0.2032 0.3048)
						)
						(arc
							(start 0.2032 0.3048)
							(mid 0.275042 0.275042)
							(end 0.3048 0.2032)
						)
					)
					(width 0)
					(fill yes)
				)
			)
		)
		(pad "2" smd custom
			(at 0 0.4445)
			(size 0.1524 0.1524)
			(layers "F.Cu" "F.Mask" "F.Paste")
			(net "GND")
			(options
				(clearance outline)
				(anchor circle)
			)
			(primitives
				(gr_poly
					(pts
						(arc
							(start 0.3048 -0.2032)
							(mid 0.275042 -0.275042)
							(end 0.2032 -0.3048)
						)
						(arc
							(start -0.2032 -0.3048)
							(mid -0.275042 -0.275042)
							(end -0.3048 -0.2032)
						)
						(arc
							(start -0.3048 0.2032)
							(mid -0.275042 0.275042)
							(end -0.2032 0.3048)
						)
						(arc
							(start 0.2032 0.3048)
							(mid 0.275042 0.275042)
							(end 0.3048 0.2032)
						)
					)
					(width 0)
					(fill yes)
				)
			)
		)
	)
	(footprint ""
		(layer "F.Cu")
		(at 7.8232 -83.439 90)
		(property "Reference" "R123"
			(at 0 0 90)
			(layer "F.SilkS")
			(hide yes)
			(effects
				(font
					(size 1.27 1.27)
				)
			)
		)
		(property "Value" "1K8R6J-GP"
			(at -0.0508 -4.8514 90)
			(unlocked yes)
			(layer "F.Fab")
			(hide yes)
			(effects
				(font
					(size 1.016 1.016)
					(thickness 0.1524)
				)
			)
		)
		(property "Device Type" "R1206H28"
			(at 0 -6.3754 90)
			(unlocked yes)
			(layer "F.Fab")
			(hide yes)
			(effects
				(font
					(size 1.016 1.016)
					(thickness 0.1524)
				)
			)
		)
		(duplicate_pad_numbers_are_jumpers no)
		(fp_line
			(start 1.016 -2.2352)
			(end 1.016 2.2352)
			(stroke
				(width 0.1524)
				(type default)
			)
			(layer "F.SilkS")
		)
		(fp_line
			(start -1.016 -2.2352)
			(end 1.016 -2.2352)
			(stroke
				(width 0.1524)
				(type default)
			)
			(layer "F.SilkS")
		)
		(fp_line
			(start 1.016 2.2352)
			(end -1.016 2.2352)
			(stroke
				(width 0.1524)
				(type default)
			)
			(layer "F.SilkS")
		)
		(fp_line
			(start -1.016 2.2352)
			(end -1.016 -2.2352)
			(stroke
				(width 0.1524)
				(type default)
			)
			(layer "F.SilkS")
		)
		(fp_rect
			(start -1.0922 2.3114)
			(end 1.0922 -2.3114)
			(stroke
				(width 0)
				(type default)
			)
			(fill no)
			(layer "F.CrtYd")
		)
		(fp_poly
			(pts
				(xy -1.0922 -2.3114) (xy 1.0922 -2.3114) (xy 1.0922 2.3114) (xy -1.0922 2.3114)
			)
			(stroke
				(width 0)
				(type default)
			)
			(fill no)
			(layer "F.Fab")
		)
		(pad "1" smd rect
			(at 0 -1.397 90)
			(size 1.651 1.27)
			(layers "F.Cu" "F.Mask" "F.Paste")
			(net "P12V")
		)
		(pad "2" smd rect
			(at 0 1.397 90)
			(size 1.651 1.27)
			(layers "F.Cu" "F.Mask" "F.Paste")
			(net "LED_DR_LED4_BLUE")
		)
	)
	(footprint ""
		(layer "F.Cu")
		(at 37.2618 -121.793)
		(property "Reference" "C257"
			(at 0 0 0)
			(layer "F.SilkS")
			(hide yes)
			(effects
				(font
					(size 1.27 1.27)
				)
			)
		)
		(property "Value" "SC1U25V3KX-1-GP"
			(at 0 -2.8194 0)
			(unlocked yes)
			(layer "F.Fab")
			(hide yes)
			(effects
				(font
					(size 1.016 1.016)
					(thickness 0.1524)
				)
			)
		)
		(property "Device Type" "C603H36"
			(at 0 -4.3434 0)
			(unlocked yes)
			(layer "F.Fab")
			(hide yes)
			(effects
				(font
					(size 1.016 1.016)
					(thickness 0.1524)
				)
			)
		)
		(duplicate_pad_numbers_are_jumpers no)
		(fp_line
			(start 0.508 0)
			(end -0.508 0)
			(stroke
				(width 0.2032)
				(type default)
			)
			(layer "F.SilkS")
		)
		(fp_rect
			(start -0.5842 1.3335)
			(end 0.5842 -1.3335)
			(stroke
				(width 0)
				(type default)
			)
			(fill no)
			(layer "F.CrtYd")
		)
		(fp_rect
			(start -0.5842 1.3335)
			(end 0.5842 -1.3335)
			(stroke
				(width 0)
				(type default)
			)
			(fill no)
			(layer "F.Fab")
		)
		(pad "1" smd custom
			(at 0 -0.762)
			(size 0.2159 0.2159)
			(layers "F.Cu" "F.Mask" "F.Paste")
			(net "P12V")
			(options
				(clearance outline)
				(anchor circle)
			)
			(primitives
				(gr_poly
					(pts
						(arc
							(start -0.3302 -0.4318)
							(mid -0.402042 -0.402042)
							(end -0.4318 -0.3302)
						)
						(arc
							(start -0.4318 0.3302)
							(mid -0.402042 0.402042)
							(end -0.3302 0.4318)
						)
						(arc
							(start 0.3302 0.4318)
							(mid 0.402042 0.402042)
							(end 0.4318 0.3302)
						)
						(arc
							(start 0.4318 -0.3302)
							(mid 0.402042 -0.402042)
							(end 0.3302 -0.4318)
						)
					)
					(width 0)
					(fill yes)
				)
			)
		)
		(pad "2" smd custom
			(at 0 0.762)
			(size 0.2159 0.2159)
			(layers "F.Cu" "F.Mask" "F.Paste")
			(net "GND")
			(options
				(clearance outline)
				(anchor circle)
			)
			(primitives
				(gr_poly
					(pts
						(arc
							(start -0.3302 -0.4318)
							(mid -0.402042 -0.402042)
							(end -0.4318 -0.3302)
						)
						(arc
							(start -0.4318 0.3302)
							(mid -0.402042 0.402042)
							(end -0.3302 0.4318)
						)
						(arc
							(start 0.3302 0.4318)
							(mid 0.402042 0.402042)
							(end 0.4318 0.3302)
						)
						(arc
							(start 0.4318 -0.3302)
							(mid 0.402042 -0.402042)
							(end 0.3302 -0.4318)
						)
					)
					(width 0)
					(fill yes)
				)
			)
		)
	)
	(footprint ""
		(layer "F.Cu")
		(at 37.8968 -139.9794 180)
		(property "Reference" "PU7"
			(at 0 0 180)
			(layer "F.SilkS")
			(hide yes)
			(effects
				(font
					(size 1.27 1.27)
				)
			)
		)
		(property "Value" "TPS2490DGSR-GP"
			(at 0 -11.1252 180)
			(unlocked yes)
			(layer "F.Fab")
			(hide yes)
			(effects
				(font
					(size 1.016 1.016)
					(thickness 0.1524)
				)
			)
		)
		(property "Device Type" "MSOP10H44"
			(at 0 -12.6492 180)
			(unlocked yes)
			(layer "F.Fab")
			(hide yes)
			(effects
				(font
					(size 1.016 1.016)
					(thickness 0.1524)
				)
			)
		)
		(duplicate_pad_numbers_are_jumpers no)
		(fp_line
			(start 1.143 1.016)
			(end -2.0066 1.016)
			(stroke
				(width 0.1524)
				(type default)
			)
			(layer "F.SilkS")
		)
		(fp_line
			(start 1.143 -1.016)
			(end 1.143 1.016)
			(stroke
				(width 0.1524)
				(type default)
			)
			(layer "F.SilkS")
		)
		(fp_line
			(start -1.5748 0)
			(end -1.9558 0.381)
			(stroke
				(width 0.1524)
				(type default)
			)
			(layer "F.SilkS")
		)
		(fp_line
			(start -1.5748 0)
			(end -1.9558 -0.381)
			(stroke
				(width 0.1524)
				(type default)
			)
			(layer "F.SilkS")
		)
		(fp_line
			(start -1.8288 1.016)
			(end -1.8288 3.048)
			(stroke
				(width 0.508)
				(type default)
			)
			(layer "F.SilkS")
		)
		(fp_line
			(start -2.0066 1.016)
			(end -2.0066 -1.016)
			(stroke
				(width 0.1524)
				(type default)
			)
			(layer "F.SilkS")
		)
		(fp_line
			(start -2.0066 -1.016)
			(end 1.143 -1.016)
			(stroke
				(width 0.1524)
				(type default)
			)
			(layer "F.SilkS")
		)
		(fp_poly
			(pts
				(xy -2.0828 3.3401) (xy 2.0828 3.3401) (xy 2.0828 -3.3401) (xy -2.0828 -3.3401)
			)
			(stroke
				(width 0)
				(type default)
			)
			(fill no)
			(layer "F.CrtYd")
		)
		(fp_poly
			(pts
				(xy -2.0828 3.3401) (xy 2.0828 3.3401) (xy 2.0828 -3.3401) (xy -2.0828 -3.3401)
			)
			(stroke
				(width 0)
				(type default)
			)
			(fill no)
			(layer "F.Fab")
		)
		(pad "1" smd rect
			(at -0.99949 2.0701 180)
			(size 0.3048 1.524)
			(layers "F.Cu" "F.Mask" "F.Paste")
			(net "P12VL_2490_EN_2")
		)
		(pad "2" smd rect
			(at -0.50038 2.0701 180)
			(size 0.3048 1.524)
			(layers "F.Cu" "F.Mask" "F.Paste")
			(net "P12VL_2490_VREF")
		)
		(pad "3" smd rect
			(at 0 2.0701 180)
			(size 0.3048 1.524)
			(layers "F.Cu" "F.Mask" "F.Paste")
			(net "P12VL_2490_PROG")
		)
		(pad "4" smd rect
			(at 0.50038 2.0701 180)
			(size 0.3048 1.524)
			(layers "F.Cu" "F.Mask" "F.Paste")
			(net "P12VL_2490_TIMER")
		)
		(pad "5" smd rect
			(at 0.99949 2.0701 180)
			(size 0.3048 1.524)
			(layers "F.Cu" "F.Mask" "F.Paste")
			(net "GND")
		)
		(pad "6" smd rect
			(at 0.99949 -2.0701 180)
			(size 0.3048 1.524)
			(layers "F.Cu" "F.Mask" "F.Paste")
			(net "P12VL_2490_PG")
		)
		(pad "7" smd rect
			(at 0.50038 -2.0701 180)
			(size 0.3048 1.524)
			(layers "F.Cu" "F.Mask" "F.Paste")
			(net "P12VL")
		)
		(pad "8" smd rect
			(at 0 -2.0701 180)
			(size 0.3048 1.524)
			(layers "F.Cu" "F.Mask" "F.Paste")
			(net "P12VL_2490_GATE")
		)
		(pad "9" smd rect
			(at -0.50038 -2.0701 180)
			(size 0.3048 1.524)
			(layers "F.Cu" "F.Mask" "F.Paste")
			(net "P12VL_2490_SENSE")
		)
		(pad "10" smd rect
			(at -0.99949 -2.0701 180)
			(size 0.3048 1.524)
			(layers "F.Cu" "F.Mask" "F.Paste")
			(net "P12VL_2490_VCC")
		)
	)
	(footprint ""
		(layer "F.Cu")
		(at 20.675092 -285.598362 180)
		(property "Reference" "R94"
			(at 0 0 180)
			(layer "F.SilkS")
			(hide yes)
			(effects
				(font
					(size 1.27 1.27)
				)
			)
		)
		(property "Value" "4K7R2F-GP"
			(at 0.064008 -3.993896 180)
			(unlocked yes)
			(layer "F.Fab")
			(hide yes)
			(effects
				(font
					(size 1.016 1.016)
					(thickness 0.1524)
				)
			)
		)
		(property "Device Type" "R402H16"
			(at 0.064008 -5.517896 180)
			(unlocked yes)
			(layer "F.Fab")
			(hide yes)
			(effects
				(font
					(size 1.016 1.016)
					(thickness 0.1524)
				)
			)
		)
		(duplicate_pad_numbers_are_jumpers no)
		(fp_line
			(start 0.508 -0.9398)
			(end -0.508 -0.9398)
			(stroke
				(width 0.1524)
				(type default)
			)
			(layer "F.SilkS")
		)
		(fp_line
			(start -0.508 -0.9398)
			(end -0.508 0.9398)
			(stroke
				(width 0.1524)
				(type default)
			)
			(layer "F.SilkS")
		)
		(fp_rect
			(start -0.508 0.9398)
			(end 0.508 -0.9398)
			(stroke
				(width 0)
				(type default)
			)
			(fill no)
			(layer "F.CrtYd")
		)
		(fp_rect
			(start -0.508 0.9398)
			(end 0.508 -0.9398)
			(stroke
				(width 0)
				(type default)
			)
			(fill no)
			(layer "F.Fab")
		)
		(pad "1" smd custom
			(at 0 -0.4445 180)
			(size 0.1397 0.1397)
			(layers "F.Cu" "F.Mask" "F.Paste")
			(net "P12V")
			(options
				(clearance outline)
				(anchor circle)
			)
			(primitives
				(gr_poly
					(pts
						(arc
							(start -0.1778 -0.2794)
							(mid -0.249642 -0.249642)
							(end -0.2794 -0.1778)
						)
						(arc
							(start -0.2794 0.1778)
							(mid -0.249642 0.249642)
							(end -0.1778 0.2794)
						)
						(arc
							(start 0.1778 0.2794)
							(mid 0.249642 0.249642)
							(end 0.2794 0.1778)
						)
						(arc
							(start 0.2794 -0.1778)
							(mid 0.249642 -0.249642)
							(end 0.1778 -0.2794)
						)
					)
					(width 0)
					(fill yes)
				)
			)
		)
		(pad "2" smd custom
			(at 0 0.4445 180)
			(size 0.1397 0.1397)
			(layers "F.Cu" "F.Mask" "F.Paste")
			(net "FAN_TACH4")
			(options
				(clearance outline)
				(anchor circle)
			)
			(primitives
				(gr_poly
					(pts
						(arc
							(start -0.1778 -0.2794)
							(mid -0.249642 -0.249642)
							(end -0.2794 -0.1778)
						)
						(arc
							(start -0.2794 0.1778)
							(mid -0.249642 0.249642)
							(end -0.1778 0.2794)
						)
						(arc
							(start 0.1778 0.2794)
							(mid 0.249642 0.249642)
							(end 0.2794 0.1778)
						)
						(arc
							(start 0.2794 -0.1778)
							(mid 0.249642 -0.249642)
							(end 0.1778 -0.2794)
						)
					)
					(width 0)
					(fill yes)
				)
			)
		)
	)
	(footprint ""
		(layer "F.Cu")
		(at 32.85109 -167.723566 180)
		(property "Reference" "R7"
			(at 0 0 180)
			(layer "F.SilkS")
			(hide yes)
			(effects
				(font
					(size 1.27 1.27)
				)
			)
		)
		(property "Value" "0R2J-2-GP"
			(at 0.064008 -3.993896 180)
			(unlocked yes)
			(layer "F.Fab")
			(hide yes)
			(effects
				(font
					(size 1.016 1.016)
					(thickness 0.1524)
				)
			)
		)
		(property "Device Type" "R402H16"
			(at 0.064008 -5.517896 180)
			(unlocked yes)
			(layer "F.Fab")
			(hide yes)
			(effects
				(font
					(size 1.016 1.016)
					(thickness 0.1524)
				)
			)
		)
		(duplicate_pad_numbers_are_jumpers no)
		(fp_line
			(start 0.508 -0.9398)
			(end -0.508 -0.9398)
			(stroke
				(width 0.1524)
				(type default)
			)
			(layer "F.SilkS")
		)
		(fp_line
			(start -0.508 -0.9398)
			(end -0.508 0.9398)
			(stroke
				(width 0.1524)
				(type default)
			)
			(layer "F.SilkS")
		)
		(fp_rect
			(start -0.508 0.9398)
			(end 0.508 -0.9398)
			(stroke
				(width 0)
				(type default)
			)
			(fill no)
			(layer "F.CrtYd")
		)
		(fp_rect
			(start -0.508 0.9398)
			(end 0.508 -0.9398)
			(stroke
				(width 0)
				(type default)
			)
			(fill no)
			(layer "F.Fab")
		)
		(pad "1" smd custom
			(at 0 -0.4445 180)
			(size 0.1397 0.1397)
			(layers "F.Cu" "F.Mask" "F.Paste")
			(net "NCT7904_RSTOUT")
			(options
				(clearance outline)
				(anchor circle)
			)
			(primitives
				(gr_poly
					(pts
						(arc
							(start -0.1778 -0.2794)
							(mid -0.249642 -0.249642)
							(end -0.2794 -0.1778)
						)
						(arc
							(start -0.2794 0.1778)
							(mid -0.249642 0.249642)
							(end -0.1778 0.2794)
						)
						(arc
							(start 0.1778 0.2794)
							(mid 0.249642 0.249642)
							(end 0.2794 0.1778)
						)
						(arc
							(start 0.2794 -0.1778)
							(mid 0.249642 -0.249642)
							(end 0.1778 -0.2794)
						)
					)
					(width 0)
					(fill yes)
				)
			)
		)
		(pad "2" smd custom
			(at 0 0.4445 180)
			(size 0.1397 0.1397)
			(layers "F.Cu" "F.Mask" "F.Paste")
			(net "TEMP_ALM#")
			(options
				(clearance outline)
				(anchor circle)
			)
			(primitives
				(gr_poly
					(pts
						(arc
							(start -0.1778 -0.2794)
							(mid -0.249642 -0.249642)
							(end -0.2794 -0.1778)
						)
						(arc
							(start -0.2794 0.1778)
							(mid -0.249642 0.249642)
							(end -0.1778 0.2794)
						)
						(arc
							(start 0.1778 0.2794)
							(mid 0.249642 0.249642)
							(end 0.2794 0.1778)
						)
						(arc
							(start 0.2794 -0.1778)
							(mid 0.249642 -0.249642)
							(end 0.1778 -0.2794)
						)
					)
					(width 0)
					(fill yes)
				)
			)
		)
	)
	(footprint ""
		(layer "F.Cu")
		(at 36.5252 -254.381)
		(property "Reference" "R48"
			(at 0 0 0)
			(layer "F.SilkS")
			(hide yes)
			(effects
				(font
					(size 1.27 1.27)
				)
			)
		)
		(property "Value" "4K7R2J-2-GP"
			(at 0.064008 -3.993896 0)
			(unlocked yes)
			(layer "F.Fab")
			(hide yes)
			(effects
				(font
					(size 1.016 1.016)
					(thickness 0.1524)
				)
			)
		)
		(property "Device Type" "R402H16"
			(at 0.064008 -5.517896 0)
			(unlocked yes)
			(layer "F.Fab")
			(hide yes)
			(effects
				(font
					(size 1.016 1.016)
					(thickness 0.1524)
				)
			)
		)
		(duplicate_pad_numbers_are_jumpers no)
		(fp_line
			(start -0.508 -0.9398)
			(end -0.508 0.9398)
			(stroke
				(width 0.1524)
				(type default)
			)
			(layer "F.SilkS")
		)
		(fp_line
			(start 0.508 -0.9398)
			(end -0.508 -0.9398)
			(stroke
				(width 0.1524)
				(type default)
			)
			(layer "F.SilkS")
		)
		(fp_rect
			(start -0.508 0.9398)
			(end 0.508 -0.9398)
			(stroke
				(width 0)
				(type default)
			)
			(fill no)
			(layer "F.CrtYd")
		)
		(fp_rect
			(start -0.508 0.9398)
			(end 0.508 -0.9398)
			(stroke
				(width 0)
				(type default)
			)
			(fill no)
			(layer "F.Fab")
		)
		(pad "1" smd custom
			(at 0 -0.4445)
			(size 0.1397 0.1397)
			(layers "F.Cu" "F.Mask" "F.Paste")
			(net "P3V3")
			(options
				(clearance outline)
				(anchor circle)
			)
			(primitives
				(gr_poly
					(pts
						(arc
							(start -0.1778 -0.2794)
							(mid -0.249642 -0.249642)
							(end -0.2794 -0.1778)
						)
						(arc
							(start -0.2794 0.1778)
							(mid -0.249642 0.249642)
							(end -0.1778 0.2794)
						)
						(arc
							(start 0.1778 0.2794)
							(mid 0.249642 0.249642)
							(end 0.2794 0.1778)
						)
						(arc
							(start 0.2794 -0.1778)
							(mid 0.249642 -0.249642)
							(end 0.1778 -0.2794)
						)
					)
					(width 0)
					(fill yes)
				)
			)
		)
		(pad "2" smd custom
			(at 0 0.4445)
			(size 0.1397 0.1397)
			(layers "F.Cu" "F.Mask" "F.Paste")
			(net "LED_DRV_RST")
			(options
				(clearance outline)
				(anchor circle)
			)
			(primitives
				(gr_poly
					(pts
						(arc
							(start -0.1778 -0.2794)
							(mid -0.249642 -0.249642)
							(end -0.2794 -0.1778)
						)
						(arc
							(start -0.2794 0.1778)
							(mid -0.249642 0.249642)
							(end -0.1778 0.2794)
						)
						(arc
							(start 0.1778 0.2794)
							(mid 0.249642 0.249642)
							(end 0.2794 0.1778)
						)
						(arc
							(start 0.2794 -0.1778)
							(mid 0.249642 -0.249642)
							(end 0.1778 -0.2794)
						)
					)
					(width 0)
					(fill yes)
				)
			)
		)
	)
	(footprint ""
		(layer "F.Cu")
		(at 41.529 -183.185816)
		(property "Reference" "U8"
			(at 0 0 0)
			(layer "F.SilkS")
			(hide yes)
			(effects
				(font
					(size 1.27 1.27)
				)
			)
		)
		(property "Value" "TSAHC74PWR-GP"
			(at -7.112 -6.0579 0)
			(unlocked yes)
			(layer "F.Fab")
			(hide yes)
			(effects
				(font
					(size 1.016 1.016)
					(thickness 0.1524)
				)
			)
		)
		(property "Device Type" "TSOIC14H48"
			(at -7.112 -7.5819 0)
			(unlocked yes)
			(layer "F.Fab")
			(hide yes)
			(effects
				(font
					(size 1.016 1.016)
					(thickness 0.1524)
				)
			)
		)
		(duplicate_pad_numbers_are_jumpers no)
		(fp_line
			(start -2.9718 -1.778)
			(end 2.1336 -1.778)
			(stroke
				(width 0.1524)
				(type default)
			)
			(layer "F.SilkS")
		)
		(fp_line
			(start -2.9718 1.778)
			(end -2.9718 -1.778)
			(stroke
				(width 0.1524)
				(type default)
			)
			(layer "F.SilkS")
		)
		(fp_line
			(start -2.9337 -0.4699)
			(end -2.9083 -0.4699)
			(stroke
				(width 0.1524)
				(type default)
			)
			(layer "F.SilkS")
		)
		(fp_line
			(start -2.9083 -0.4699)
			(end -2.4384 0)
			(stroke
				(width 0.1524)
				(type default)
			)
			(layer "F.SilkS")
		)
		(fp_line
			(start -2.8956 0.4572)
			(end -2.921 0.4572)
			(stroke
				(width 0.1524)
				(type default)
			)
			(layer "F.SilkS")
		)
		(fp_line
			(start -2.794 3.8227)
			(end -2.794 1.7018)
			(stroke
				(width 0.508)
				(type default)
			)
			(layer "F.SilkS")
		)
		(fp_line
			(start -2.4384 0)
			(end -2.8956 0.4572)
			(stroke
				(width 0.1524)
				(type default)
			)
			(layer "F.SilkS")
		)
		(fp_line
			(start 2.1336 -1.778)
			(end 2.1336 1.778)
			(stroke
				(width 0.1524)
				(type default)
			)
			(layer "F.SilkS")
		)
		(fp_line
			(start 2.1336 1.778)
			(end -2.9718 1.778)
			(stroke
				(width 0.1524)
				(type default)
			)
			(layer "F.SilkS")
		)
		(fp_poly
			(pts
				(xy -2.1336 -1.7653) (xy 2.1336 -1.7653) (xy 2.1336 1.778) (xy -2.1336 1.778)
			)
			(stroke
				(width 0)
				(type default)
			)
			(fill yes)
			(layer "F.SilkS")
		)
		(fp_rect
			(start -2.5019 3.2004)
			(end 2.5019 -3.2004)
			(stroke
				(width 0)
				(type default)
			)
			(fill no)
			(layer "F.CrtYd")
		)
		(fp_poly
			(pts
				(xy -3.048 4.0894) (xy -3.048 -2.5781) (xy -2.5019 -2.5781) (xy -2.5019 3.2004) (xy 2.5019 3.2004)
				(xy 2.5019 -3.2004) (xy -2.5019 -3.2004) (xy -2.5019 -2.5908) (xy -3.048 -2.5908) (xy -3.048 -4.0894)
				(xy 3.048 -4.0894) (xy 3.048 4.0894)
			)
			(stroke
				(width 0)
				(type default)
			)
			(fill no)
			(layer "F.CrtYd")
		)
		(fp_rect
			(start -3.048 4.0894)
			(end 3.048 -4.0894)
			(stroke
				(width 0)
				(type default)
			)
			(fill no)
			(layer "F.Fab")
		)
		(pad "1" smd rect
			(at -1.94945 2.8194)
			(size 0.3556 1.524)
			(layers "F.Cu" "F.Mask" "F.Paste")
			(net "D_LATCH_CLR")
		)
		(pad "2" smd rect
			(at -1.30048 2.8194)
			(size 0.3556 1.524)
			(layers "F.Cu" "F.Mask" "F.Paste")
			(net "GND")
		)
		(pad "3" smd rect
			(at -0.65024 2.8194)
			(size 0.3556 1.524)
			(layers "F.Cu" "F.Mask" "F.Paste")
			(net "TEMP_ALM#_IN_D")
		)
		(pad "4" smd rect
			(at 0 2.8194)
			(size 0.3556 1.524)
			(layers "F.Cu" "F.Mask" "F.Paste")
			(net "D_LATCH_PRE#")
		)
		(pad "5" smd rect
			(at 0.65024 2.8194)
			(size 0.3556 1.524)
			(layers "F.Cu" "F.Mask" "F.Paste")
			(net "D_LATCH_Q")
		)
		(pad "6" smd rect
			(at 1.30048 2.8194)
			(size 0.3556 1.524)
			(layers "F.Cu" "F.Mask" "F.Paste")
			(net "D_LATCH_Q#")
		)
		(pad "7" smd rect
			(at 1.94945 2.8194)
			(size 0.3556 1.524)
			(layers "F.Cu" "F.Mask" "F.Paste")
			(net "GND")
		)
		(pad "8" smd rect
			(at 1.94945 -2.8194)
			(size 0.3556 1.524)
			(layers "F.Cu" "F.Mask" "F.Paste")
			(net "Net_58")
		)
		(pad "9" smd rect
			(at 1.30048 -2.8194)
			(size 0.3556 1.524)
			(layers "F.Cu" "F.Mask" "F.Paste")
			(net "Net_59")
		)
		(pad "10" smd rect
			(at 0.65024 -2.8194)
			(size 0.3556 1.524)
			(layers "F.Cu" "F.Mask" "F.Paste")
			(net "P3V3_AUX")
		)
		(pad "11" smd rect
			(at 0 -2.8194)
			(size 0.3556 1.524)
			(layers "F.Cu" "F.Mask" "F.Paste")
			(net "GND")
		)
		(pad "12" smd rect
			(at -0.65024 -2.8194)
			(size 0.3556 1.524)
			(layers "F.Cu" "F.Mask" "F.Paste")
			(net "GND")
		)
		(pad "13" smd rect
			(at -1.30048 -2.8194)
			(size 0.3556 1.524)
			(layers "F.Cu" "F.Mask" "F.Paste")
			(net "P3V3_AUX")
		)
		(pad "14" smd rect
			(at -1.94945 -2.8194)
			(size 0.3556 1.524)
			(layers "F.Cu" "F.Mask" "F.Paste")
			(net "P3V3_AUX")
		)
	)
	(footprint ""
		(layer "F.Cu")
		(at 37.5666 -254.3556)
		(property "Reference" "R59"
			(at 0 0 0)
			(layer "F.SilkS")
			(hide yes)
			(effects
				(font
					(size 1.27 1.27)
				)
			)
		)
		(property "Value" "330R2J-3-GP"
			(at 0.064008 -3.993896 0)
			(unlocked yes)
			(layer "F.Fab")
			(hide yes)
			(effects
				(font
					(size 1.016 1.016)
					(thickness 0.1524)
				)
			)
		)
		(property "Device Type" "R402H16"
			(at 0.064008 -5.517896 0)
			(unlocked yes)
			(layer "F.Fab")
			(hide yes)
			(effects
				(font
					(size 1.016 1.016)
					(thickness 0.1524)
				)
			)
		)
		(duplicate_pad_numbers_are_jumpers no)
		(fp_line
			(start -0.508 -0.9398)
			(end -0.508 0.9398)
			(stroke
				(width 0.1524)
				(type default)
			)
			(layer "F.SilkS")
		)
		(fp_line
			(start 0.508 -0.9398)
			(end -0.508 -0.9398)
			(stroke
				(width 0.1524)
				(type default)
			)
			(layer "F.SilkS")
		)
		(fp_rect
			(start -0.508 0.9398)
			(end 0.508 -0.9398)
			(stroke
				(width 0)
				(type default)
			)
			(fill no)
			(layer "F.CrtYd")
		)
		(fp_rect
			(start -0.508 0.9398)
			(end 0.508 -0.9398)
			(stroke
				(width 0)
				(type default)
			)
			(fill no)
			(layer "F.Fab")
		)
		(pad "1" smd custom
			(at 0 -0.4445)
			(size 0.1397 0.1397)
			(layers "F.Cu" "F.Mask" "F.Paste")
			(net "P3V3")
			(options
				(clearance outline)
				(anchor circle)
			)
			(primitives
				(gr_poly
					(pts
						(arc
							(start -0.1778 -0.2794)
							(mid -0.249642 -0.249642)
							(end -0.2794 -0.1778)
						)
						(arc
							(start -0.2794 0.1778)
							(mid -0.249642 0.249642)
							(end -0.1778 0.2794)
						)
						(arc
							(start 0.1778 0.2794)
							(mid 0.249642 0.249642)
							(end 0.2794 0.1778)
						)
						(arc
							(start 0.2794 -0.1778)
							(mid 0.249642 -0.249642)
							(end 0.1778 -0.2794)
						)
					)
					(width 0)
					(fill yes)
				)
			)
		)
		(pad "2" smd custom
			(at 0 0.4445)
			(size 0.1397 0.1397)
			(layers "F.Cu" "F.Mask" "F.Paste")
			(net "LED_DR_LED7_RESERVE")
			(options
				(clearance outline)
				(anchor circle)
			)
			(primitives
				(gr_poly
					(pts
						(arc
							(start -0.1778 -0.2794)
							(mid -0.249642 -0.249642)
							(end -0.2794 -0.1778)
						)
						(arc
							(start -0.2794 0.1778)
							(mid -0.249642 0.249642)
							(end -0.1778 0.2794)
						)
						(arc
							(start 0.1778 0.2794)
							(mid 0.249642 0.249642)
							(end 0.2794 0.1778)
						)
						(arc
							(start 0.2794 -0.1778)
							(mid 0.249642 -0.249642)
							(end 0.1778 -0.2794)
						)
					)
					(width 0)
					(fill yes)
				)
			)
		)
	)
	(footprint ""
		(layer "F.Cu")
		(at 14.5796 -171.4754)
		(property "Reference" "R49"
			(at 0 0 0)
			(layer "F.SilkS")
			(hide yes)
			(effects
				(font
					(size 1.27 1.27)
				)
			)
		)
		(property "Value" "4K7R2F-GP"
			(at 0.064008 -3.993896 0)
			(unlocked yes)
			(layer "F.Fab")
			(hide yes)
			(effects
				(font
					(size 1.016 1.016)
					(thickness 0.1524)
				)
			)
		)
		(property "Device Type" "R402H16"
			(at 0.064008 -5.517896 0)
			(unlocked yes)
			(layer "F.Fab")
			(hide yes)
			(effects
				(font
					(size 1.016 1.016)
					(thickness 0.1524)
				)
			)
		)
		(duplicate_pad_numbers_are_jumpers no)
		(fp_line
			(start -0.508 -0.9398)
			(end -0.508 0.9398)
			(stroke
				(width 0.1524)
				(type default)
			)
			(layer "F.SilkS")
		)
		(fp_line
			(start 0.508 -0.9398)
			(end -0.508 -0.9398)
			(stroke
				(width 0.1524)
				(type default)
			)
			(layer "F.SilkS")
		)
		(fp_rect
			(start -0.508 0.9398)
			(end 0.508 -0.9398)
			(stroke
				(width 0)
				(type default)
			)
			(fill no)
			(layer "F.CrtYd")
		)
		(fp_rect
			(start -0.508 0.9398)
			(end 0.508 -0.9398)
			(stroke
				(width 0)
				(type default)
			)
			(fill no)
			(layer "F.Fab")
		)
		(pad "1" smd custom
			(at 0 -0.4445)
			(size 0.1397 0.1397)
			(layers "F.Cu" "F.Mask" "F.Paste")
			(net "P3V3")
			(options
				(clearance outline)
				(anchor circle)
			)
			(primitives
				(gr_poly
					(pts
						(arc
							(start -0.1778 -0.2794)
							(mid -0.249642 -0.249642)
							(end -0.2794 -0.1778)
						)
						(arc
							(start -0.2794 0.1778)
							(mid -0.249642 0.249642)
							(end -0.1778 0.2794)
						)
						(arc
							(start 0.1778 0.2794)
							(mid 0.249642 0.249642)
							(end 0.2794 0.1778)
						)
						(arc
							(start 0.2794 -0.1778)
							(mid 0.249642 -0.249642)
							(end 0.1778 -0.2794)
						)
					)
					(width 0)
					(fill yes)
				)
			)
		)
		(pad "2" smd custom
			(at 0 0.4445)
			(size 0.1397 0.1397)
			(layers "F.Cu" "F.Mask" "F.Paste")
			(net "SEB_PEER_1A_1B_HB_OUT")
			(options
				(clearance outline)
				(anchor circle)
			)
			(primitives
				(gr_poly
					(pts
						(arc
							(start -0.1778 -0.2794)
							(mid -0.249642 -0.249642)
							(end -0.2794 -0.1778)
						)
						(arc
							(start -0.2794 0.1778)
							(mid -0.249642 0.249642)
							(end -0.1778 0.2794)
						)
						(arc
							(start 0.1778 0.2794)
							(mid 0.249642 0.249642)
							(end 0.2794 0.1778)
						)
						(arc
							(start 0.2794 -0.1778)
							(mid 0.249642 -0.249642)
							(end 0.1778 -0.2794)
						)
					)
					(width 0)
					(fill yes)
				)
			)
		)
	)
	(footprint ""
		(layer "F.Cu")
		(at 16.67129 -175.540924 180)
		(property "Reference" "C9"
			(at 0 0 180)
			(layer "F.SilkS")
			(hide yes)
			(effects
				(font
					(size 1.27 1.27)
				)
			)
		)
		(property "Value" "SC1U16V3KX-5GP"
			(at 0 -2.8194 180)
			(unlocked yes)
			(layer "F.Fab")
			(hide yes)
			(effects
				(font
					(size 1.016 1.016)
					(thickness 0.1524)
				)
			)
		)
		(property "Device Type" "C603H36"
			(at 0 -4.3434 180)
			(unlocked yes)
			(layer "F.Fab")
			(hide yes)
			(effects
				(font
					(size 1.016 1.016)
					(thickness 0.1524)
				)
			)
		)
		(duplicate_pad_numbers_are_jumpers no)
		(fp_line
			(start 0.508 0)
			(end -0.508 0)
			(stroke
				(width 0.2032)
				(type default)
			)
			(layer "F.SilkS")
		)
		(fp_rect
			(start -0.5842 1.3335)
			(end 0.5842 -1.3335)
			(stroke
				(width 0)
				(type default)
			)
			(fill no)
			(layer "F.CrtYd")
		)
		(fp_rect
			(start -0.5842 1.3335)
			(end 0.5842 -1.3335)
			(stroke
				(width 0)
				(type default)
			)
			(fill no)
			(layer "F.Fab")
		)
		(pad "1" smd custom
			(at 0 -0.762 180)
			(size 0.2159 0.2159)
			(layers "F.Cu" "F.Mask" "F.Paste")
			(net "P3V3")
			(options
				(clearance outline)
				(anchor circle)
			)
			(primitives
				(gr_poly
					(pts
						(arc
							(start -0.3302 -0.4318)
							(mid -0.402042 -0.402042)
							(end -0.4318 -0.3302)
						)
						(arc
							(start -0.4318 0.3302)
							(mid -0.402042 0.402042)
							(end -0.3302 0.4318)
						)
						(arc
							(start 0.3302 0.4318)
							(mid 0.402042 0.402042)
							(end 0.4318 0.3302)
						)
						(arc
							(start 0.4318 -0.3302)
							(mid 0.402042 -0.402042)
							(end 0.3302 -0.4318)
						)
					)
					(width 0)
					(fill yes)
				)
			)
		)
		(pad "2" smd custom
			(at 0 0.762 180)
			(size 0.2159 0.2159)
			(layers "F.Cu" "F.Mask" "F.Paste")
			(net "GND")
			(options
				(clearance outline)
				(anchor circle)
			)
			(primitives
				(gr_poly
					(pts
						(arc
							(start -0.3302 -0.4318)
							(mid -0.402042 -0.402042)
							(end -0.4318 -0.3302)
						)
						(arc
							(start -0.4318 0.3302)
							(mid -0.402042 0.402042)
							(end -0.3302 0.4318)
						)
						(arc
							(start 0.3302 0.4318)
							(mid 0.402042 0.402042)
							(end 0.4318 0.3302)
						)
						(arc
							(start 0.4318 -0.3302)
							(mid 0.402042 -0.402042)
							(end 0.3302 -0.4318)
						)
					)
					(width 0)
					(fill yes)
				)
			)
		)
	)
	(footprint ""
		(layer "F.Cu")
		(at 27.305 -378.079)
		(property "Reference" "PR2"
			(at 0 0 0)
			(layer "F.SilkS")
			(hide yes)
			(effects
				(font
					(size 1.27 1.27)
				)
			)
		)
		(property "Value" "10R2F-L-GP"
			(at 0.064008 -3.993896 0)
			(unlocked yes)
			(layer "F.Fab")
			(hide yes)
			(effects
				(font
					(size 1.016 1.016)
					(thickness 0.1524)
				)
			)
		)
		(property "Device Type" "R402H14"
			(at 0.064008 -5.517896 0)
			(unlocked yes)
			(layer "F.Fab")
			(hide yes)
			(effects
				(font
					(size 1.016 1.016)
					(thickness 0.1524)
				)
			)
		)
		(duplicate_pad_numbers_are_jumpers no)
		(fp_line
			(start -0.508 -0.9398)
			(end -0.508 0.9398)
			(stroke
				(width 0.1524)
				(type default)
			)
			(layer "F.SilkS")
		)
		(fp_line
			(start 0.508 -0.9398)
			(end -0.508 -0.9398)
			(stroke
				(width 0.1524)
				(type default)
			)
			(layer "F.SilkS")
		)
		(fp_rect
			(start -0.508 0.9398)
			(end 0.508 -0.9398)
			(stroke
				(width 0)
				(type default)
			)
			(fill no)
			(layer "F.CrtYd")
		)
		(fp_rect
			(start -0.508 0.9398)
			(end 0.508 -0.9398)
			(stroke
				(width 0)
				(type default)
			)
			(fill no)
			(layer "F.Fab")
		)
		(pad "1" smd custom
			(at 0 -0.4445)
			(size 0.1397 0.1397)
			(layers "F.Cu" "F.Mask" "F.Paste")
			(net "P12V_AUX")
			(options
				(clearance outline)
				(anchor circle)
			)
			(primitives
				(gr_poly
					(pts
						(arc
							(start -0.1778 -0.2794)
							(mid -0.249642 -0.249642)
							(end -0.2794 -0.1778)
						)
						(arc
							(start -0.2794 0.1778)
							(mid -0.249642 0.249642)
							(end -0.1778 0.2794)
						)
						(arc
							(start 0.1778 0.2794)
							(mid 0.249642 0.249642)
							(end 0.2794 0.1778)
						)
						(arc
							(start 0.2794 -0.1778)
							(mid 0.249642 -0.249642)
							(end 0.1778 -0.2794)
						)
					)
					(width 0)
					(fill yes)
				)
			)
		)
		(pad "2" smd custom
			(at 0 0.4445)
			(size 0.1397 0.1397)
			(layers "F.Cu" "F.Mask" "F.Paste")
			(net "ADM1276_VCC")
			(options
				(clearance outline)
				(anchor circle)
			)
			(primitives
				(gr_poly
					(pts
						(arc
							(start -0.1778 -0.2794)
							(mid -0.249642 -0.249642)
							(end -0.2794 -0.1778)
						)
						(arc
							(start -0.2794 0.1778)
							(mid -0.249642 0.249642)
							(end -0.1778 0.2794)
						)
						(arc
							(start 0.1778 0.2794)
							(mid 0.249642 0.249642)
							(end 0.2794 0.1778)
						)
						(arc
							(start 0.2794 -0.1778)
							(mid 0.249642 -0.249642)
							(end 0.1778 -0.2794)
						)
					)
					(width 0)
					(fill yes)
				)
			)
		)
	)
	(footprint ""
		(layer "F.Cu")
		(at 12.064492 -61.391546)
		(property "Reference" "C32"
			(at 0 0 0)
			(layer "F.SilkS")
			(hide yes)
			(effects
				(font
					(size 1.27 1.27)
				)
			)
		)
		(property "Value" "SC1U25V3KX-1-GP"
			(at 0 -2.8194 0)
			(unlocked yes)
			(layer "F.Fab")
			(hide yes)
			(effects
				(font
					(size 1.016 1.016)
					(thickness 0.1524)
				)
			)
		)
		(property "Device Type" "C603H36"
			(at 0 -4.3434 0)
			(unlocked yes)
			(layer "F.Fab")
			(hide yes)
			(effects
				(font
					(size 1.016 1.016)
					(thickness 0.1524)
				)
			)
		)
		(duplicate_pad_numbers_are_jumpers no)
		(fp_line
			(start 0.508 0)
			(end -0.508 0)
			(stroke
				(width 0.2032)
				(type default)
			)
			(layer "F.SilkS")
		)
		(fp_rect
			(start -0.5842 1.3335)
			(end 0.5842 -1.3335)
			(stroke
				(width 0)
				(type default)
			)
			(fill no)
			(layer "F.CrtYd")
		)
		(fp_rect
			(start -0.5842 1.3335)
			(end 0.5842 -1.3335)
			(stroke
				(width 0)
				(type default)
			)
			(fill no)
			(layer "F.Fab")
		)
		(pad "1" smd custom
			(at 0 -0.762)
			(size 0.2159 0.2159)
			(layers "F.Cu" "F.Mask" "F.Paste")
			(net "P12V")
			(options
				(clearance outline)
				(anchor circle)
			)
			(primitives
				(gr_poly
					(pts
						(arc
							(start -0.3302 -0.4318)
							(mid -0.402042 -0.402042)
							(end -0.4318 -0.3302)
						)
						(arc
							(start -0.4318 0.3302)
							(mid -0.402042 0.402042)
							(end -0.3302 0.4318)
						)
						(arc
							(start 0.3302 0.4318)
							(mid 0.402042 0.402042)
							(end 0.4318 0.3302)
						)
						(arc
							(start 0.4318 -0.3302)
							(mid 0.402042 -0.402042)
							(end 0.3302 -0.4318)
						)
					)
					(width 0)
					(fill yes)
				)
			)
		)
		(pad "2" smd custom
			(at 0 0.762)
			(size 0.2159 0.2159)
			(layers "F.Cu" "F.Mask" "F.Paste")
			(net "GND")
			(options
				(clearance outline)
				(anchor circle)
			)
			(primitives
				(gr_poly
					(pts
						(arc
							(start -0.3302 -0.4318)
							(mid -0.402042 -0.402042)
							(end -0.4318 -0.3302)
						)
						(arc
							(start -0.4318 0.3302)
							(mid -0.402042 0.402042)
							(end -0.3302 0.4318)
						)
						(arc
							(start 0.3302 0.4318)
							(mid 0.402042 0.402042)
							(end 0.4318 0.3302)
						)
						(arc
							(start 0.4318 -0.3302)
							(mid 0.402042 -0.402042)
							(end 0.3302 -0.4318)
						)
					)
					(width 0)
					(fill yes)
				)
			)
		)
	)
	(footprint ""
		(layer "F.Cu")
		(at 26.543 -237.871)
		(property "Reference" "R154"
			(at 0 0 0)
			(layer "F.SilkS")
			(hide yes)
			(effects
				(font
					(size 1.27 1.27)
				)
			)
		)
		(property "Value" "0R0805-PAD-2-GP"
			(at 0.0508 -2.7432 0)
			(unlocked yes)
			(layer "F.Fab")
			(hide yes)
			(effects
				(font
					(size 1.016 1.016)
					(thickness 0.1524)
				)
			)
		)
		(property "Device Type" "0R0805-PAD-1"
			(at 0.0508 -4.2672 0)
			(unlocked yes)
			(layer "F.Fab")
			(hide yes)
			(effects
				(font
					(size 1.016 1.016)
					(thickness 0.1524)
				)
			)
		)
		(duplicate_pad_numbers_are_jumpers no)
		(fp_line
			(start -0.889 -1.7018)
			(end 0.889 -1.7018)
			(stroke
				(width 0.1524)
				(type default)
			)
			(layer "F.SilkS")
		)
		(fp_line
			(start -0.889 1.7018)
			(end -0.889 -1.7018)
			(stroke
				(width 0.1524)
				(type default)
			)
			(layer "F.SilkS")
		)
		(fp_line
			(start 0.889 -1.7018)
			(end 0.889 1.7018)
			(stroke
				(width 0.1524)
				(type default)
			)
			(layer "F.SilkS")
		)
		(fp_line
			(start 0.889 1.7018)
			(end -0.889 1.7018)
			(stroke
				(width 0.1524)
				(type default)
			)
			(layer "F.SilkS")
		)
		(fp_rect
			(start -0.9652 1.778)
			(end 0.9652 -1.778)
			(stroke
				(width 0)
				(type default)
			)
			(fill no)
			(layer "F.CrtYd")
		)
		(fp_rect
			(start -0.9652 1.778)
			(end 0.9652 -1.778)
			(stroke
				(width 0)
				(type default)
			)
			(fill no)
			(layer "F.Fab")
		)
		(pad "1" smd rect
			(at 0 -0.9652)
			(size 1.397 1.5621)
			(drill
				(offset 0 0.20955)
			)
			(layers "F.Cu" "F.Mask" "F.Paste")
			(net "P3V3_LX_COPPER")
		)
		(pad "2" smd rect
			(at 0 0.9652)
			(size 1.397 1.568704)
			(drill
				(offset 0 -0.206248)
			)
			(layers "F.Cu" "F.Mask" "F.Paste")
			(net "P3V3")
		)
	)
	(footprint ""
		(layer "F.Cu")
		(at 15.113 -56.134 -90)
		(property "Reference" "R361"
			(at 0 0 270)
			(layer "F.SilkS")
			(hide yes)
			(effects
				(font
					(size 1.27 1.27)
				)
			)
		)
		(property "Value" "100R2J-2-GP"
			(at 0.064008 -3.993896 270)
			(unlocked yes)
			(layer "F.Fab")
			(hide yes)
			(effects
				(font
					(size 1.016 1.016)
					(thickness 0.1524)
				)
			)
		)
		(property "Device Type" "R402H14"
			(at 0.064008 -5.517896 270)
			(unlocked yes)
			(layer "F.Fab")
			(hide yes)
			(effects
				(font
					(size 1.016 1.016)
					(thickness 0.1524)
				)
			)
		)
		(duplicate_pad_numbers_are_jumpers no)
		(fp_line
			(start -0.508 -0.9398)
			(end -0.508 0.9398)
			(stroke
				(width 0.1524)
				(type default)
			)
			(layer "F.SilkS")
		)
		(fp_line
			(start 0.508 -0.9398)
			(end -0.508 -0.9398)
			(stroke
				(width 0.1524)
				(type default)
			)
			(layer "F.SilkS")
		)
		(fp_rect
			(start -0.508 0.9398)
			(end 0.508 -0.9398)
			(stroke
				(width 0)
				(type default)
			)
			(fill no)
			(layer "F.CrtYd")
		)
		(fp_rect
			(start -0.508 0.9398)
			(end 0.508 -0.9398)
			(stroke
				(width 0)
				(type default)
			)
			(fill no)
			(layer "F.Fab")
		)
		(pad "1" smd custom
			(at 0 -0.4445 270)
			(size 0.1397 0.1397)
			(layers "F.Cu" "F.Mask" "F.Paste")
			(net "LOWER_TRAY_ID")
			(options
				(clearance outline)
				(anchor circle)
			)
			(primitives
				(gr_poly
					(pts
						(arc
							(start -0.1778 -0.2794)
							(mid -0.249642 -0.249642)
							(end -0.2794 -0.1778)
						)
						(arc
							(start -0.2794 0.1778)
							(mid -0.249642 0.249642)
							(end -0.1778 0.2794)
						)
						(arc
							(start 0.1778 0.2794)
							(mid 0.249642 0.249642)
							(end 0.2794 0.1778)
						)
						(arc
							(start 0.2794 -0.1778)
							(mid 0.249642 -0.249642)
							(end 0.1778 -0.2794)
						)
					)
					(width 0)
					(fill yes)
				)
			)
		)
		(pad "2" smd custom
			(at 0 0.4445 270)
			(size 0.1397 0.1397)
			(layers "F.Cu" "F.Mask" "F.Paste")
			(net "GND")
			(options
				(clearance outline)
				(anchor circle)
			)
			(primitives
				(gr_poly
					(pts
						(arc
							(start -0.1778 -0.2794)
							(mid -0.249642 -0.249642)
							(end -0.2794 -0.1778)
						)
						(arc
							(start -0.2794 0.1778)
							(mid -0.249642 0.249642)
							(end -0.1778 0.2794)
						)
						(arc
							(start 0.1778 0.2794)
							(mid 0.249642 0.249642)
							(end 0.2794 0.1778)
						)
						(arc
							(start 0.2794 -0.1778)
							(mid 0.249642 -0.249642)
							(end 0.1778 -0.2794)
						)
					)
					(width 0)
					(fill yes)
				)
			)
		)
	)
	(footprint ""
		(layer "F.Cu")
		(at 22.225 -18.161 90)
		(property "Reference" "R75"
			(at 0 0 90)
			(layer "F.SilkS")
			(hide yes)
			(effects
				(font
					(size 1.27 1.27)
				)
			)
		)
		(property "Value" "10KR2F-2-GP"
			(at 0.064008 -3.993896 90)
			(unlocked yes)
			(layer "F.Fab")
			(hide yes)
			(effects
				(font
					(size 1.016 1.016)
					(thickness 0.1524)
				)
			)
		)
		(property "Device Type" "R402H16"
			(at 0.064008 -5.517896 90)
			(unlocked yes)
			(layer "F.Fab")
			(hide yes)
			(effects
				(font
					(size 1.016 1.016)
					(thickness 0.1524)
				)
			)
		)
		(duplicate_pad_numbers_are_jumpers no)
		(fp_line
			(start 0.508 -0.9398)
			(end -0.508 -0.9398)
			(stroke
				(width 0.1524)
				(type default)
			)
			(layer "F.SilkS")
		)
		(fp_line
			(start -0.508 -0.9398)
			(end -0.508 0.9398)
			(stroke
				(width 0.1524)
				(type default)
			)
			(layer "F.SilkS")
		)
		(fp_rect
			(start -0.508 0.9398)
			(end 0.508 -0.9398)
			(stroke
				(width 0)
				(type default)
			)
			(fill no)
			(layer "F.CrtYd")
		)
		(fp_rect
			(start -0.508 0.9398)
			(end 0.508 -0.9398)
			(stroke
				(width 0)
				(type default)
			)
			(fill no)
			(layer "F.Fab")
		)
		(pad "1" smd custom
			(at 0 -0.4445 90)
			(size 0.1397 0.1397)
			(layers "F.Cu" "F.Mask" "F.Paste")
			(net "FANIN_12")
			(options
				(clearance outline)
				(anchor circle)
			)
			(primitives
				(gr_poly
					(pts
						(arc
							(start -0.1778 -0.2794)
							(mid -0.249642 -0.249642)
							(end -0.2794 -0.1778)
						)
						(arc
							(start -0.2794 0.1778)
							(mid -0.249642 0.249642)
							(end -0.1778 0.2794)
						)
						(arc
							(start 0.1778 0.2794)
							(mid 0.249642 0.249642)
							(end 0.2794 0.1778)
						)
						(arc
							(start 0.2794 -0.1778)
							(mid 0.249642 -0.249642)
							(end 0.1778 -0.2794)
						)
					)
					(width 0)
					(fill yes)
				)
			)
		)
		(pad "2" smd custom
			(at 0 0.4445 90)
			(size 0.1397 0.1397)
			(layers "F.Cu" "F.Mask" "F.Paste")
			(net "GND")
			(options
				(clearance outline)
				(anchor circle)
			)
			(primitives
				(gr_poly
					(pts
						(arc
							(start -0.1778 -0.2794)
							(mid -0.249642 -0.249642)
							(end -0.2794 -0.1778)
						)
						(arc
							(start -0.2794 0.1778)
							(mid -0.249642 0.249642)
							(end -0.1778 0.2794)
						)
						(arc
							(start 0.1778 0.2794)
							(mid 0.249642 0.249642)
							(end 0.2794 0.1778)
						)
						(arc
							(start 0.2794 -0.1778)
							(mid 0.249642 -0.249642)
							(end 0.1778 -0.2794)
						)
					)
					(width 0)
					(fill yes)
				)
			)
		)
	)
	(footprint ""
		(layer "F.Cu")
		(at 26.15438 -376.08256 -90)
		(property "Reference" "PC2"
			(at 0 0 270)
			(layer "F.SilkS")
			(hide yes)
			(effects
				(font
					(size 1.27 1.27)
				)
			)
		)
		(property "Value" "SC10U25V5KX-GP"
			(at -0.0762 -6.1214 270)
			(unlocked yes)
			(layer "F.Fab")
			(hide yes)
			(effects
				(font
					(size 1.016 1.016)
					(thickness 0.1524)
				)
			)
		)
		(property "Device Type" "C805H56"
			(at -0.0762 -8.1534 270)
			(unlocked yes)
			(layer "F.Fab")
			(hide yes)
			(effects
				(font
					(size 1.016 1.016)
					(thickness 0.1524)
				)
			)
		)
		(duplicate_pad_numbers_are_jumpers no)
		(fp_line
			(start 0.635 0)
			(end -0.635 0)
			(stroke
				(width 0.508)
				(type default)
			)
			(layer "F.SilkS")
		)
		(fp_rect
			(start -0.9652 1.778)
			(end 0.9652 -1.778)
			(stroke
				(width 0)
				(type default)
			)
			(fill no)
			(layer "F.CrtYd")
		)
		(fp_poly
			(pts
				(xy -0.9652 -1.778) (xy 0.9652 -1.778) (xy 0.9652 1.778) (xy -0.9652 1.778)
			)
			(stroke
				(width 0)
				(type default)
			)
			(fill no)
			(layer "F.Fab")
		)
		(pad "1" smd rect
			(at 0 -0.9652 270)
			(size 1.397 1.143)
			(layers "F.Cu" "F.Mask" "F.Paste")
			(net "ADM1276_VCC")
		)
		(pad "2" smd rect
			(at 0 0.9652 270)
			(size 1.397 1.143)
			(layers "F.Cu" "F.Mask" "F.Paste")
			(net "GND")
		)
	)
	(footprint ""
		(layer "F.Cu")
		(at 18.7198 -137.5664 180)
		(property "Reference" "PR104"
			(at 0 0 180)
			(layer "F.SilkS")
			(hide yes)
			(effects
				(font
					(size 1.27 1.27)
				)
			)
		)
		(property "Value" "2K7R2F-GP"
			(at 0.064008 -3.993896 180)
			(unlocked yes)
			(layer "F.Fab")
			(hide yes)
			(effects
				(font
					(size 1.016 1.016)
					(thickness 0.1524)
				)
			)
		)
		(property "Device Type" "R402H16"
			(at 0.064008 -5.517896 180)
			(unlocked yes)
			(layer "F.Fab")
			(hide yes)
			(effects
				(font
					(size 1.016 1.016)
					(thickness 0.1524)
				)
			)
		)
		(duplicate_pad_numbers_are_jumpers no)
		(fp_line
			(start 0.508 -0.9398)
			(end -0.508 -0.9398)
			(stroke
				(width 0.1524)
				(type default)
			)
			(layer "F.SilkS")
		)
		(fp_line
			(start -0.508 -0.9398)
			(end -0.508 0.9398)
			(stroke
				(width 0.1524)
				(type default)
			)
			(layer "F.SilkS")
		)
		(fp_rect
			(start -0.508 0.9398)
			(end 0.508 -0.9398)
			(stroke
				(width 0)
				(type default)
			)
			(fill no)
			(layer "F.CrtYd")
		)
		(fp_rect
			(start -0.508 0.9398)
			(end 0.508 -0.9398)
			(stroke
				(width 0)
				(type default)
			)
			(fill no)
			(layer "F.Fab")
		)
		(pad "1" smd custom
			(at 0 -0.4445 180)
			(size 0.1397 0.1397)
			(layers "F.Cu" "F.Mask" "F.Paste")
			(net "P12VU")
			(options
				(clearance outline)
				(anchor circle)
			)
			(primitives
				(gr_poly
					(pts
						(arc
							(start -0.1778 -0.2794)
							(mid -0.249642 -0.249642)
							(end -0.2794 -0.1778)
						)
						(arc
							(start -0.2794 0.1778)
							(mid -0.249642 0.249642)
							(end -0.1778 0.2794)
						)
						(arc
							(start 0.1778 0.2794)
							(mid 0.249642 0.249642)
							(end 0.2794 0.1778)
						)
						(arc
							(start 0.2794 -0.1778)
							(mid 0.249642 -0.249642)
							(end 0.1778 -0.2794)
						)
					)
					(width 0)
					(fill yes)
				)
			)
		)
		(pad "2" smd custom
			(at 0 0.4445 180)
			(size 0.1397 0.1397)
			(layers "F.Cu" "F.Mask" "F.Paste")
			(net "P12VU_2490_PG")
			(options
				(clearance outline)
				(anchor circle)
			)
			(primitives
				(gr_poly
					(pts
						(arc
							(start -0.1778 -0.2794)
							(mid -0.249642 -0.249642)
							(end -0.2794 -0.1778)
						)
						(arc
							(start -0.2794 0.1778)
							(mid -0.249642 0.249642)
							(end -0.1778 0.2794)
						)
						(arc
							(start 0.1778 0.2794)
							(mid 0.249642 0.249642)
							(end 0.2794 0.1778)
						)
						(arc
							(start 0.2794 -0.1778)
							(mid 0.249642 -0.249642)
							(end 0.1778 -0.2794)
						)
					)
					(width 0)
					(fill yes)
				)
			)
		)
	)
	(footprint ""
		(layer "F.Cu")
		(at 48.895 -111.633 90)
		(property "Reference" "PR119"
			(at 0 0 90)
			(layer "F.SilkS")
			(hide yes)
			(effects
				(font
					(size 1.27 1.27)
				)
			)
		)
		(property "Value" "10R2F-L-GP"
			(at 0.064008 -3.993896 90)
			(unlocked yes)
			(layer "F.Fab")
			(hide yes)
			(effects
				(font
					(size 1.016 1.016)
					(thickness 0.1524)
				)
			)
		)
		(property "Device Type" "R402H14"
			(at 0.064008 -5.517896 90)
			(unlocked yes)
			(layer "F.Fab")
			(hide yes)
			(effects
				(font
					(size 1.016 1.016)
					(thickness 0.1524)
				)
			)
		)
		(duplicate_pad_numbers_are_jumpers no)
		(fp_line
			(start 0.508 -0.9398)
			(end -0.508 -0.9398)
			(stroke
				(width 0.1524)
				(type default)
			)
			(layer "F.SilkS")
		)
		(fp_line
			(start -0.508 -0.9398)
			(end -0.508 0.9398)
			(stroke
				(width 0.1524)
				(type default)
			)
			(layer "F.SilkS")
		)
		(fp_rect
			(start -0.508 0.9398)
			(end 0.508 -0.9398)
			(stroke
				(width 0)
				(type default)
			)
			(fill no)
			(layer "F.CrtYd")
		)
		(fp_rect
			(start -0.508 0.9398)
			(end 0.508 -0.9398)
			(stroke
				(width 0)
				(type default)
			)
			(fill no)
			(layer "F.Fab")
		)
		(pad "1" smd custom
			(at 0 -0.4445 90)
			(size 0.1397 0.1397)
			(layers "F.Cu" "F.Mask" "F.Paste")
			(net "P12VL_2490_GATE_DRV_2")
			(options
				(clearance outline)
				(anchor circle)
			)
			(primitives
				(gr_poly
					(pts
						(arc
							(start -0.1778 -0.2794)
							(mid -0.249642 -0.249642)
							(end -0.2794 -0.1778)
						)
						(arc
							(start -0.2794 0.1778)
							(mid -0.249642 0.249642)
							(end -0.1778 0.2794)
						)
						(arc
							(start 0.1778 0.2794)
							(mid 0.249642 0.249642)
							(end 0.2794 0.1778)
						)
						(arc
							(start 0.2794 -0.1778)
							(mid 0.249642 -0.249642)
							(end 0.1778 -0.2794)
						)
					)
					(width 0)
					(fill yes)
				)
			)
		)
		(pad "2" smd custom
			(at 0 0.4445 90)
			(size 0.1397 0.1397)
			(layers "F.Cu" "F.Mask" "F.Paste")
			(net "P12VL_2490_GATE")
			(options
				(clearance outline)
				(anchor circle)
			)
			(primitives
				(gr_poly
					(pts
						(arc
							(start -0.1778 -0.2794)
							(mid -0.249642 -0.249642)
							(end -0.2794 -0.1778)
						)
						(arc
							(start -0.2794 0.1778)
							(mid -0.249642 0.249642)
							(end -0.1778 0.2794)
						)
						(arc
							(start 0.1778 0.2794)
							(mid 0.249642 0.249642)
							(end 0.2794 0.1778)
						)
						(arc
							(start 0.2794 -0.1778)
							(mid 0.249642 -0.249642)
							(end 0.1778 -0.2794)
						)
					)
					(width 0)
					(fill yes)
				)
			)
		)
	)
	(footprint ""
		(layer "F.Cu")
		(at 16.3068 -254.3302 180)
		(property "Reference" "R86"
			(at 0 0 180)
			(layer "F.SilkS")
			(hide yes)
			(effects
				(font
					(size 1.27 1.27)
				)
			)
		)
		(property "Value" "27KR3F-GP"
			(at -0.0254 -2.5146 180)
			(unlocked yes)
			(layer "F.Fab")
			(hide yes)
			(effects
				(font
					(size 1.016 1.016)
					(thickness 0.1524)
				)
			)
		)
		(property "Device Type" "R603H22"
			(at -0.0254 -4.0386 180)
			(unlocked yes)
			(layer "F.Fab")
			(hide yes)
			(effects
				(font
					(size 1.016 1.016)
					(thickness 0.1524)
				)
			)
		)
		(duplicate_pad_numbers_are_jumpers no)
		(fp_line
			(start 0.2032 0)
			(end 0.4826 0)
			(stroke
				(width 0.2032)
				(type default)
			)
			(layer "F.SilkS")
		)
		(fp_line
			(start -0.4826 0)
			(end -0.2032 0)
			(stroke
				(width 0.2032)
				(type default)
			)
			(layer "F.SilkS")
		)
		(fp_rect
			(start -0.5842 1.3335)
			(end 0.5842 -1.3335)
			(stroke
				(width 0)
				(type default)
			)
			(fill no)
			(layer "F.CrtYd")
		)
		(fp_rect
			(start -0.5842 1.3335)
			(end 0.5842 -1.3335)
			(stroke
				(width 0)
				(type default)
			)
			(fill no)
			(layer "F.Fab")
		)
		(pad "1" smd custom
			(at 0 -0.762 180)
			(size 0.2159 0.2159)
			(layers "F.Cu" "F.Mask" "F.Paste")
			(net "FANIN_5")
			(options
				(clearance outline)
				(anchor circle)
			)
			(primitives
				(gr_poly
					(pts
						(arc
							(start -0.3302 -0.4318)
							(mid -0.402042 -0.402042)
							(end -0.4318 -0.3302)
						)
						(arc
							(start -0.4318 0.3302)
							(mid -0.402042 0.402042)
							(end -0.3302 0.4318)
						)
						(arc
							(start 0.3302 0.4318)
							(mid 0.402042 0.402042)
							(end 0.4318 0.3302)
						)
						(arc
							(start 0.4318 -0.3302)
							(mid 0.402042 -0.402042)
							(end 0.3302 -0.4318)
						)
					)
					(width 0)
					(fill yes)
				)
			)
		)
		(pad "2" smd custom
			(at 0 0.762 180)
			(size 0.2159 0.2159)
			(layers "F.Cu" "F.Mask" "F.Paste")
			(net "FAN_TACH5")
			(options
				(clearance outline)
				(anchor circle)
			)
			(primitives
				(gr_poly
					(pts
						(arc
							(start -0.3302 -0.4318)
							(mid -0.402042 -0.402042)
							(end -0.4318 -0.3302)
						)
						(arc
							(start -0.4318 0.3302)
							(mid -0.402042 0.402042)
							(end -0.3302 0.4318)
						)
						(arc
							(start 0.3302 0.4318)
							(mid 0.402042 0.402042)
							(end 0.4318 0.3302)
						)
						(arc
							(start 0.4318 -0.3302)
							(mid 0.402042 -0.402042)
							(end 0.3302 -0.4318)
						)
					)
					(width 0)
					(fill yes)
				)
			)
		)
	)
	(footprint ""
		(layer "F.Cu")
		(at 9.906 -261.112 180)
		(property "Reference" "R125"
			(at 0 0 180)
			(layer "F.SilkS")
			(hide yes)
			(effects
				(font
					(size 1.27 1.27)
				)
			)
		)
		(property "Value" "1K8R6J-GP"
			(at -0.0508 -4.8514 180)
			(unlocked yes)
			(layer "F.Fab")
			(hide yes)
			(effects
				(font
					(size 1.016 1.016)
					(thickness 0.1524)
				)
			)
		)
		(property "Device Type" "R1206H28"
			(at 0 -6.3754 180)
			(unlocked yes)
			(layer "F.Fab")
			(hide yes)
			(effects
				(font
					(size 1.016 1.016)
					(thickness 0.1524)
				)
			)
		)
		(duplicate_pad_numbers_are_jumpers no)
		(fp_line
			(start 1.016 2.2352)
			(end -1.016 2.2352)
			(stroke
				(width 0.1524)
				(type default)
			)
			(layer "F.SilkS")
		)
		(fp_line
			(start 1.016 -2.2352)
			(end 1.016 2.2352)
			(stroke
				(width 0.1524)
				(type default)
			)
			(layer "F.SilkS")
		)
		(fp_line
			(start -1.016 2.2352)
			(end -1.016 -2.2352)
			(stroke
				(width 0.1524)
				(type default)
			)
			(layer "F.SilkS")
		)
		(fp_line
			(start -1.016 -2.2352)
			(end 1.016 -2.2352)
			(stroke
				(width 0.1524)
				(type default)
			)
			(layer "F.SilkS")
		)
		(fp_rect
			(start -1.0922 2.3114)
			(end 1.0922 -2.3114)
			(stroke
				(width 0)
				(type default)
			)
			(fill no)
			(layer "F.CrtYd")
		)
		(fp_poly
			(pts
				(xy -1.0922 -2.3114) (xy 1.0922 -2.3114) (xy 1.0922 2.3114) (xy -1.0922 2.3114)
			)
			(stroke
				(width 0)
				(type default)
			)
			(fill no)
			(layer "F.Fab")
		)
		(pad "1" smd rect
			(at 0 -1.397 180)
			(size 1.651 1.27)
			(layers "F.Cu" "F.Mask" "F.Paste")
			(net "P12V")
		)
		(pad "2" smd rect
			(at 0 1.397 180)
			(size 1.651 1.27)
			(layers "F.Cu" "F.Mask" "F.Paste")
			(net "LED_DR_LED2_BLUE")
		)
	)
	(footprint ""
		(layer "F.Cu")
		(at 41.3258 -136.271 90)
		(property "Reference" "PC88"
			(at 0 0 90)
			(layer "F.SilkS")
			(hide yes)
			(effects
				(font
					(size 1.27 1.27)
				)
			)
		)
		(property "Value" "SC220P50V2KX-3GP"
			(at 1.1811 -2.7051 90)
			(unlocked yes)
			(layer "F.Fab")
			(hide yes)
			(effects
				(font
					(size 1.016 1.016)
					(thickness 0.1524)
				)
			)
		)
		(property "Device Type" "C402H22"
			(at 1.1811 -4.2291 90)
			(unlocked yes)
			(layer "F.Fab")
			(hide yes)
			(effects
				(font
					(size 1.016 1.016)
					(thickness 0.1524)
				)
			)
		)
		(duplicate_pad_numbers_are_jumpers no)
		(fp_rect
			(start -0.4318 0.9525)
			(end 0.4318 -0.9525)
			(stroke
				(width 0)
				(type default)
			)
			(fill no)
			(layer "F.CrtYd")
		)
		(fp_rect
			(start -0.4318 0.9525)
			(end 0.4318 -0.9525)
			(stroke
				(width 0)
				(type default)
			)
			(fill no)
			(layer "F.Fab")
		)
		(pad "1" smd custom
			(at 0 -0.4445 90)
			(size 0.1524 0.1524)
			(layers "F.Cu" "F.Mask" "F.Paste")
			(net "P12VL_2490_SENSE")
			(options
				(clearance outline)
				(anchor circle)
			)
			(primitives
				(gr_poly
					(pts
						(arc
							(start 0.3048 -0.2032)
							(mid 0.275042 -0.275042)
							(end 0.2032 -0.3048)
						)
						(arc
							(start -0.2032 -0.3048)
							(mid -0.275042 -0.275042)
							(end -0.3048 -0.2032)
						)
						(arc
							(start -0.3048 0.2032)
							(mid -0.275042 0.275042)
							(end -0.2032 0.3048)
						)
						(arc
							(start 0.2032 0.3048)
							(mid 0.275042 0.275042)
							(end 0.3048 0.2032)
						)
					)
					(width 0)
					(fill yes)
				)
			)
		)
		(pad "2" smd custom
			(at 0 0.4445 90)
			(size 0.1524 0.1524)
			(layers "F.Cu" "F.Mask" "F.Paste")
			(net "P12VL_2490_VCC")
			(options
				(clearance outline)
				(anchor circle)
			)
			(primitives
				(gr_poly
					(pts
						(arc
							(start 0.3048 -0.2032)
							(mid 0.275042 -0.275042)
							(end 0.2032 -0.3048)
						)
						(arc
							(start -0.2032 -0.3048)
							(mid -0.275042 -0.275042)
							(end -0.3048 -0.2032)
						)
						(arc
							(start -0.3048 0.2032)
							(mid -0.275042 0.275042)
							(end -0.2032 0.3048)
						)
						(arc
							(start 0.2032 0.3048)
							(mid 0.275042 0.275042)
							(end 0.3048 0.2032)
						)
					)
					(width 0)
					(fill yes)
				)
			)
		)
	)
	(footprint ""
		(layer "F.Cu")
		(at 18.7706 -139.7254 90)
		(property "Reference" "TP23"
			(at 0 0 90)
			(layer "F.SilkS")
			(hide yes)
			(effects
				(font
					(size 1.27 1.27)
				)
			)
		)
		(property "Value" "TPAD32-GP"
			(at 0 -3.166364 90)
			(unlocked yes)
			(layer "F.Fab")
			(hide yes)
			(effects
				(font
					(size 1.016 1.016)
					(thickness 0.1524)
				)
			)
		)
		(property "Device Type" "TPAD32"
			(at 0 -4.690618 90)
			(unlocked yes)
			(layer "F.Fab")
			(hide yes)
			(effects
				(font
					(size 1.016 1.016)
					(thickness 0.1524)
				)
			)
		)
		(duplicate_pad_numbers_are_jumpers no)
		(fp_poly
			(pts
				(arc
					(start 0.7112 0)
					(mid -0.7112 0)
					(end 0.7112 0)
				)
			)
			(stroke
				(width 0)
				(type default)
			)
			(fill no)
			(layer "F.CrtYd")
		)
		(fp_poly
			(pts
				(arc
					(start 0.7112 0)
					(mid -0.7112 0)
					(end 0.7112 0)
				)
			)
			(stroke
				(width 0)
				(type default)
			)
			(fill no)
			(layer "F.Fab")
		)
		(pad "1" smd circle
			(at 0 0 90)
			(size 0.8128 0.8128)
			(layers "F.Cu" "F.Mask" "F.Paste")
			(net "P12VU_2490_PG")
		)
	)
	(footprint ""
		(layer "F.Cu")
		(at 21.844 -376.936 90)
		(property "Reference" "PR34"
			(at 0 0 90)
			(layer "F.SilkS")
			(hide yes)
			(effects
				(font
					(size 1.27 1.27)
				)
			)
		)
		(property "Value" "51KR2F-L-GP"
			(at 0.064008 -3.993896 90)
			(unlocked yes)
			(layer "F.Fab")
			(hide yes)
			(effects
				(font
					(size 1.016 1.016)
					(thickness 0.1524)
				)
			)
		)
		(property "Device Type" "R402H16"
			(at 0.064008 -5.517896 90)
			(unlocked yes)
			(layer "F.Fab")
			(hide yes)
			(effects
				(font
					(size 1.016 1.016)
					(thickness 0.1524)
				)
			)
		)
		(duplicate_pad_numbers_are_jumpers no)
		(fp_line
			(start 0.508 -0.9398)
			(end -0.508 -0.9398)
			(stroke
				(width 0.1524)
				(type default)
			)
			(layer "F.SilkS")
		)
		(fp_line
			(start -0.508 -0.9398)
			(end -0.508 0.9398)
			(stroke
				(width 0.1524)
				(type default)
			)
			(layer "F.SilkS")
		)
		(fp_rect
			(start -0.508 0.9398)
			(end 0.508 -0.9398)
			(stroke
				(width 0)
				(type default)
			)
			(fill no)
			(layer "F.CrtYd")
		)
		(fp_rect
			(start -0.508 0.9398)
			(end 0.508 -0.9398)
			(stroke
				(width 0)
				(type default)
			)
			(fill no)
			(layer "F.Fab")
		)
		(pad "1" smd custom
			(at 0 -0.4445 90)
			(size 0.1397 0.1397)
			(layers "F.Cu" "F.Mask" "F.Paste")
			(net "P12V_AUX")
			(options
				(clearance outline)
				(anchor circle)
			)
			(primitives
				(gr_poly
					(pts
						(arc
							(start -0.1778 -0.2794)
							(mid -0.249642 -0.249642)
							(end -0.2794 -0.1778)
						)
						(arc
							(start -0.2794 0.1778)
							(mid -0.249642 0.249642)
							(end -0.1778 0.2794)
						)
						(arc
							(start 0.1778 0.2794)
							(mid 0.249642 0.249642)
							(end 0.2794 0.1778)
						)
						(arc
							(start 0.2794 -0.1778)
							(mid 0.249642 -0.249642)
							(end 0.1778 -0.2794)
						)
					)
					(width 0)
					(fill yes)
				)
			)
		)
		(pad "2" smd custom
			(at 0 0.4445 90)
			(size 0.1397 0.1397)
			(layers "F.Cu" "F.Mask" "F.Paste")
			(net "ADM1276_UV")
			(options
				(clearance outline)
				(anchor circle)
			)
			(primitives
				(gr_poly
					(pts
						(arc
							(start -0.1778 -0.2794)
							(mid -0.249642 -0.249642)
							(end -0.2794 -0.1778)
						)
						(arc
							(start -0.2794 0.1778)
							(mid -0.249642 0.249642)
							(end -0.1778 0.2794)
						)
						(arc
							(start 0.1778 0.2794)
							(mid 0.249642 0.249642)
							(end 0.2794 0.1778)
						)
						(arc
							(start 0.2794 -0.1778)
							(mid 0.249642 -0.249642)
							(end 0.1778 -0.2794)
						)
					)
					(width 0)
					(fill yes)
				)
			)
		)
	)
	(footprint ""
		(layer "F.Cu")
		(at 23.622 -363.601 -90)
		(property "Reference" "PC5"
			(at 0 0 270)
			(layer "F.SilkS")
			(hide yes)
			(effects
				(font
					(size 1.27 1.27)
				)
			)
		)
		(property "Value" "SCD01U25V2KX-3GP"
			(at 1.1811 -2.7051 270)
			(unlocked yes)
			(layer "F.Fab")
			(hide yes)
			(effects
				(font
					(size 1.016 1.016)
					(thickness 0.1524)
				)
			)
		)
		(property "Device Type" "C402H22"
			(at 1.1811 -4.2291 270)
			(unlocked yes)
			(layer "F.Fab")
			(hide yes)
			(effects
				(font
					(size 1.016 1.016)
					(thickness 0.1524)
				)
			)
		)
		(duplicate_pad_numbers_are_jumpers no)
		(fp_rect
			(start -0.4318 0.9525)
			(end 0.4318 -0.9525)
			(stroke
				(width 0)
				(type default)
			)
			(fill no)
			(layer "F.CrtYd")
		)
		(fp_rect
			(start -0.4318 0.9525)
			(end 0.4318 -0.9525)
			(stroke
				(width 0)
				(type default)
			)
			(fill no)
			(layer "F.Fab")
		)
		(pad "1" smd custom
			(at 0 -0.4445 270)
			(size 0.1524 0.1524)
			(layers "F.Cu" "F.Mask" "F.Paste")
			(net "ADM1276_TIMER")
			(options
				(clearance outline)
				(anchor circle)
			)
			(primitives
				(gr_poly
					(pts
						(arc
							(start 0.3048 -0.2032)
							(mid 0.275042 -0.275042)
							(end 0.2032 -0.3048)
						)
						(arc
							(start -0.2032 -0.3048)
							(mid -0.275042 -0.275042)
							(end -0.3048 -0.2032)
						)
						(arc
							(start -0.3048 0.2032)
							(mid -0.275042 0.275042)
							(end -0.2032 0.3048)
						)
						(arc
							(start 0.2032 0.3048)
							(mid 0.275042 0.275042)
							(end 0.3048 0.2032)
						)
					)
					(width 0)
					(fill yes)
				)
			)
		)
		(pad "2" smd custom
			(at 0 0.4445 270)
			(size 0.1524 0.1524)
			(layers "F.Cu" "F.Mask" "F.Paste")
			(net "GND")
			(options
				(clearance outline)
				(anchor circle)
			)
			(primitives
				(gr_poly
					(pts
						(arc
							(start 0.3048 -0.2032)
							(mid 0.275042 -0.275042)
							(end 0.2032 -0.3048)
						)
						(arc
							(start -0.2032 -0.3048)
							(mid -0.275042 -0.275042)
							(end -0.3048 -0.2032)
						)
						(arc
							(start -0.3048 0.2032)
							(mid -0.275042 0.275042)
							(end -0.2032 0.3048)
						)
						(arc
							(start 0.2032 0.3048)
							(mid 0.275042 0.275042)
							(end 0.3048 0.2032)
						)
					)
					(width 0)
					(fill yes)
				)
			)
		)
	)
	(footprint ""
		(layer "F.Cu")
		(at 28.2956 -362.1786 90)
		(property "Reference" "PR12"
			(at 0 0 90)
			(layer "F.SilkS")
			(hide yes)
			(effects
				(font
					(size 1.27 1.27)
				)
			)
		)
		(property "Value" "0R2J-2-GP"
			(at 0.064008 -3.993896 90)
			(unlocked yes)
			(layer "F.Fab")
			(hide yes)
			(effects
				(font
					(size 1.016 1.016)
					(thickness 0.1524)
				)
			)
		)
		(property "Device Type" "R402H16"
			(at 0.064008 -5.517896 90)
			(unlocked yes)
			(layer "F.Fab")
			(hide yes)
			(effects
				(font
					(size 1.016 1.016)
					(thickness 0.1524)
				)
			)
		)
		(duplicate_pad_numbers_are_jumpers no)
		(fp_line
			(start 0.508 -0.9398)
			(end -0.508 -0.9398)
			(stroke
				(width 0.1524)
				(type default)
			)
			(layer "F.SilkS")
		)
		(fp_line
			(start -0.508 -0.9398)
			(end -0.508 0.9398)
			(stroke
				(width 0.1524)
				(type default)
			)
			(layer "F.SilkS")
		)
		(fp_rect
			(start -0.508 0.9398)
			(end 0.508 -0.9398)
			(stroke
				(width 0)
				(type default)
			)
			(fill no)
			(layer "F.CrtYd")
		)
		(fp_rect
			(start -0.508 0.9398)
			(end 0.508 -0.9398)
			(stroke
				(width 0)
				(type default)
			)
			(fill no)
			(layer "F.Fab")
		)
		(pad "1" smd custom
			(at 0 -0.4445 90)
			(size 0.1397 0.1397)
			(layers "F.Cu" "F.Mask" "F.Paste")
			(net "ADM1276_LATCH#")
			(options
				(clearance outline)
				(anchor circle)
			)
			(primitives
				(gr_poly
					(pts
						(arc
							(start -0.1778 -0.2794)
							(mid -0.249642 -0.249642)
							(end -0.2794 -0.1778)
						)
						(arc
							(start -0.2794 0.1778)
							(mid -0.249642 0.249642)
							(end -0.1778 0.2794)
						)
						(arc
							(start 0.1778 0.2794)
							(mid 0.249642 0.249642)
							(end 0.2794 0.1778)
						)
						(arc
							(start 0.2794 -0.1778)
							(mid 0.249642 -0.249642)
							(end 0.1778 -0.2794)
						)
					)
					(width 0)
					(fill yes)
				)
			)
		)
		(pad "2" smd custom
			(at 0 0.4445 90)
			(size 0.1397 0.1397)
			(layers "F.Cu" "F.Mask" "F.Paste")
			(net "ADM1276_EN")
			(options
				(clearance outline)
				(anchor circle)
			)
			(primitives
				(gr_poly
					(pts
						(arc
							(start -0.1778 -0.2794)
							(mid -0.249642 -0.249642)
							(end -0.2794 -0.1778)
						)
						(arc
							(start -0.2794 0.1778)
							(mid -0.249642 0.249642)
							(end -0.1778 0.2794)
						)
						(arc
							(start 0.1778 0.2794)
							(mid 0.249642 0.249642)
							(end 0.2794 0.1778)
						)
						(arc
							(start 0.2794 -0.1778)
							(mid 0.249642 -0.249642)
							(end 0.1778 -0.2794)
						)
					)
					(width 0)
					(fill yes)
				)
			)
		)
	)
	(footprint ""
		(layer "F.Cu")
		(at 26.3906 -121.7676)
		(property "Reference" "C258"
			(at 0 0 0)
			(layer "F.SilkS")
			(hide yes)
			(effects
				(font
					(size 1.27 1.27)
				)
			)
		)
		(property "Value" "SC1U25V3KX-1-GP"
			(at 0 -2.8194 0)
			(unlocked yes)
			(layer "F.Fab")
			(hide yes)
			(effects
				(font
					(size 1.016 1.016)
					(thickness 0.1524)
				)
			)
		)
		(property "Device Type" "C603H36"
			(at 0 -4.3434 0)
			(unlocked yes)
			(layer "F.Fab")
			(hide yes)
			(effects
				(font
					(size 1.016 1.016)
					(thickness 0.1524)
				)
			)
		)
		(duplicate_pad_numbers_are_jumpers no)
		(fp_line
			(start 0.508 0)
			(end -0.508 0)
			(stroke
				(width 0.2032)
				(type default)
			)
			(layer "F.SilkS")
		)
		(fp_rect
			(start -0.5842 1.3335)
			(end 0.5842 -1.3335)
			(stroke
				(width 0)
				(type default)
			)
			(fill no)
			(layer "F.CrtYd")
		)
		(fp_rect
			(start -0.5842 1.3335)
			(end 0.5842 -1.3335)
			(stroke
				(width 0)
				(type default)
			)
			(fill no)
			(layer "F.Fab")
		)
		(pad "1" smd custom
			(at 0 -0.762)
			(size 0.2159 0.2159)
			(layers "F.Cu" "F.Mask" "F.Paste")
			(net "P12V")
			(options
				(clearance outline)
				(anchor circle)
			)
			(primitives
				(gr_poly
					(pts
						(arc
							(start -0.3302 -0.4318)
							(mid -0.402042 -0.402042)
							(end -0.4318 -0.3302)
						)
						(arc
							(start -0.4318 0.3302)
							(mid -0.402042 0.402042)
							(end -0.3302 0.4318)
						)
						(arc
							(start 0.3302 0.4318)
							(mid 0.402042 0.402042)
							(end 0.4318 0.3302)
						)
						(arc
							(start 0.4318 -0.3302)
							(mid 0.402042 -0.402042)
							(end 0.3302 -0.4318)
						)
					)
					(width 0)
					(fill yes)
				)
			)
		)
		(pad "2" smd custom
			(at 0 0.762)
			(size 0.2159 0.2159)
			(layers "F.Cu" "F.Mask" "F.Paste")
			(net "GND")
			(options
				(clearance outline)
				(anchor circle)
			)
			(primitives
				(gr_poly
					(pts
						(arc
							(start -0.3302 -0.4318)
							(mid -0.402042 -0.402042)
							(end -0.4318 -0.3302)
						)
						(arc
							(start -0.4318 0.3302)
							(mid -0.402042 0.402042)
							(end -0.3302 0.4318)
						)
						(arc
							(start 0.3302 0.4318)
							(mid 0.402042 0.402042)
							(end 0.4318 0.3302)
						)
						(arc
							(start 0.4318 -0.3302)
							(mid 0.402042 -0.402042)
							(end 0.3302 -0.4318)
						)
					)
					(width 0)
					(fill yes)
				)
			)
		)
	)
	(footprint ""
		(layer "F.Cu")
		(at 45.81271 -163.594034)
		(property "Reference" "R3"
			(at 0 0 0)
			(layer "F.SilkS")
			(hide yes)
			(effects
				(font
					(size 1.27 1.27)
				)
			)
		)
		(property "Value" "4K7R2F-GP"
			(at 0.064008 -3.993896 0)
			(unlocked yes)
			(layer "F.Fab")
			(hide yes)
			(effects
				(font
					(size 1.016 1.016)
					(thickness 0.1524)
				)
			)
		)
		(property "Device Type" "R402H16"
			(at 0.064008 -5.517896 0)
			(unlocked yes)
			(layer "F.Fab")
			(hide yes)
			(effects
				(font
					(size 1.016 1.016)
					(thickness 0.1524)
				)
			)
		)
		(duplicate_pad_numbers_are_jumpers no)
		(fp_line
			(start -0.508 -0.9398)
			(end -0.508 0.9398)
			(stroke
				(width 0.1524)
				(type default)
			)
			(layer "F.SilkS")
		)
		(fp_line
			(start 0.508 -0.9398)
			(end -0.508 -0.9398)
			(stroke
				(width 0.1524)
				(type default)
			)
			(layer "F.SilkS")
		)
		(fp_rect
			(start -0.508 0.9398)
			(end 0.508 -0.9398)
			(stroke
				(width 0)
				(type default)
			)
			(fill no)
			(layer "F.CrtYd")
		)
		(fp_rect
			(start -0.508 0.9398)
			(end 0.508 -0.9398)
			(stroke
				(width 0)
				(type default)
			)
			(fill no)
			(layer "F.Fab")
		)
		(pad "1" smd custom
			(at 0 -0.4445)
			(size 0.1397 0.1397)
			(layers "F.Cu" "F.Mask" "F.Paste")
			(net "OSC_TRI_S")
			(options
				(clearance outline)
				(anchor circle)
			)
			(primitives
				(gr_poly
					(pts
						(arc
							(start -0.1778 -0.2794)
							(mid -0.249642 -0.249642)
							(end -0.2794 -0.1778)
						)
						(arc
							(start -0.2794 0.1778)
							(mid -0.249642 0.249642)
							(end -0.1778 0.2794)
						)
						(arc
							(start 0.1778 0.2794)
							(mid 0.249642 0.249642)
							(end 0.2794 0.1778)
						)
						(arc
							(start 0.2794 -0.1778)
							(mid 0.249642 -0.249642)
							(end 0.1778 -0.2794)
						)
					)
					(width 0)
					(fill yes)
				)
			)
		)
		(pad "2" smd custom
			(at 0 0.4445)
			(size 0.1397 0.1397)
			(layers "F.Cu" "F.Mask" "F.Paste")
			(net "P3V3")
			(options
				(clearance outline)
				(anchor circle)
			)
			(primitives
				(gr_poly
					(pts
						(arc
							(start -0.1778 -0.2794)
							(mid -0.249642 -0.249642)
							(end -0.2794 -0.1778)
						)
						(arc
							(start -0.2794 0.1778)
							(mid -0.249642 0.249642)
							(end -0.1778 0.2794)
						)
						(arc
							(start 0.1778 0.2794)
							(mid 0.249642 0.249642)
							(end 0.2794 0.1778)
						)
						(arc
							(start 0.2794 -0.1778)
							(mid 0.249642 -0.249642)
							(end 0.1778 -0.2794)
						)
					)
					(width 0)
					(fill yes)
				)
			)
		)
	)
	(footprint ""
		(layer "F.Cu")
		(at 31.75 -381 180)
		(property "Reference" "PR21"
			(at 0 0 180)
			(layer "F.SilkS")
			(hide yes)
			(effects
				(font
					(size 1.27 1.27)
				)
			)
		)
		(property "Value" "10R2F-L-GP"
			(at 0.064008 -3.993896 180)
			(unlocked yes)
			(layer "F.Fab")
			(hide yes)
			(effects
				(font
					(size 1.016 1.016)
					(thickness 0.1524)
				)
			)
		)
		(property "Device Type" "R402H14"
			(at 0.064008 -5.517896 180)
			(unlocked yes)
			(layer "F.Fab")
			(hide yes)
			(effects
				(font
					(size 1.016 1.016)
					(thickness 0.1524)
				)
			)
		)
		(duplicate_pad_numbers_are_jumpers no)
		(fp_line
			(start 0.508 -0.9398)
			(end -0.508 -0.9398)
			(stroke
				(width 0.1524)
				(type default)
			)
			(layer "F.SilkS")
		)
		(fp_line
			(start -0.508 -0.9398)
			(end -0.508 0.9398)
			(stroke
				(width 0.1524)
				(type default)
			)
			(layer "F.SilkS")
		)
		(fp_rect
			(start -0.508 0.9398)
			(end 0.508 -0.9398)
			(stroke
				(width 0)
				(type default)
			)
			(fill no)
			(layer "F.CrtYd")
		)
		(fp_rect
			(start -0.508 0.9398)
			(end 0.508 -0.9398)
			(stroke
				(width 0)
				(type default)
			)
			(fill no)
			(layer "F.Fab")
		)
		(pad "1" smd custom
			(at 0 -0.4445 180)
			(size 0.1397 0.1397)
			(layers "F.Cu" "F.Mask" "F.Paste")
			(net "ADM1276_SENSE-")
			(options
				(clearance outline)
				(anchor circle)
			)
			(primitives
				(gr_poly
					(pts
						(arc
							(start -0.1778 -0.2794)
							(mid -0.249642 -0.249642)
							(end -0.2794 -0.1778)
						)
						(arc
							(start -0.2794 0.1778)
							(mid -0.249642 0.249642)
							(end -0.1778 0.2794)
						)
						(arc
							(start 0.1778 0.2794)
							(mid 0.249642 0.249642)
							(end 0.2794 0.1778)
						)
						(arc
							(start 0.2794 -0.1778)
							(mid 0.249642 -0.249642)
							(end 0.1778 -0.2794)
						)
					)
					(width 0)
					(fill yes)
				)
			)
		)
		(pad "2" smd custom
			(at 0 0.4445 180)
			(size 0.1397 0.1397)
			(layers "F.Cu" "F.Mask" "F.Paste")
			(net "SENSE-_R1")
			(options
				(clearance outline)
				(anchor circle)
			)
			(primitives
				(gr_poly
					(pts
						(arc
							(start -0.1778 -0.2794)
							(mid -0.249642 -0.249642)
							(end -0.2794 -0.1778)
						)
						(arc
							(start -0.2794 0.1778)
							(mid -0.249642 0.249642)
							(end -0.1778 0.2794)
						)
						(arc
							(start 0.1778 0.2794)
							(mid 0.249642 0.249642)
							(end 0.2794 0.1778)
						)
						(arc
							(start 0.2794 -0.1778)
							(mid 0.249642 -0.249642)
							(end 0.1778 -0.2794)
						)
					)
					(width 0)
					(fill yes)
				)
			)
		)
	)
	(footprint ""
		(layer "F.Cu")
		(at 15.6464 -53.2384 180)
		(property "Reference" "R357"
			(at 0 0 180)
			(layer "F.SilkS")
			(hide yes)
			(effects
				(font
					(size 1.27 1.27)
				)
			)
		)
		(property "Value" "10KR2F-2-GP"
			(at 0.064008 -3.993896 180)
			(unlocked yes)
			(layer "F.Fab")
			(hide yes)
			(effects
				(font
					(size 1.016 1.016)
					(thickness 0.1524)
				)
			)
		)
		(property "Device Type" "R402H16"
			(at 0.064008 -5.517896 180)
			(unlocked yes)
			(layer "F.Fab")
			(hide yes)
			(effects
				(font
					(size 1.016 1.016)
					(thickness 0.1524)
				)
			)
		)
		(duplicate_pad_numbers_are_jumpers no)
		(fp_line
			(start 0.508 -0.9398)
			(end -0.508 -0.9398)
			(stroke
				(width 0.1524)
				(type default)
			)
			(layer "F.SilkS")
		)
		(fp_line
			(start -0.508 -0.9398)
			(end -0.508 0.9398)
			(stroke
				(width 0.1524)
				(type default)
			)
			(layer "F.SilkS")
		)
		(fp_rect
			(start -0.508 0.9398)
			(end 0.508 -0.9398)
			(stroke
				(width 0)
				(type default)
			)
			(fill no)
			(layer "F.CrtYd")
		)
		(fp_rect
			(start -0.508 0.9398)
			(end 0.508 -0.9398)
			(stroke
				(width 0)
				(type default)
			)
			(fill no)
			(layer "F.Fab")
		)
		(pad "1" smd custom
			(at 0 -0.4445 180)
			(size 0.1397 0.1397)
			(layers "F.Cu" "F.Mask" "F.Paste")
			(net "P3V3")
			(options
				(clearance outline)
				(anchor circle)
			)
			(primitives
				(gr_poly
					(pts
						(arc
							(start -0.1778 -0.2794)
							(mid -0.249642 -0.249642)
							(end -0.2794 -0.1778)
						)
						(arc
							(start -0.2794 0.1778)
							(mid -0.249642 0.249642)
							(end -0.1778 0.2794)
						)
						(arc
							(start 0.1778 0.2794)
							(mid 0.249642 0.249642)
							(end 0.2794 0.1778)
						)
						(arc
							(start 0.2794 -0.1778)
							(mid 0.249642 -0.249642)
							(end 0.1778 -0.2794)
						)
					)
					(width 0)
					(fill yes)
				)
			)
		)
		(pad "2" smd custom
			(at 0 0.4445 180)
			(size 0.1397 0.1397)
			(layers "F.Cu" "F.Mask" "F.Paste")
			(net "FCB_HW_REVISION")
			(options
				(clearance outline)
				(anchor circle)
			)
			(primitives
				(gr_poly
					(pts
						(arc
							(start -0.1778 -0.2794)
							(mid -0.249642 -0.249642)
							(end -0.2794 -0.1778)
						)
						(arc
							(start -0.2794 0.1778)
							(mid -0.249642 0.249642)
							(end -0.1778 0.2794)
						)
						(arc
							(start 0.1778 0.2794)
							(mid 0.249642 0.249642)
							(end 0.2794 0.1778)
						)
						(arc
							(start 0.2794 -0.1778)
							(mid 0.249642 -0.249642)
							(end 0.1778 -0.2794)
						)
					)
					(width 0)
					(fill yes)
				)
			)
		)
	)
	(footprint ""
		(layer "F.Cu")
		(at 27.686 -381 180)
		(property "Reference" "PR17"
			(at 0 0 180)
			(layer "F.SilkS")
			(hide yes)
			(effects
				(font
					(size 1.27 1.27)
				)
			)
		)
		(property "Value" "10R2F-L-GP"
			(at 0.064008 -3.993896 180)
			(unlocked yes)
			(layer "F.Fab")
			(hide yes)
			(effects
				(font
					(size 1.016 1.016)
					(thickness 0.1524)
				)
			)
		)
		(property "Device Type" "R402H14"
			(at 0.064008 -5.517896 180)
			(unlocked yes)
			(layer "F.Fab")
			(hide yes)
			(effects
				(font
					(size 1.016 1.016)
					(thickness 0.1524)
				)
			)
		)
		(duplicate_pad_numbers_are_jumpers no)
		(fp_line
			(start 0.508 -0.9398)
			(end -0.508 -0.9398)
			(stroke
				(width 0.1524)
				(type default)
			)
			(layer "F.SilkS")
		)
		(fp_line
			(start -0.508 -0.9398)
			(end -0.508 0.9398)
			(stroke
				(width 0.1524)
				(type default)
			)
			(layer "F.SilkS")
		)
		(fp_rect
			(start -0.508 0.9398)
			(end 0.508 -0.9398)
			(stroke
				(width 0)
				(type default)
			)
			(fill no)
			(layer "F.CrtYd")
		)
		(fp_rect
			(start -0.508 0.9398)
			(end 0.508 -0.9398)
			(stroke
				(width 0)
				(type default)
			)
			(fill no)
			(layer "F.Fab")
		)
		(pad "1" smd custom
			(at 0 -0.4445 180)
			(size 0.1397 0.1397)
			(layers "F.Cu" "F.Mask" "F.Paste")
			(net "ADM1276_SENSE+")
			(options
				(clearance outline)
				(anchor circle)
			)
			(primitives
				(gr_poly
					(pts
						(arc
							(start -0.1778 -0.2794)
							(mid -0.249642 -0.249642)
							(end -0.2794 -0.1778)
						)
						(arc
							(start -0.2794 0.1778)
							(mid -0.249642 0.249642)
							(end -0.1778 0.2794)
						)
						(arc
							(start 0.1778 0.2794)
							(mid 0.249642 0.249642)
							(end 0.2794 0.1778)
						)
						(arc
							(start 0.2794 -0.1778)
							(mid 0.249642 -0.249642)
							(end 0.1778 -0.2794)
						)
					)
					(width 0)
					(fill yes)
				)
			)
		)
		(pad "2" smd custom
			(at 0 0.4445 180)
			(size 0.1397 0.1397)
			(layers "F.Cu" "F.Mask" "F.Paste")
			(net "SENSE+_R4")
			(options
				(clearance outline)
				(anchor circle)
			)
			(primitives
				(gr_poly
					(pts
						(arc
							(start -0.1778 -0.2794)
							(mid -0.249642 -0.249642)
							(end -0.2794 -0.1778)
						)
						(arc
							(start -0.2794 0.1778)
							(mid -0.249642 0.249642)
							(end -0.1778 0.2794)
						)
						(arc
							(start 0.1778 0.2794)
							(mid 0.249642 0.249642)
							(end 0.2794 0.1778)
						)
						(arc
							(start 0.2794 -0.1778)
							(mid 0.249642 -0.249642)
							(end 0.1778 -0.2794)
						)
					)
					(width 0)
					(fill yes)
				)
			)
		)
	)
	(footprint ""
		(layer "F.Cu")
		(at 12.9794 -449.5292 90)
		(property "Reference" "R105"
			(at 0 0 90)
			(layer "F.SilkS")
			(hide yes)
			(effects
				(font
					(size 1.27 1.27)
				)
			)
		)
		(property "Value" "10KR2F-2-GP"
			(at 0.064008 -3.993896 90)
			(unlocked yes)
			(layer "F.Fab")
			(hide yes)
			(effects
				(font
					(size 1.016 1.016)
					(thickness 0.1524)
				)
			)
		)
		(property "Device Type" "R402H16"
			(at 0.064008 -5.517896 90)
			(unlocked yes)
			(layer "F.Fab")
			(hide yes)
			(effects
				(font
					(size 1.016 1.016)
					(thickness 0.1524)
				)
			)
		)
		(duplicate_pad_numbers_are_jumpers no)
		(fp_line
			(start 0.508 -0.9398)
			(end -0.508 -0.9398)
			(stroke
				(width 0.1524)
				(type default)
			)
			(layer "F.SilkS")
		)
		(fp_line
			(start -0.508 -0.9398)
			(end -0.508 0.9398)
			(stroke
				(width 0.1524)
				(type default)
			)
			(layer "F.SilkS")
		)
		(fp_rect
			(start -0.508 0.9398)
			(end 0.508 -0.9398)
			(stroke
				(width 0)
				(type default)
			)
			(fill no)
			(layer "F.CrtYd")
		)
		(fp_rect
			(start -0.508 0.9398)
			(end 0.508 -0.9398)
			(stroke
				(width 0)
				(type default)
			)
			(fill no)
			(layer "F.Fab")
		)
		(pad "1" smd custom
			(at 0 -0.4445 90)
			(size 0.1397 0.1397)
			(layers "F.Cu" "F.Mask" "F.Paste")
			(net "FANIN_2")
			(options
				(clearance outline)
				(anchor circle)
			)
			(primitives
				(gr_poly
					(pts
						(arc
							(start -0.1778 -0.2794)
							(mid -0.249642 -0.249642)
							(end -0.2794 -0.1778)
						)
						(arc
							(start -0.2794 0.1778)
							(mid -0.249642 0.249642)
							(end -0.1778 0.2794)
						)
						(arc
							(start 0.1778 0.2794)
							(mid 0.249642 0.249642)
							(end 0.2794 0.1778)
						)
						(arc
							(start 0.2794 -0.1778)
							(mid 0.249642 -0.249642)
							(end 0.1778 -0.2794)
						)
					)
					(width 0)
					(fill yes)
				)
			)
		)
		(pad "2" smd custom
			(at 0 0.4445 90)
			(size 0.1397 0.1397)
			(layers "F.Cu" "F.Mask" "F.Paste")
			(net "GND")
			(options
				(clearance outline)
				(anchor circle)
			)
			(primitives
				(gr_poly
					(pts
						(arc
							(start -0.1778 -0.2794)
							(mid -0.249642 -0.249642)
							(end -0.2794 -0.1778)
						)
						(arc
							(start -0.2794 0.1778)
							(mid -0.249642 0.249642)
							(end -0.1778 0.2794)
						)
						(arc
							(start 0.1778 0.2794)
							(mid 0.249642 0.249642)
							(end 0.2794 0.1778)
						)
						(arc
							(start 0.2794 -0.1778)
							(mid 0.249642 -0.249642)
							(end 0.1778 -0.2794)
						)
					)
					(width 0)
					(fill yes)
				)
			)
		)
	)
	(footprint ""
		(layer "F.Cu")
		(at 16.2814 -231.4194)
		(property "Reference" "R115"
			(at 0 0 0)
			(layer "F.SilkS")
			(hide yes)
			(effects
				(font
					(size 1.27 1.27)
				)
			)
		)
		(property "Value" "2KR2F-3-GP"
			(at 0.064008 -3.993896 0)
			(unlocked yes)
			(layer "F.Fab")
			(hide yes)
			(effects
				(font
					(size 1.016 1.016)
					(thickness 0.1524)
				)
			)
		)
		(property "Device Type" "R402H16"
			(at 0.064008 -5.517896 0)
			(unlocked yes)
			(layer "F.Fab")
			(hide yes)
			(effects
				(font
					(size 1.016 1.016)
					(thickness 0.1524)
				)
			)
		)
		(duplicate_pad_numbers_are_jumpers no)
		(fp_line
			(start -0.508 -0.9398)
			(end -0.508 0.9398)
			(stroke
				(width 0.1524)
				(type default)
			)
			(layer "F.SilkS")
		)
		(fp_line
			(start 0.508 -0.9398)
			(end -0.508 -0.9398)
			(stroke
				(width 0.1524)
				(type default)
			)
			(layer "F.SilkS")
		)
		(fp_rect
			(start -0.508 0.9398)
			(end 0.508 -0.9398)
			(stroke
				(width 0)
				(type default)
			)
			(fill no)
			(layer "F.CrtYd")
		)
		(fp_rect
			(start -0.508 0.9398)
			(end 0.508 -0.9398)
			(stroke
				(width 0)
				(type default)
			)
			(fill no)
			(layer "F.Fab")
		)
		(pad "1" smd custom
			(at 0 -0.4445)
			(size 0.1397 0.1397)
			(layers "F.Cu" "F.Mask" "F.Paste")
			(net "LED_DR_LED3")
			(options
				(clearance outline)
				(anchor circle)
			)
			(primitives
				(gr_poly
					(pts
						(arc
							(start -0.1778 -0.2794)
							(mid -0.249642 -0.249642)
							(end -0.2794 -0.1778)
						)
						(arc
							(start -0.2794 0.1778)
							(mid -0.249642 0.249642)
							(end -0.1778 0.2794)
						)
						(arc
							(start 0.1778 0.2794)
							(mid 0.249642 0.249642)
							(end 0.2794 0.1778)
						)
						(arc
							(start 0.2794 -0.1778)
							(mid 0.249642 -0.249642)
							(end 0.1778 -0.2794)
						)
					)
					(width 0)
					(fill yes)
				)
			)
		)
		(pad "2" smd custom
			(at 0 0.4445)
			(size 0.1397 0.1397)
			(layers "F.Cu" "F.Mask" "F.Paste")
			(net "LED_DR_LED3_B")
			(options
				(clearance outline)
				(anchor circle)
			)
			(primitives
				(gr_poly
					(pts
						(arc
							(start -0.1778 -0.2794)
							(mid -0.249642 -0.249642)
							(end -0.2794 -0.1778)
						)
						(arc
							(start -0.2794 0.1778)
							(mid -0.249642 0.249642)
							(end -0.1778 0.2794)
						)
						(arc
							(start 0.1778 0.2794)
							(mid 0.249642 0.249642)
							(end 0.2794 0.1778)
						)
						(arc
							(start 0.2794 -0.1778)
							(mid 0.249642 -0.249642)
							(end 0.1778 -0.2794)
						)
					)
					(width 0)
					(fill yes)
				)
			)
		)
	)
	(footprint ""
		(layer "F.Cu")
		(at 26.8732 -357.6574 -90)
		(property "Reference" "R367"
			(at 0 0 270)
			(layer "F.SilkS")
			(hide yes)
			(effects
				(font
					(size 1.27 1.27)
				)
			)
		)
		(property "Value" "10KR2F-2-GP"
			(at 0.064008 -3.993896 270)
			(unlocked yes)
			(layer "F.Fab")
			(hide yes)
			(effects
				(font
					(size 1.016 1.016)
					(thickness 0.1524)
				)
			)
		)
		(property "Device Type" "R402H16"
			(at 0.064008 -5.517896 270)
			(unlocked yes)
			(layer "F.Fab")
			(hide yes)
			(effects
				(font
					(size 1.016 1.016)
					(thickness 0.1524)
				)
			)
		)
		(duplicate_pad_numbers_are_jumpers no)
		(fp_line
			(start -0.508 -0.9398)
			(end -0.508 0.9398)
			(stroke
				(width 0.1524)
				(type default)
			)
			(layer "F.SilkS")
		)
		(fp_line
			(start 0.508 -0.9398)
			(end -0.508 -0.9398)
			(stroke
				(width 0.1524)
				(type default)
			)
			(layer "F.SilkS")
		)
		(fp_rect
			(start -0.508 0.9398)
			(end 0.508 -0.9398)
			(stroke
				(width 0)
				(type default)
			)
			(fill no)
			(layer "F.CrtYd")
		)
		(fp_rect
			(start -0.508 0.9398)
			(end 0.508 -0.9398)
			(stroke
				(width 0)
				(type default)
			)
			(fill no)
			(layer "F.Fab")
		)
		(pad "1" smd custom
			(at 0 -0.4445 270)
			(size 0.1397 0.1397)
			(layers "F.Cu" "F.Mask" "F.Paste")
			(net "P3V3")
			(options
				(clearance outline)
				(anchor circle)
			)
			(primitives
				(gr_poly
					(pts
						(arc
							(start -0.1778 -0.2794)
							(mid -0.249642 -0.249642)
							(end -0.2794 -0.1778)
						)
						(arc
							(start -0.2794 0.1778)
							(mid -0.249642 0.249642)
							(end -0.1778 0.2794)
						)
						(arc
							(start 0.1778 0.2794)
							(mid 0.249642 0.249642)
							(end 0.2794 0.1778)
						)
						(arc
							(start 0.2794 -0.1778)
							(mid 0.249642 -0.249642)
							(end 0.1778 -0.2794)
						)
					)
					(width 0)
					(fill yes)
				)
			)
		)
		(pad "2" smd custom
			(at 0 0.4445 270)
			(size 0.1397 0.1397)
			(layers "F.Cu" "F.Mask" "F.Paste")
			(net "TEMP_ALM#_G")
			(options
				(clearance outline)
				(anchor circle)
			)
			(primitives
				(gr_poly
					(pts
						(arc
							(start -0.1778 -0.2794)
							(mid -0.249642 -0.249642)
							(end -0.2794 -0.1778)
						)
						(arc
							(start -0.2794 0.1778)
							(mid -0.249642 0.249642)
							(end -0.1778 0.2794)
						)
						(arc
							(start 0.1778 0.2794)
							(mid 0.249642 0.249642)
							(end 0.2794 0.1778)
						)
						(arc
							(start 0.2794 -0.1778)
							(mid 0.249642 -0.249642)
							(end 0.1778 -0.2794)
						)
					)
					(width 0)
					(fill yes)
				)
			)
		)
	)
	(footprint ""
		(layer "F.Cu")
		(at 24.384 -237.871)
		(property "Reference" "PC43"
			(at 0 0 0)
			(layer "F.SilkS")
			(hide yes)
			(effects
				(font
					(size 1.27 1.27)
				)
			)
		)
		(property "Value" "SC22U16V6MX-GP"
			(at -0.0762 -5.1308 0)
			(unlocked yes)
			(layer "F.Fab")
			(hide yes)
			(effects
				(font
					(size 1.016 1.016)
					(thickness 0.1524)
				)
			)
		)
		(property "Device Type" "C1206H71"
			(at -0.127 -6.6548 0)
			(unlocked yes)
			(layer "F.Fab")
			(hide yes)
			(effects
				(font
					(size 1.016 1.016)
					(thickness 0.1524)
				)
			)
		)
		(duplicate_pad_numbers_are_jumpers no)
		(fp_line
			(start -1.016 -2.2352)
			(end 1.016 -2.2352)
			(stroke
				(width 0.1524)
				(type default)
			)
			(layer "F.SilkS")
		)
		(fp_line
			(start -1.016 -0.8382)
			(end -1.016 -2.2352)
			(stroke
				(width 0.1524)
				(type default)
			)
			(layer "F.SilkS")
		)
		(fp_line
			(start -1.016 2.2352)
			(end -1.016 0.8382)
			(stroke
				(width 0.1524)
				(type default)
			)
			(layer "F.SilkS")
		)
		(fp_line
			(start 1.016 -2.2352)
			(end 1.016 -0.8382)
			(stroke
				(width 0.1524)
				(type default)
			)
			(layer "F.SilkS")
		)
		(fp_line
			(start 1.016 0.8382)
			(end 1.016 2.2352)
			(stroke
				(width 0.1524)
				(type default)
			)
			(layer "F.SilkS")
		)
		(fp_line
			(start 1.016 2.2352)
			(end -1.016 2.2352)
			(stroke
				(width 0.1524)
				(type default)
			)
			(layer "F.SilkS")
		)
		(fp_rect
			(start -1.0922 2.3114)
			(end 1.0922 -2.3114)
			(stroke
				(width 0)
				(type default)
			)
			(fill no)
			(layer "F.CrtYd")
		)
		(fp_poly
			(pts
				(xy 1.0922 -2.3114) (xy 1.0922 2.3114) (xy -1.0922 2.3114) (xy -1.0922 -2.3114)
			)
			(stroke
				(width 0)
				(type default)
			)
			(fill no)
			(layer "F.Fab")
		)
		(pad "1" smd rect
			(at 0 -1.397)
			(size 1.651 1.27)
			(layers "F.Cu" "F.Mask" "F.Paste")
			(net "P3V3_LX_COPPER")
		)
		(pad "2" smd rect
			(at 0 1.397)
			(size 1.651 1.27)
			(layers "F.Cu" "F.Mask" "F.Paste")
			(net "GND")
		)
	)
	(footprint ""
		(layer "F.Cu")
		(at 30.734 -381 180)
		(property "Reference" "PR20"
			(at 0 0 180)
			(layer "F.SilkS")
			(hide yes)
			(effects
				(font
					(size 1.27 1.27)
				)
			)
		)
		(property "Value" "10R2F-L-GP"
			(at 0.064008 -3.993896 180)
			(unlocked yes)
			(layer "F.Fab")
			(hide yes)
			(effects
				(font
					(size 1.016 1.016)
					(thickness 0.1524)
				)
			)
		)
		(property "Device Type" "R402H14"
			(at 0.064008 -5.517896 180)
			(unlocked yes)
			(layer "F.Fab")
			(hide yes)
			(effects
				(font
					(size 1.016 1.016)
					(thickness 0.1524)
				)
			)
		)
		(duplicate_pad_numbers_are_jumpers no)
		(fp_line
			(start 0.508 -0.9398)
			(end -0.508 -0.9398)
			(stroke
				(width 0.1524)
				(type default)
			)
			(layer "F.SilkS")
		)
		(fp_line
			(start -0.508 -0.9398)
			(end -0.508 0.9398)
			(stroke
				(width 0.1524)
				(type default)
			)
			(layer "F.SilkS")
		)
		(fp_rect
			(start -0.508 0.9398)
			(end 0.508 -0.9398)
			(stroke
				(width 0)
				(type default)
			)
			(fill no)
			(layer "F.CrtYd")
		)
		(fp_rect
			(start -0.508 0.9398)
			(end 0.508 -0.9398)
			(stroke
				(width 0)
				(type default)
			)
			(fill no)
			(layer "F.Fab")
		)
		(pad "1" smd custom
			(at 0 -0.4445 180)
			(size 0.1397 0.1397)
			(layers "F.Cu" "F.Mask" "F.Paste")
			(net "ADM1276_SENSE+")
			(options
				(clearance outline)
				(anchor circle)
			)
			(primitives
				(gr_poly
					(pts
						(arc
							(start -0.1778 -0.2794)
							(mid -0.249642 -0.249642)
							(end -0.2794 -0.1778)
						)
						(arc
							(start -0.2794 0.1778)
							(mid -0.249642 0.249642)
							(end -0.1778 0.2794)
						)
						(arc
							(start 0.1778 0.2794)
							(mid 0.249642 0.249642)
							(end 0.2794 0.1778)
						)
						(arc
							(start 0.2794 -0.1778)
							(mid 0.249642 -0.249642)
							(end 0.1778 -0.2794)
						)
					)
					(width 0)
					(fill yes)
				)
			)
		)
		(pad "2" smd custom
			(at 0 0.4445 180)
			(size 0.1397 0.1397)
			(layers "F.Cu" "F.Mask" "F.Paste")
			(net "SENSE+_R1")
			(options
				(clearance outline)
				(anchor circle)
			)
			(primitives
				(gr_poly
					(pts
						(arc
							(start -0.1778 -0.2794)
							(mid -0.249642 -0.249642)
							(end -0.2794 -0.1778)
						)
						(arc
							(start -0.2794 0.1778)
							(mid -0.249642 0.249642)
							(end -0.1778 0.2794)
						)
						(arc
							(start 0.1778 0.2794)
							(mid 0.249642 0.249642)
							(end 0.2794 0.1778)
						)
						(arc
							(start 0.2794 -0.1778)
							(mid 0.249642 -0.249642)
							(end 0.1778 -0.2794)
						)
					)
					(width 0)
					(fill yes)
				)
			)
		)
	)
	(footprint ""
		(layer "F.Cu")
		(at 31.75 -357.048816)
		(property "Reference" "Q49"
			(at 0 0 0)
			(layer "F.SilkS")
			(hide yes)
			(effects
				(font
					(size 1.27 1.27)
				)
			)
		)
		(property "Value" "2N7002-11-GP"
			(at 0.127 -8.9662 0)
			(unlocked yes)
			(layer "F.Fab")
			(hide yes)
			(effects
				(font
					(size 1.016 1.016)
					(thickness 0.1524)
				)
			)
		)
		(property "Device Type" "SOT23DGS2D4H44"
			(at 0.127 -10.4902 0)
			(unlocked yes)
			(layer "F.Fab")
			(hide yes)
			(effects
				(font
					(size 1.016 1.016)
					(thickness 0.1524)
				)
			)
		)
		(duplicate_pad_numbers_are_jumpers no)
		(fp_line
			(start -1.651 -1.778)
			(end -1.651 1.778)
			(stroke
				(width 0.1524)
				(type default)
			)
			(layer "F.SilkS")
		)
		(fp_line
			(start -1.651 1.778)
			(end 1.651 1.778)
			(stroke
				(width 0.1524)
				(type default)
			)
			(layer "F.SilkS")
		)
		(fp_line
			(start 1.651 -1.778)
			(end -1.651 -1.778)
			(stroke
				(width 0.1524)
				(type default)
			)
			(layer "F.SilkS")
		)
		(fp_line
			(start 1.651 1.778)
			(end 1.651 -1.778)
			(stroke
				(width 0.1524)
				(type default)
			)
			(layer "F.SilkS")
		)
		(fp_poly
			(pts
				(xy -1.778 1.8796) (xy -1.778 -1.8796) (xy 1.778 -1.8796) (xy 1.778 1.8796)
			)
			(stroke
				(width 0)
				(type default)
			)
			(fill no)
			(layer "F.CrtYd")
		)
		(fp_poly
			(pts
				(xy -1.778 1.8796) (xy -1.778 -1.8796) (xy 1.778 -1.8796) (xy 1.778 1.8796)
			)
			(stroke
				(width 0)
				(type default)
			)
			(fill no)
			(layer "F.Fab")
		)
		(pad "D" smd custom
			(at 0 -0.9525)
			(size 0.1905 0.1905)
			(layers "F.Cu" "F.Mask" "F.Paste")
			(net "ADM1276_EN")
			(options
				(clearance outline)
				(anchor circle)
			)
			(primitives
				(gr_poly
					(pts
						(arc
							(start -0.1778 0.5715)
							(mid -0.321484 0.511984)
							(end -0.381 0.3683)
						)
						(arc
							(start -0.381 -0.3683)
							(mid -0.321484 -0.511984)
							(end -0.1778 -0.5715)
						)
						(arc
							(start 0.1778 -0.5715)
							(mid 0.321484 -0.511984)
							(end 0.381 -0.3683)
						)
						(arc
							(start 0.381 0.3683)
							(mid 0.321484 0.511984)
							(end 0.1778 0.5715)
						)
					)
					(width 0)
					(fill yes)
				)
			)
		)
		(pad "G" smd custom
			(at -0.98425 0.9525)
			(size 0.1905 0.1905)
			(layers "F.Cu" "F.Mask" "F.Paste")
			(net "OTP_RETRY_G")
			(options
				(clearance outline)
				(anchor circle)
			)
			(primitives
				(gr_poly
					(pts
						(arc
							(start -0.1778 0.5715)
							(mid -0.321484 0.511984)
							(end -0.381 0.3683)
						)
						(arc
							(start -0.381 -0.3683)
							(mid -0.321484 -0.511984)
							(end -0.1778 -0.5715)
						)
						(arc
							(start 0.1778 -0.5715)
							(mid 0.321484 -0.511984)
							(end 0.381 -0.3683)
						)
						(arc
							(start 0.381 0.3683)
							(mid 0.321484 0.511984)
							(end 0.1778 0.5715)
						)
					)
					(width 0)
					(fill yes)
				)
			)
		)
		(pad "S" smd custom
			(at 0.98425 0.9525)
			(size 0.1905 0.1905)
			(layers "F.Cu" "F.Mask" "F.Paste")
			(net "GND")
			(options
				(clearance outline)
				(anchor circle)
			)
			(primitives
				(gr_poly
					(pts
						(arc
							(start -0.1778 0.5715)
							(mid -0.321484 0.511984)
							(end -0.381 0.3683)
						)
						(arc
							(start -0.381 -0.3683)
							(mid -0.321484 -0.511984)
							(end -0.1778 -0.5715)
						)
						(arc
							(start 0.1778 -0.5715)
							(mid 0.321484 -0.511984)
							(end 0.381 -0.3683)
						)
						(arc
							(start 0.381 0.3683)
							(mid 0.321484 0.511984)
							(end 0.1778 0.5715)
						)
					)
					(width 0)
					(fill yes)
				)
			)
		)
	)
	(footprint ""
		(layer "F.Cu")
		(at 27.0764 -168.1988 -90)
		(property "Reference" "R164"
			(at 0 0 270)
			(layer "F.SilkS")
			(hide yes)
			(effects
				(font
					(size 1.27 1.27)
				)
			)
		)
		(property "Value" "0R2J-2-GP"
			(at 0.064008 -3.993896 270)
			(unlocked yes)
			(layer "F.Fab")
			(hide yes)
			(effects
				(font
					(size 1.016 1.016)
					(thickness 0.1524)
				)
			)
		)
		(property "Device Type" "R402H16"
			(at 0.064008 -5.517896 270)
			(unlocked yes)
			(layer "F.Fab")
			(hide yes)
			(effects
				(font
					(size 1.016 1.016)
					(thickness 0.1524)
				)
			)
		)
		(duplicate_pad_numbers_are_jumpers no)
		(fp_line
			(start -0.508 -0.9398)
			(end -0.508 0.9398)
			(stroke
				(width 0.1524)
				(type default)
			)
			(layer "F.SilkS")
		)
		(fp_line
			(start 0.508 -0.9398)
			(end -0.508 -0.9398)
			(stroke
				(width 0.1524)
				(type default)
			)
			(layer "F.SilkS")
		)
		(fp_rect
			(start -0.508 0.9398)
			(end 0.508 -0.9398)
			(stroke
				(width 0)
				(type default)
			)
			(fill no)
			(layer "F.CrtYd")
		)
		(fp_rect
			(start -0.508 0.9398)
			(end 0.508 -0.9398)
			(stroke
				(width 0)
				(type default)
			)
			(fill no)
			(layer "F.Fab")
		)
		(pad "1" smd custom
			(at 0 -0.4445 270)
			(size 0.1397 0.1397)
			(layers "F.Cu" "F.Mask" "F.Paste")
			(net "PWM_BUFFER_IN_FAN3_FAN4")
			(options
				(clearance outline)
				(anchor circle)
			)
			(primitives
				(gr_poly
					(pts
						(arc
							(start -0.1778 -0.2794)
							(mid -0.249642 -0.249642)
							(end -0.2794 -0.1778)
						)
						(arc
							(start -0.2794 0.1778)
							(mid -0.249642 0.249642)
							(end -0.1778 0.2794)
						)
						(arc
							(start 0.1778 0.2794)
							(mid 0.249642 0.249642)
							(end 0.2794 0.1778)
						)
						(arc
							(start 0.2794 -0.1778)
							(mid 0.249642 -0.249642)
							(end 0.1778 -0.2794)
						)
					)
					(width 0)
					(fill yes)
				)
			)
		)
		(pad "2" smd custom
			(at 0 0.4445 270)
			(size 0.1397 0.1397)
			(layers "F.Cu" "F.Mask" "F.Paste")
			(net "PWM_BUFFER_IN_FAN5_FAN6")
			(options
				(clearance outline)
				(anchor circle)
			)
			(primitives
				(gr_poly
					(pts
						(arc
							(start -0.1778 -0.2794)
							(mid -0.249642 -0.249642)
							(end -0.2794 -0.1778)
						)
						(arc
							(start -0.2794 0.1778)
							(mid -0.249642 0.249642)
							(end -0.1778 0.2794)
						)
						(arc
							(start 0.1778 0.2794)
							(mid 0.249642 0.249642)
							(end 0.2794 0.1778)
						)
						(arc
							(start 0.2794 -0.1778)
							(mid 0.249642 -0.249642)
							(end 0.1778 -0.2794)
						)
					)
					(width 0)
					(fill yes)
				)
			)
		)
	)
	(footprint ""
		(layer "F.Cu")
		(at 30.3022 -253.8984 180)
		(property "Reference" "R46"
			(at 0 0 180)
			(layer "F.SilkS")
			(hide yes)
			(effects
				(font
					(size 1.27 1.27)
				)
			)
		)
		(property "Value" "0R2J-2-GP"
			(at 0.064008 -3.993896 180)
			(unlocked yes)
			(layer "F.Fab")
			(hide yes)
			(effects
				(font
					(size 1.016 1.016)
					(thickness 0.1524)
				)
			)
		)
		(property "Device Type" "R402H16"
			(at 0.064008 -5.517896 180)
			(unlocked yes)
			(layer "F.Fab")
			(hide yes)
			(effects
				(font
					(size 1.016 1.016)
					(thickness 0.1524)
				)
			)
		)
		(duplicate_pad_numbers_are_jumpers no)
		(fp_line
			(start 0.508 -0.9398)
			(end -0.508 -0.9398)
			(stroke
				(width 0.1524)
				(type default)
			)
			(layer "F.SilkS")
		)
		(fp_line
			(start -0.508 -0.9398)
			(end -0.508 0.9398)
			(stroke
				(width 0.1524)
				(type default)
			)
			(layer "F.SilkS")
		)
		(fp_rect
			(start -0.508 0.9398)
			(end 0.508 -0.9398)
			(stroke
				(width 0)
				(type default)
			)
			(fill no)
			(layer "F.CrtYd")
		)
		(fp_rect
			(start -0.508 0.9398)
			(end 0.508 -0.9398)
			(stroke
				(width 0)
				(type default)
			)
			(fill no)
			(layer "F.Fab")
		)
		(pad "1" smd custom
			(at 0 -0.4445 180)
			(size 0.1397 0.1397)
			(layers "F.Cu" "F.Mask" "F.Paste")
			(net "I2C_C_SCL_EEPROM")
			(options
				(clearance outline)
				(anchor circle)
			)
			(primitives
				(gr_poly
					(pts
						(arc
							(start -0.1778 -0.2794)
							(mid -0.249642 -0.249642)
							(end -0.2794 -0.1778)
						)
						(arc
							(start -0.2794 0.1778)
							(mid -0.249642 0.249642)
							(end -0.1778 0.2794)
						)
						(arc
							(start 0.1778 0.2794)
							(mid 0.249642 0.249642)
							(end 0.2794 0.1778)
						)
						(arc
							(start 0.2794 -0.1778)
							(mid 0.249642 -0.249642)
							(end 0.1778 -0.2794)
						)
					)
					(width 0)
					(fill yes)
				)
			)
		)
		(pad "2" smd custom
			(at 0 0.4445 180)
			(size 0.1397 0.1397)
			(layers "F.Cu" "F.Mask" "F.Paste")
			(net "I2C_C_SCL")
			(options
				(clearance outline)
				(anchor circle)
			)
			(primitives
				(gr_poly
					(pts
						(arc
							(start -0.1778 -0.2794)
							(mid -0.249642 -0.249642)
							(end -0.2794 -0.1778)
						)
						(arc
							(start -0.2794 0.1778)
							(mid -0.249642 0.249642)
							(end -0.1778 0.2794)
						)
						(arc
							(start 0.1778 0.2794)
							(mid 0.249642 0.249642)
							(end 0.2794 0.1778)
						)
						(arc
							(start 0.2794 -0.1778)
							(mid 0.249642 -0.249642)
							(end 0.1778 -0.2794)
						)
					)
					(width 0)
					(fill yes)
				)
			)
		)
	)
	(footprint ""
		(layer "F.Cu")
		(at 7.8232 -81.6102 90)
		(property "Reference" "R29"
			(at 0 0 90)
			(layer "F.SilkS")
			(hide yes)
			(effects
				(font
					(size 1.27 1.27)
				)
			)
		)
		(property "Value" "33R2F-3-GP"
			(at 0.064008 -3.993896 90)
			(unlocked yes)
			(layer "F.Fab")
			(hide yes)
			(effects
				(font
					(size 1.016 1.016)
					(thickness 0.1524)
				)
			)
		)
		(property "Device Type" "R402H16"
			(at 0.064008 -5.517896 90)
			(unlocked yes)
			(layer "F.Fab")
			(hide yes)
			(effects
				(font
					(size 1.016 1.016)
					(thickness 0.1524)
				)
			)
		)
		(duplicate_pad_numbers_are_jumpers no)
		(fp_line
			(start 0.508 -0.9398)
			(end -0.508 -0.9398)
			(stroke
				(width 0.1524)
				(type default)
			)
			(layer "F.SilkS")
		)
		(fp_line
			(start -0.508 -0.9398)
			(end -0.508 0.9398)
			(stroke
				(width 0.1524)
				(type default)
			)
			(layer "F.SilkS")
		)
		(fp_rect
			(start -0.508 0.9398)
			(end 0.508 -0.9398)
			(stroke
				(width 0)
				(type default)
			)
			(fill no)
			(layer "F.CrtYd")
		)
		(fp_rect
			(start -0.508 0.9398)
			(end 0.508 -0.9398)
			(stroke
				(width 0)
				(type default)
			)
			(fill no)
			(layer "F.Fab")
		)
		(pad "1" smd custom
			(at 0 -0.4445 90)
			(size 0.1397 0.1397)
			(layers "F.Cu" "F.Mask" "F.Paste")
			(net "P3V3")
			(options
				(clearance outline)
				(anchor circle)
			)
			(primitives
				(gr_poly
					(pts
						(arc
							(start -0.1778 -0.2794)
							(mid -0.249642 -0.249642)
							(end -0.2794 -0.1778)
						)
						(arc
							(start -0.2794 0.1778)
							(mid -0.249642 0.249642)
							(end -0.1778 0.2794)
						)
						(arc
							(start 0.1778 0.2794)
							(mid 0.249642 0.249642)
							(end 0.2794 0.1778)
						)
						(arc
							(start 0.2794 -0.1778)
							(mid 0.249642 -0.249642)
							(end 0.1778 -0.2794)
						)
					)
					(width 0)
					(fill yes)
				)
			)
		)
		(pad "2" smd custom
			(at 0 0.4445 90)
			(size 0.1397 0.1397)
			(layers "F.Cu" "F.Mask" "F.Paste")
			(net "LED_DR_LED4_BLUE")
			(options
				(clearance outline)
				(anchor circle)
			)
			(primitives
				(gr_poly
					(pts
						(arc
							(start -0.1778 -0.2794)
							(mid -0.249642 -0.249642)
							(end -0.2794 -0.1778)
						)
						(arc
							(start -0.2794 0.1778)
							(mid -0.249642 0.249642)
							(end -0.1778 0.2794)
						)
						(arc
							(start 0.1778 0.2794)
							(mid 0.249642 0.249642)
							(end 0.2794 0.1778)
						)
						(arc
							(start 0.2794 -0.1778)
							(mid 0.249642 -0.249642)
							(end 0.1778 -0.2794)
						)
					)
					(width 0)
					(fill yes)
				)
			)
		)
	)
	(footprint ""
		(layer "F.Cu")
		(at 8.3058 -64.8208)
		(property "Reference" "R25"
			(at 0 0 0)
			(layer "F.SilkS")
			(hide yes)
			(effects
				(font
					(size 1.27 1.27)
				)
			)
		)
		(property "Value" "33R2F-3-GP"
			(at 0.064008 -3.993896 0)
			(unlocked yes)
			(layer "F.Fab")
			(hide yes)
			(effects
				(font
					(size 1.016 1.016)
					(thickness 0.1524)
				)
			)
		)
		(property "Device Type" "R402H16"
			(at 0.064008 -5.517896 0)
			(unlocked yes)
			(layer "F.Fab")
			(hide yes)
			(effects
				(font
					(size 1.016 1.016)
					(thickness 0.1524)
				)
			)
		)
		(duplicate_pad_numbers_are_jumpers no)
		(fp_line
			(start -0.508 -0.9398)
			(end -0.508 0.9398)
			(stroke
				(width 0.1524)
				(type default)
			)
			(layer "F.SilkS")
		)
		(fp_line
			(start 0.508 -0.9398)
			(end -0.508 -0.9398)
			(stroke
				(width 0.1524)
				(type default)
			)
			(layer "F.SilkS")
		)
		(fp_rect
			(start -0.508 0.9398)
			(end 0.508 -0.9398)
			(stroke
				(width 0)
				(type default)
			)
			(fill no)
			(layer "F.CrtYd")
		)
		(fp_rect
			(start -0.508 0.9398)
			(end 0.508 -0.9398)
			(stroke
				(width 0)
				(type default)
			)
			(fill no)
			(layer "F.Fab")
		)
		(pad "1" smd custom
			(at 0 -0.4445)
			(size 0.1397 0.1397)
			(layers "F.Cu" "F.Mask" "F.Paste")
			(net "P3V3")
			(options
				(clearance outline)
				(anchor circle)
			)
			(primitives
				(gr_poly
					(pts
						(arc
							(start -0.1778 -0.2794)
							(mid -0.249642 -0.249642)
							(end -0.2794 -0.1778)
						)
						(arc
							(start -0.2794 0.1778)
							(mid -0.249642 0.249642)
							(end -0.1778 0.2794)
						)
						(arc
							(start 0.1778 0.2794)
							(mid 0.249642 0.249642)
							(end 0.2794 0.1778)
						)
						(arc
							(start 0.2794 -0.1778)
							(mid 0.249642 -0.249642)
							(end 0.1778 -0.2794)
						)
					)
					(width 0)
					(fill yes)
				)
			)
		)
		(pad "2" smd custom
			(at 0 0.4445)
			(size 0.1397 0.1397)
			(layers "F.Cu" "F.Mask" "F.Paste")
			(net "LED_DR_LED5_BLUE")
			(options
				(clearance outline)
				(anchor circle)
			)
			(primitives
				(gr_poly
					(pts
						(arc
							(start -0.1778 -0.2794)
							(mid -0.249642 -0.249642)
							(end -0.2794 -0.1778)
						)
						(arc
							(start -0.2794 0.1778)
							(mid -0.249642 0.249642)
							(end -0.1778 0.2794)
						)
						(arc
							(start 0.1778 0.2794)
							(mid 0.249642 0.249642)
							(end 0.2794 0.1778)
						)
						(arc
							(start 0.2794 -0.1778)
							(mid 0.249642 -0.249642)
							(end 0.1778 -0.2794)
						)
					)
					(width 0)
					(fill yes)
				)
			)
		)
	)
	(footprint ""
		(layer "F.Cu")
		(at 39.064184 -360.4768 90)
		(property "Reference" "PR59"
			(at 0 0 90)
			(layer "F.SilkS")
			(hide yes)
			(effects
				(font
					(size 1.27 1.27)
				)
			)
		)
		(property "Value" "4K7R2F-GP"
			(at 0.064008 -3.993896 90)
			(unlocked yes)
			(layer "F.Fab")
			(hide yes)
			(effects
				(font
					(size 1.016 1.016)
					(thickness 0.1524)
				)
			)
		)
		(property "Device Type" "R402H16"
			(at 0.064008 -5.517896 90)
			(unlocked yes)
			(layer "F.Fab")
			(hide yes)
			(effects
				(font
					(size 1.016 1.016)
					(thickness 0.1524)
				)
			)
		)
		(duplicate_pad_numbers_are_jumpers no)
		(fp_line
			(start 0.508 -0.9398)
			(end -0.508 -0.9398)
			(stroke
				(width 0.1524)
				(type default)
			)
			(layer "F.SilkS")
		)
		(fp_line
			(start -0.508 -0.9398)
			(end -0.508 0.9398)
			(stroke
				(width 0.1524)
				(type default)
			)
			(layer "F.SilkS")
		)
		(fp_rect
			(start -0.508 0.9398)
			(end 0.508 -0.9398)
			(stroke
				(width 0)
				(type default)
			)
			(fill no)
			(layer "F.CrtYd")
		)
		(fp_rect
			(start -0.508 0.9398)
			(end 0.508 -0.9398)
			(stroke
				(width 0)
				(type default)
			)
			(fill no)
			(layer "F.Fab")
		)
		(pad "1" smd custom
			(at 0 -0.4445 90)
			(size 0.1397 0.1397)
			(layers "F.Cu" "F.Mask" "F.Paste")
			(net "P12V_AUX")
			(options
				(clearance outline)
				(anchor circle)
			)
			(primitives
				(gr_poly
					(pts
						(arc
							(start -0.1778 -0.2794)
							(mid -0.249642 -0.249642)
							(end -0.2794 -0.1778)
						)
						(arc
							(start -0.2794 0.1778)
							(mid -0.249642 0.249642)
							(end -0.1778 0.2794)
						)
						(arc
							(start 0.1778 0.2794)
							(mid 0.249642 0.249642)
							(end 0.2794 0.1778)
						)
						(arc
							(start 0.2794 -0.1778)
							(mid 0.249642 -0.249642)
							(end 0.1778 -0.2794)
						)
					)
					(width 0)
					(fill yes)
				)
			)
		)
		(pad "2" smd custom
			(at 0 0.4445 90)
			(size 0.1397 0.1397)
			(layers "F.Cu" "F.Mask" "F.Paste")
			(net "OTP_RETRY_B")
			(options
				(clearance outline)
				(anchor circle)
			)
			(primitives
				(gr_poly
					(pts
						(arc
							(start -0.1778 -0.2794)
							(mid -0.249642 -0.249642)
							(end -0.2794 -0.1778)
						)
						(arc
							(start -0.2794 0.1778)
							(mid -0.249642 0.249642)
							(end -0.1778 0.2794)
						)
						(arc
							(start 0.1778 0.2794)
							(mid 0.249642 0.249642)
							(end 0.2794 0.1778)
						)
						(arc
							(start 0.2794 -0.1778)
							(mid 0.249642 -0.249642)
							(end 0.1778 -0.2794)
						)
					)
					(width 0)
					(fill yes)
				)
			)
		)
	)
	(footprint ""
		(layer "F.Cu")
		(at 5.4864 -449.4784 -90)
		(property "Reference" "R104"
			(at 0 0 270)
			(layer "F.SilkS")
			(hide yes)
			(effects
				(font
					(size 1.27 1.27)
				)
			)
		)
		(property "Value" "10KR2F-2-GP"
			(at 0.064008 -3.993896 270)
			(unlocked yes)
			(layer "F.Fab")
			(hide yes)
			(effects
				(font
					(size 1.016 1.016)
					(thickness 0.1524)
				)
			)
		)
		(property "Device Type" "R402H16"
			(at 0.064008 -5.517896 270)
			(unlocked yes)
			(layer "F.Fab")
			(hide yes)
			(effects
				(font
					(size 1.016 1.016)
					(thickness 0.1524)
				)
			)
		)
		(duplicate_pad_numbers_are_jumpers no)
		(fp_line
			(start -0.508 -0.9398)
			(end -0.508 0.9398)
			(stroke
				(width 0.1524)
				(type default)
			)
			(layer "F.SilkS")
		)
		(fp_line
			(start 0.508 -0.9398)
			(end -0.508 -0.9398)
			(stroke
				(width 0.1524)
				(type default)
			)
			(layer "F.SilkS")
		)
		(fp_rect
			(start -0.508 0.9398)
			(end 0.508 -0.9398)
			(stroke
				(width 0)
				(type default)
			)
			(fill no)
			(layer "F.CrtYd")
		)
		(fp_rect
			(start -0.508 0.9398)
			(end 0.508 -0.9398)
			(stroke
				(width 0)
				(type default)
			)
			(fill no)
			(layer "F.Fab")
		)
		(pad "1" smd custom
			(at 0 -0.4445 270)
			(size 0.1397 0.1397)
			(layers "F.Cu" "F.Mask" "F.Paste")
			(net "FANIN_1")
			(options
				(clearance outline)
				(anchor circle)
			)
			(primitives
				(gr_poly
					(pts
						(arc
							(start -0.1778 -0.2794)
							(mid -0.249642 -0.249642)
							(end -0.2794 -0.1778)
						)
						(arc
							(start -0.2794 0.1778)
							(mid -0.249642 0.249642)
							(end -0.1778 0.2794)
						)
						(arc
							(start 0.1778 0.2794)
							(mid 0.249642 0.249642)
							(end 0.2794 0.1778)
						)
						(arc
							(start 0.2794 -0.1778)
							(mid 0.249642 -0.249642)
							(end 0.1778 -0.2794)
						)
					)
					(width 0)
					(fill yes)
				)
			)
		)
		(pad "2" smd custom
			(at 0 0.4445 270)
			(size 0.1397 0.1397)
			(layers "F.Cu" "F.Mask" "F.Paste")
			(net "GND")
			(options
				(clearance outline)
				(anchor circle)
			)
			(primitives
				(gr_poly
					(pts
						(arc
							(start -0.1778 -0.2794)
							(mid -0.249642 -0.249642)
							(end -0.2794 -0.1778)
						)
						(arc
							(start -0.2794 0.1778)
							(mid -0.249642 0.249642)
							(end -0.1778 0.2794)
						)
						(arc
							(start 0.1778 0.2794)
							(mid 0.249642 0.249642)
							(end 0.2794 0.1778)
						)
						(arc
							(start 0.2794 -0.1778)
							(mid 0.249642 -0.249642)
							(end 0.1778 -0.2794)
						)
					)
					(width 0)
					(fill yes)
				)
			)
		)
	)
	(footprint ""
		(layer "F.Cu")
		(at 34.99231 -167.734234)
		(property "Reference" "R9"
			(at 0 0 0)
			(layer "F.SilkS")
			(hide yes)
			(effects
				(font
					(size 1.27 1.27)
				)
			)
		)
		(property "Value" "100KR2J-1-GP"
			(at 0.064008 -3.993896 0)
			(unlocked yes)
			(layer "F.Fab")
			(hide yes)
			(effects
				(font
					(size 1.016 1.016)
					(thickness 0.1524)
				)
			)
		)
		(property "Device Type" "R402H16"
			(at 0.064008 -5.517896 0)
			(unlocked yes)
			(layer "F.Fab")
			(hide yes)
			(effects
				(font
					(size 1.016 1.016)
					(thickness 0.1524)
				)
			)
		)
		(duplicate_pad_numbers_are_jumpers no)
		(fp_line
			(start -0.508 -0.9398)
			(end -0.508 0.9398)
			(stroke
				(width 0.1524)
				(type default)
			)
			(layer "F.SilkS")
		)
		(fp_line
			(start 0.508 -0.9398)
			(end -0.508 -0.9398)
			(stroke
				(width 0.1524)
				(type default)
			)
			(layer "F.SilkS")
		)
		(fp_rect
			(start -0.508 0.9398)
			(end 0.508 -0.9398)
			(stroke
				(width 0)
				(type default)
			)
			(fill no)
			(layer "F.CrtYd")
		)
		(fp_rect
			(start -0.508 0.9398)
			(end 0.508 -0.9398)
			(stroke
				(width 0)
				(type default)
			)
			(fill no)
			(layer "F.Fab")
		)
		(pad "1" smd custom
			(at 0 -0.4445)
			(size 0.1397 0.1397)
			(layers "F.Cu" "F.Mask" "F.Paste")
			(net "P3V3")
			(options
				(clearance outline)
				(anchor circle)
			)
			(primitives
				(gr_poly
					(pts
						(arc
							(start -0.1778 -0.2794)
							(mid -0.249642 -0.249642)
							(end -0.2794 -0.1778)
						)
						(arc
							(start -0.2794 0.1778)
							(mid -0.249642 0.249642)
							(end -0.1778 0.2794)
						)
						(arc
							(start 0.1778 0.2794)
							(mid 0.249642 0.249642)
							(end 0.2794 0.1778)
						)
						(arc
							(start 0.2794 -0.1778)
							(mid 0.249642 -0.249642)
							(end 0.1778 -0.2794)
						)
					)
					(width 0)
					(fill yes)
				)
			)
		)
		(pad "2" smd custom
			(at 0 0.4445)
			(size 0.1397 0.1397)
			(layers "F.Cu" "F.Mask" "F.Paste")
			(net "NCT7904_ADR")
			(options
				(clearance outline)
				(anchor circle)
			)
			(primitives
				(gr_poly
					(pts
						(arc
							(start -0.1778 -0.2794)
							(mid -0.249642 -0.249642)
							(end -0.2794 -0.1778)
						)
						(arc
							(start -0.2794 0.1778)
							(mid -0.249642 0.249642)
							(end -0.1778 0.2794)
						)
						(arc
							(start 0.1778 0.2794)
							(mid 0.249642 0.249642)
							(end 0.2794 0.1778)
						)
						(arc
							(start 0.2794 -0.1778)
							(mid 0.249642 -0.249642)
							(end 0.1778 -0.2794)
						)
					)
					(width 0)
					(fill yes)
				)
			)
		)
	)
	(footprint ""
		(layer "F.Cu")
		(at 31.7246 -184.2516)
		(property "Reference" "PR117"
			(at 0 0 0)
			(layer "F.SilkS")
			(hide yes)
			(effects
				(font
					(size 1.27 1.27)
				)
			)
		)
		(property "Value" "3K3R3F-GP"
			(at -0.0254 -2.5146 0)
			(unlocked yes)
			(layer "F.Fab")
			(hide yes)
			(effects
				(font
					(size 1.016 1.016)
					(thickness 0.1524)
				)
			)
		)
		(property "Device Type" "R603H22"
			(at -0.0254 -4.0386 0)
			(unlocked yes)
			(layer "F.Fab")
			(hide yes)
			(effects
				(font
					(size 1.016 1.016)
					(thickness 0.1524)
				)
			)
		)
		(duplicate_pad_numbers_are_jumpers no)
		(fp_line
			(start -0.4826 0)
			(end -0.2032 0)
			(stroke
				(width 0.2032)
				(type default)
			)
			(layer "F.SilkS")
		)
		(fp_line
			(start 0.2032 0)
			(end 0.4826 0)
			(stroke
				(width 0.2032)
				(type default)
			)
			(layer "F.SilkS")
		)
		(fp_rect
			(start -0.5842 1.3335)
			(end 0.5842 -1.3335)
			(stroke
				(width 0)
				(type default)
			)
			(fill no)
			(layer "F.CrtYd")
		)
		(fp_rect
			(start -0.5842 1.3335)
			(end 0.5842 -1.3335)
			(stroke
				(width 0)
				(type default)
			)
			(fill no)
			(layer "F.Fab")
		)
		(pad "1" smd custom
			(at 0 -0.762)
			(size 0.2159 0.2159)
			(layers "F.Cu" "F.Mask" "F.Paste")
			(net "P12V_AUX")
			(options
				(clearance outline)
				(anchor circle)
			)
			(primitives
				(gr_poly
					(pts
						(arc
							(start -0.3302 -0.4318)
							(mid -0.402042 -0.402042)
							(end -0.4318 -0.3302)
						)
						(arc
							(start -0.4318 0.3302)
							(mid -0.402042 0.402042)
							(end -0.3302 0.4318)
						)
						(arc
							(start 0.3302 0.4318)
							(mid 0.402042 0.402042)
							(end 0.4318 0.3302)
						)
						(arc
							(start 0.4318 -0.3302)
							(mid 0.402042 -0.402042)
							(end 0.3302 -0.4318)
						)
					)
					(width 0)
					(fill yes)
				)
			)
		)
		(pad "2" smd custom
			(at 0 0.762)
			(size 0.2159 0.2159)
			(layers "F.Cu" "F.Mask" "F.Paste")
			(net "P3V3_AUX_BJT_B")
			(options
				(clearance outline)
				(anchor circle)
			)
			(primitives
				(gr_poly
					(pts
						(arc
							(start -0.3302 -0.4318)
							(mid -0.402042 -0.402042)
							(end -0.4318 -0.3302)
						)
						(arc
							(start -0.4318 0.3302)
							(mid -0.402042 0.402042)
							(end -0.3302 0.4318)
						)
						(arc
							(start 0.3302 0.4318)
							(mid 0.402042 0.402042)
							(end 0.4318 0.3302)
						)
						(arc
							(start 0.4318 -0.3302)
							(mid 0.402042 -0.402042)
							(end 0.3302 -0.4318)
						)
					)
					(width 0)
					(fill yes)
				)
			)
		)
	)
	(footprint ""
		(layer "F.Cu")
		(at 16.052292 -289.636962 180)
		(property "Reference" "R102"
			(at 0 0 180)
			(layer "F.SilkS")
			(hide yes)
			(effects
				(font
					(size 1.27 1.27)
				)
			)
		)
		(property "Value" "10KR2F-2-GP"
			(at 0.064008 -3.993896 180)
			(unlocked yes)
			(layer "F.Fab")
			(hide yes)
			(effects
				(font
					(size 1.016 1.016)
					(thickness 0.1524)
				)
			)
		)
		(property "Device Type" "R402H16"
			(at 0.064008 -5.517896 180)
			(unlocked yes)
			(layer "F.Fab")
			(hide yes)
			(effects
				(font
					(size 1.016 1.016)
					(thickness 0.1524)
				)
			)
		)
		(duplicate_pad_numbers_are_jumpers no)
		(fp_line
			(start 0.508 -0.9398)
			(end -0.508 -0.9398)
			(stroke
				(width 0.1524)
				(type default)
			)
			(layer "F.SilkS")
		)
		(fp_line
			(start -0.508 -0.9398)
			(end -0.508 0.9398)
			(stroke
				(width 0.1524)
				(type default)
			)
			(layer "F.SilkS")
		)
		(fp_rect
			(start -0.508 0.9398)
			(end 0.508 -0.9398)
			(stroke
				(width 0)
				(type default)
			)
			(fill no)
			(layer "F.CrtYd")
		)
		(fp_rect
			(start -0.508 0.9398)
			(end 0.508 -0.9398)
			(stroke
				(width 0)
				(type default)
			)
			(fill no)
			(layer "F.Fab")
		)
		(pad "1" smd custom
			(at 0 -0.4445 180)
			(size 0.1397 0.1397)
			(layers "F.Cu" "F.Mask" "F.Paste")
			(net "FANIN_3")
			(options
				(clearance outline)
				(anchor circle)
			)
			(primitives
				(gr_poly
					(pts
						(arc
							(start -0.1778 -0.2794)
							(mid -0.249642 -0.249642)
							(end -0.2794 -0.1778)
						)
						(arc
							(start -0.2794 0.1778)
							(mid -0.249642 0.249642)
							(end -0.1778 0.2794)
						)
						(arc
							(start 0.1778 0.2794)
							(mid 0.249642 0.249642)
							(end 0.2794 0.1778)
						)
						(arc
							(start 0.2794 -0.1778)
							(mid 0.249642 -0.249642)
							(end 0.1778 -0.2794)
						)
					)
					(width 0)
					(fill yes)
				)
			)
		)
		(pad "2" smd custom
			(at 0 0.4445 180)
			(size 0.1397 0.1397)
			(layers "F.Cu" "F.Mask" "F.Paste")
			(net "GND")
			(options
				(clearance outline)
				(anchor circle)
			)
			(primitives
				(gr_poly
					(pts
						(arc
							(start -0.1778 -0.2794)
							(mid -0.249642 -0.249642)
							(end -0.2794 -0.1778)
						)
						(arc
							(start -0.2794 0.1778)
							(mid -0.249642 0.249642)
							(end -0.1778 0.2794)
						)
						(arc
							(start 0.1778 0.2794)
							(mid 0.249642 0.249642)
							(end 0.2794 0.1778)
						)
						(arc
							(start 0.2794 -0.1778)
							(mid 0.249642 -0.249642)
							(end 0.1778 -0.2794)
						)
					)
					(width 0)
					(fill yes)
				)
			)
		)
	)
	(footprint ""
		(layer "F.Cu")
		(at 38.024816 -354.076 -90)
		(property "Reference" "R363"
			(at 0 0 270)
			(layer "F.SilkS")
			(hide yes)
			(effects
				(font
					(size 1.27 1.27)
				)
			)
		)
		(property "Value" "5K1R2F-2-GP"
			(at 0.064008 -3.993896 270)
			(unlocked yes)
			(layer "F.Fab")
			(hide yes)
			(effects
				(font
					(size 1.016 1.016)
					(thickness 0.1524)
				)
			)
		)
		(property "Device Type" "R402H16"
			(at 0.064008 -5.517896 270)
			(unlocked yes)
			(layer "F.Fab")
			(hide yes)
			(effects
				(font
					(size 1.016 1.016)
					(thickness 0.1524)
				)
			)
		)
		(duplicate_pad_numbers_are_jumpers no)
		(fp_line
			(start -0.508 -0.9398)
			(end -0.508 0.9398)
			(stroke
				(width 0.1524)
				(type default)
			)
			(layer "F.SilkS")
		)
		(fp_line
			(start 0.508 -0.9398)
			(end -0.508 -0.9398)
			(stroke
				(width 0.1524)
				(type default)
			)
			(layer "F.SilkS")
		)
		(fp_rect
			(start -0.508 0.9398)
			(end 0.508 -0.9398)
			(stroke
				(width 0)
				(type default)
			)
			(fill no)
			(layer "F.CrtYd")
		)
		(fp_rect
			(start -0.508 0.9398)
			(end 0.508 -0.9398)
			(stroke
				(width 0)
				(type default)
			)
			(fill no)
			(layer "F.Fab")
		)
		(pad "1" smd custom
			(at 0 -0.4445 270)
			(size 0.1397 0.1397)
			(layers "F.Cu" "F.Mask" "F.Paste")
			(net "OTP_RETRY_B")
			(options
				(clearance outline)
				(anchor circle)
			)
			(primitives
				(gr_poly
					(pts
						(arc
							(start -0.1778 -0.2794)
							(mid -0.249642 -0.249642)
							(end -0.2794 -0.1778)
						)
						(arc
							(start -0.2794 0.1778)
							(mid -0.249642 0.249642)
							(end -0.1778 0.2794)
						)
						(arc
							(start 0.1778 0.2794)
							(mid 0.249642 0.249642)
							(end 0.2794 0.1778)
						)
						(arc
							(start 0.2794 -0.1778)
							(mid 0.249642 -0.249642)
							(end 0.1778 -0.2794)
						)
					)
					(width 0)
					(fill yes)
				)
			)
		)
		(pad "2" smd custom
			(at 0 0.4445 270)
			(size 0.1397 0.1397)
			(layers "F.Cu" "F.Mask" "F.Paste")
			(net "GND")
			(options
				(clearance outline)
				(anchor circle)
			)
			(primitives
				(gr_poly
					(pts
						(arc
							(start -0.1778 -0.2794)
							(mid -0.249642 -0.249642)
							(end -0.2794 -0.1778)
						)
						(arc
							(start -0.2794 0.1778)
							(mid -0.249642 0.249642)
							(end -0.1778 0.2794)
						)
						(arc
							(start 0.1778 0.2794)
							(mid 0.249642 0.249642)
							(end 0.2794 0.1778)
						)
						(arc
							(start 0.2794 -0.1778)
							(mid 0.249642 -0.249642)
							(end 0.1778 -0.2794)
						)
					)
					(width 0)
					(fill yes)
				)
			)
		)
	)
	(footprint ""
		(layer "F.Cu")
		(at 40.132 -122.428)
		(property "Reference" "PR63"
			(at 0 0 0)
			(layer "F.SilkS")
			(hide yes)
			(effects
				(font
					(size 1.27 1.27)
				)
			)
		)
		(property "Value" "D002R2512F-GP"
			(at -3.228594 -1.194054 0)
			(unlocked yes)
			(layer "F.Fab")
			(hide yes)
			(effects
				(font
					(size 1.016 1.016)
					(thickness 0.1524)
				)
			)
		)
		(property "Device Type" "R2512-2H32"
			(at -3.228594 -2.718054 0)
			(unlocked yes)
			(layer "F.Fab")
			(hide yes)
			(effects
				(font
					(size 1.016 1.016)
					(thickness 0.1524)
				)
			)
		)
		(duplicate_pad_numbers_are_jumpers no)
		(fp_line
			(start -1.9685 -3.81)
			(end 1.9685 -3.81)
			(stroke
				(width 0.1524)
				(type default)
			)
			(layer "F.SilkS")
		)
		(fp_line
			(start -1.9685 3.81)
			(end -1.9685 -3.81)
			(stroke
				(width 0.1524)
				(type default)
			)
			(layer "F.SilkS")
		)
		(fp_line
			(start 1.9685 -3.81)
			(end 1.9685 3.81)
			(stroke
				(width 0.1524)
				(type default)
			)
			(layer "F.SilkS")
		)
		(fp_line
			(start 1.9685 3.81)
			(end -1.9685 3.81)
			(stroke
				(width 0.1524)
				(type default)
			)
			(layer "F.SilkS")
		)
		(fp_rect
			(start -1.5875 3.175)
			(end 1.5875 -3.175)
			(stroke
				(width 0)
				(type default)
			)
			(fill no)
			(layer "F.CrtYd")
		)
		(fp_poly
			(pts
				(xy -2.2225 3.8862) (xy -2.2225 0.00254) (xy -1.5875 0.00254) (xy -1.5875 3.175) (xy 1.5875 3.175)
				(xy 1.5875 -3.175) (xy -1.5875 -3.175) (xy -1.5875 -0.00254) (xy -2.2225 -0.00254) (xy -2.2225 -3.8862)
				(xy 2.2225 -3.8862) (xy 2.2225 3.8862)
			)
			(stroke
				(width 0)
				(type default)
			)
			(fill no)
			(layer "F.CrtYd")
		)
		(fp_rect
			(start -2.2225 3.8862)
			(end 2.2225 -3.8862)
			(stroke
				(width 0)
				(type default)
			)
			(fill no)
			(layer "F.Fab")
		)
		(pad "1" smd rect
			(at 0 -2.273808)
			(size 3.429 2.5654)
			(layers "F.Cu" "F.Mask" "F.Paste")
			(net "P12V")
		)
		(pad "2" smd rect
			(at 0 2.273808)
			(size 3.429 2.5654)
			(layers "F.Cu" "F.Mask" "F.Paste")
			(net "P12VL_NET")
		)
	)
	(footprint ""
		(layer "F.Cu")
		(at 7.112 -452.374 90)
		(property "Reference" "D11"
			(at 0 0 90)
			(layer "F.SilkS")
			(hide yes)
			(effects
				(font
					(size 1.27 1.27)
				)
			)
		)
		(property "Value" "BAS16H-GP"
			(at 0 -5.5372 90)
			(unlocked yes)
			(layer "F.Fab")
			(hide yes)
			(effects
				(font
					(size 1.016 1.016)
					(thickness 0.1524)
				)
			)
		)
		(property "Device Type" "SOD123AKH48"
			(at 0 -7.0612 90)
			(unlocked yes)
			(layer "F.Fab")
			(hide yes)
			(effects
				(font
					(size 1.016 1.016)
					(thickness 0.1524)
				)
			)
		)
		(duplicate_pad_numbers_are_jumpers no)
		(fp_line
			(start 1.016 -2.667)
			(end -1.016 -2.667)
			(stroke
				(width 0.1524)
				(type default)
			)
			(layer "F.SilkS")
		)
		(fp_line
			(start -1.016 -2.667)
			(end -1.016 2.667)
			(stroke
				(width 0.1524)
				(type default)
			)
			(layer "F.SilkS")
		)
		(fp_line
			(start 1.016 2.667)
			(end 1.016 -2.667)
			(stroke
				(width 0.1524)
				(type default)
			)
			(layer "F.SilkS")
		)
		(fp_line
			(start -1.016 2.667)
			(end 1.016 2.667)
			(stroke
				(width 0.1524)
				(type default)
			)
			(layer "F.SilkS")
		)
		(fp_line
			(start 0.889 2.921)
			(end -0.889 2.921)
			(stroke
				(width 0.508)
				(type default)
			)
			(layer "F.SilkS")
		)
		(fp_rect
			(start -1.143 3.175)
			(end 1.143 -2.794)
			(stroke
				(width 0)
				(type default)
			)
			(fill no)
			(layer "F.CrtYd")
		)
		(fp_poly
			(pts
				(xy -1.143 -2.794) (xy 1.143 -2.794) (xy 1.143 3.175) (xy -1.143 3.175)
			)
			(stroke
				(width 0)
				(type default)
			)
			(fill no)
			(layer "F.Fab")
		)
		(pad "A" smd rect
			(at 0 -1.6891 90)
			(size 0.889 1.397)
			(layers "F.Cu" "F.Mask" "F.Paste")
			(net "FAN_TACH1")
		)
		(pad "K" smd rect
			(at 0 1.6891 90)
			(size 0.889 1.397)
			(layers "F.Cu" "F.Mask" "F.Paste")
			(net "P12V")
		)
	)
	(footprint ""
		(layer "F.Cu")
		(at 8.4836 -62.7126 -90)
		(property "Reference" "R122"
			(at 0 0 270)
			(layer "F.SilkS")
			(hide yes)
			(effects
				(font
					(size 1.27 1.27)
				)
			)
		)
		(property "Value" "1K8R6J-GP"
			(at -0.0508 -4.8514 270)
			(unlocked yes)
			(layer "F.Fab")
			(hide yes)
			(effects
				(font
					(size 1.016 1.016)
					(thickness 0.1524)
				)
			)
		)
		(property "Device Type" "R1206H28"
			(at 0 -6.3754 270)
			(unlocked yes)
			(layer "F.Fab")
			(hide yes)
			(effects
				(font
					(size 1.016 1.016)
					(thickness 0.1524)
				)
			)
		)
		(duplicate_pad_numbers_are_jumpers no)
		(fp_line
			(start -1.016 2.2352)
			(end -1.016 -2.2352)
			(stroke
				(width 0.1524)
				(type default)
			)
			(layer "F.SilkS")
		)
		(fp_line
			(start 1.016 2.2352)
			(end -1.016 2.2352)
			(stroke
				(width 0.1524)
				(type default)
			)
			(layer "F.SilkS")
		)
		(fp_line
			(start -1.016 -2.2352)
			(end 1.016 -2.2352)
			(stroke
				(width 0.1524)
				(type default)
			)
			(layer "F.SilkS")
		)
		(fp_line
			(start 1.016 -2.2352)
			(end 1.016 2.2352)
			(stroke
				(width 0.1524)
				(type default)
			)
			(layer "F.SilkS")
		)
		(fp_rect
			(start -1.0922 2.3114)
			(end 1.0922 -2.3114)
			(stroke
				(width 0)
				(type default)
			)
			(fill no)
			(layer "F.CrtYd")
		)
		(fp_poly
			(pts
				(xy -1.0922 -2.3114) (xy 1.0922 -2.3114) (xy 1.0922 2.3114) (xy -1.0922 2.3114)
			)
			(stroke
				(width 0)
				(type default)
			)
			(fill no)
			(layer "F.Fab")
		)
		(pad "1" smd rect
			(at 0 -1.397 270)
			(size 1.651 1.27)
			(layers "F.Cu" "F.Mask" "F.Paste")
			(net "P12V")
		)
		(pad "2" smd rect
			(at 0 1.397 270)
			(size 1.651 1.27)
			(layers "F.Cu" "F.Mask" "F.Paste")
			(net "LED_DR_LED5_BLUE")
		)
	)
	(footprint ""
		(layer "F.Cu")
		(at 26.289 -248.158 180)
		(property "Reference" "PC42"
			(at 0 0 180)
			(layer "F.SilkS")
			(hide yes)
			(effects
				(font
					(size 1.27 1.27)
				)
			)
		)
		(property "Value" "SC22P50V3JN-DLGP"
			(at 0 -2.8194 180)
			(unlocked yes)
			(layer "F.Fab")
			(hide yes)
			(effects
				(font
					(size 1.016 1.016)
					(thickness 0.1524)
				)
			)
		)
		(property "Device Type" "C603H36"
			(at 0 -4.3434 180)
			(unlocked yes)
			(layer "F.Fab")
			(hide yes)
			(effects
				(font
					(size 1.016 1.016)
					(thickness 0.1524)
				)
			)
		)
		(duplicate_pad_numbers_are_jumpers no)
		(fp_line
			(start 0.508 0)
			(end -0.508 0)
			(stroke
				(width 0.2032)
				(type default)
			)
			(layer "F.SilkS")
		)
		(fp_rect
			(start -0.5842 1.3335)
			(end 0.5842 -1.3335)
			(stroke
				(width 0)
				(type default)
			)
			(fill no)
			(layer "F.CrtYd")
		)
		(fp_rect
			(start -0.5842 1.3335)
			(end 0.5842 -1.3335)
			(stroke
				(width 0)
				(type default)
			)
			(fill no)
			(layer "F.Fab")
		)
		(pad "1" smd custom
			(at 0 -0.762 180)
			(size 0.2159 0.2159)
			(layers "F.Cu" "F.Mask" "F.Paste")
			(net "P3V3_LX_COPPER")
			(options
				(clearance outline)
				(anchor circle)
			)
			(primitives
				(gr_poly
					(pts
						(arc
							(start -0.3302 -0.4318)
							(mid -0.402042 -0.402042)
							(end -0.4318 -0.3302)
						)
						(arc
							(start -0.4318 0.3302)
							(mid -0.402042 0.402042)
							(end -0.3302 0.4318)
						)
						(arc
							(start 0.3302 0.4318)
							(mid 0.402042 0.402042)
							(end 0.4318 0.3302)
						)
						(arc
							(start 0.4318 -0.3302)
							(mid 0.402042 -0.402042)
							(end 0.3302 -0.4318)
						)
					)
					(width 0)
					(fill yes)
				)
			)
		)
		(pad "2" smd custom
			(at 0 0.762 180)
			(size 0.2159 0.2159)
			(layers "F.Cu" "F.Mask" "F.Paste")
			(net "P3V3_FB")
			(options
				(clearance outline)
				(anchor circle)
			)
			(primitives
				(gr_poly
					(pts
						(arc
							(start -0.3302 -0.4318)
							(mid -0.402042 -0.402042)
							(end -0.4318 -0.3302)
						)
						(arc
							(start -0.4318 0.3302)
							(mid -0.402042 0.402042)
							(end -0.3302 0.4318)
						)
						(arc
							(start 0.3302 0.4318)
							(mid 0.402042 0.402042)
							(end 0.4318 0.3302)
						)
						(arc
							(start 0.4318 -0.3302)
							(mid 0.402042 -0.402042)
							(end 0.3302 -0.4318)
						)
					)
					(width 0)
					(fill yes)
				)
			)
		)
	)
	(footprint ""
		(layer "F.Cu")
		(at 4.040124 -482.700076 -90)
		(property "Reference" "CN1"
			(at 0 0 270)
			(layer "F.SilkS")
			(hide yes)
			(effects
				(font
					(size 1.27 1.27)
				)
			)
		)
		(property "Value" "JWT-CON5-42-GP"
			(at -7.8105 2.9591 270)
			(unlocked yes)
			(layer "F.Fab")
			(hide yes)
			(effects
				(font
					(size 1.016 1.016)
					(thickness 0.1524)
				)
			)
		)
		(property "Device Type" "A2541WR0-1TX5PA-6T-0E"
			(at -7.8105 1.4351 270)
			(unlocked yes)
			(layer "F.Fab")
			(hide yes)
			(effects
				(font
					(size 1.016 1.016)
					(thickness 0.1524)
				)
			)
		)
		(duplicate_pad_numbers_are_jumpers no)
		(fp_line
			(start -6.604 10.287)
			(end 6.604 10.287)
			(stroke
				(width 0.1524)
				(type default)
			)
			(layer "F.SilkS")
		)
		(fp_line
			(start 6.604 10.287)
			(end 6.604 -0.9652)
			(stroke
				(width 0.1524)
				(type default)
			)
			(layer "F.SilkS")
		)
		(fp_line
			(start -6.604 -0.9652)
			(end -6.604 10.287)
			(stroke
				(width 0.1524)
				(type default)
			)
			(layer "F.SilkS")
		)
		(fp_line
			(start 6.604 -0.9652)
			(end -6.604 -0.9652)
			(stroke
				(width 0.1524)
				(type default)
			)
			(layer "F.SilkS")
		)
		(fp_line
			(start -6.731 -1.0922)
			(end -6.731 0.1778)
			(stroke
				(width 0.4064)
				(type default)
			)
			(layer "F.SilkS")
		)
		(fp_line
			(start -5.461 -1.0922)
			(end -6.731 -1.0922)
			(stroke
				(width 0.4064)
				(type default)
			)
			(layer "F.SilkS")
		)
		(fp_circle
			(center -5.08 0)
			(end -5.08 -1.0668)
			(stroke
				(width 0.3048)
				(type default)
			)
			(fill no)
			(layer "F.SilkS")
		)
		(fp_circle
			(center -2.54 0)
			(end -2.54 -1.0668)
			(stroke
				(width 0.3048)
				(type default)
			)
			(fill no)
			(layer "F.SilkS")
		)
		(fp_circle
			(center 0 0)
			(end 0 -1.0668)
			(stroke
				(width 0.3048)
				(type default)
			)
			(fill no)
			(layer "F.SilkS")
		)
		(fp_circle
			(center 2.54 0)
			(end 2.54 -1.0668)
			(stroke
				(width 0.3048)
				(type default)
			)
			(fill no)
			(layer "F.SilkS")
		)
		(fp_circle
			(center 5.08 0)
			(end 5.08 -1.0668)
			(stroke
				(width 0.3048)
				(type default)
			)
			(fill no)
			(layer "F.SilkS")
		)
		(fp_rect
			(start -6.35 10.033)
			(end 6.35 -0.3302)
			(stroke
				(width 0)
				(type default)
			)
			(fill no)
			(layer "F.CrtYd")
		)
		(fp_poly
			(pts
				(xy -6.35 -0.3302) (xy 6.858 -0.3302) (xy 6.858 -1.2192) (xy -6.858 -1.2192) (xy -6.858 10.541)
				(xy 6.858 10.541) (xy 6.858 -0.3175) (xy 6.35 -0.3175) (xy 6.35 10.033) (xy -6.35 10.033)
			)
			(stroke
				(width 0)
				(type default)
			)
			(fill no)
			(layer "F.CrtYd")
		)
		(fp_rect
			(start -6.858 10.541)
			(end 6.858 -1.2192)
			(stroke
				(width 0)
				(type default)
			)
			(fill no)
			(layer "F.Fab")
		)
		(pad "1" thru_hole circle
			(at -5.08 0 270)
			(size 1.4224 1.4224)
			(drill 1.016)
			(layers "*.Cu" "*.Mask")
			(remove_unused_layers no)
			(net "GND")
			(clearance 0.1524)
			(thermal_gap 0.1524)
		)
		(pad "2" thru_hole circle
			(at -2.54 0 270)
			(size 1.4224 1.4224)
			(drill 1.016)
			(layers "*.Cu" "*.Mask")
			(remove_unused_layers no)
			(net "P12V_FAN1")
			(clearance 0.1524)
			(thermal_gap 0.1524)
		)
		(pad "3" thru_hole circle
			(at 0 0 270)
			(size 1.4224 1.4224)
			(drill 1.016)
			(layers "*.Cu" "*.Mask")
			(remove_unused_layers no)
			(net "FAN_TACH2")
			(clearance 0.1524)
			(thermal_gap 0.1524)
		)
		(pad "4" thru_hole circle
			(at 2.54 0 270)
			(size 1.4224 1.4224)
			(drill 1.016)
			(layers "*.Cu" "*.Mask")
			(remove_unused_layers no)
			(net "PWM_OUT_FAN1_NET")
			(clearance 0.1524)
			(thermal_gap 0.1524)
		)
		(pad "5" thru_hole circle
			(at 5.08 0 270)
			(size 1.4224 1.4224)
			(drill 1.016)
			(layers "*.Cu" "*.Mask")
			(remove_unused_layers no)
			(net "FAN_TACH1")
			(clearance 0.1524)
			(thermal_gap 0.1524)
		)
	)
	(footprint ""
		(layer "F.Cu")
		(at 17.8816 -253.9492 90)
		(property "Reference" "R90"
			(at 0 0 90)
			(layer "F.SilkS")
			(hide yes)
			(effects
				(font
					(size 1.27 1.27)
				)
			)
		)
		(property "Value" "10KR2F-2-GP"
			(at 0.064008 -3.993896 90)
			(unlocked yes)
			(layer "F.Fab")
			(hide yes)
			(effects
				(font
					(size 1.016 1.016)
					(thickness 0.1524)
				)
			)
		)
		(property "Device Type" "R402H16"
			(at 0.064008 -5.517896 90)
			(unlocked yes)
			(layer "F.Fab")
			(hide yes)
			(effects
				(font
					(size 1.016 1.016)
					(thickness 0.1524)
				)
			)
		)
		(duplicate_pad_numbers_are_jumpers no)
		(fp_line
			(start 0.508 -0.9398)
			(end -0.508 -0.9398)
			(stroke
				(width 0.1524)
				(type default)
			)
			(layer "F.SilkS")
		)
		(fp_line
			(start -0.508 -0.9398)
			(end -0.508 0.9398)
			(stroke
				(width 0.1524)
				(type default)
			)
			(layer "F.SilkS")
		)
		(fp_rect
			(start -0.508 0.9398)
			(end 0.508 -0.9398)
			(stroke
				(width 0)
				(type default)
			)
			(fill no)
			(layer "F.CrtYd")
		)
		(fp_rect
			(start -0.508 0.9398)
			(end 0.508 -0.9398)
			(stroke
				(width 0)
				(type default)
			)
			(fill no)
			(layer "F.Fab")
		)
		(pad "1" smd custom
			(at 0 -0.4445 90)
			(size 0.1397 0.1397)
			(layers "F.Cu" "F.Mask" "F.Paste")
			(net "FANIN_5")
			(options
				(clearance outline)
				(anchor circle)
			)
			(primitives
				(gr_poly
					(pts
						(arc
							(start -0.1778 -0.2794)
							(mid -0.249642 -0.249642)
							(end -0.2794 -0.1778)
						)
						(arc
							(start -0.2794 0.1778)
							(mid -0.249642 0.249642)
							(end -0.1778 0.2794)
						)
						(arc
							(start 0.1778 0.2794)
							(mid 0.249642 0.249642)
							(end 0.2794 0.1778)
						)
						(arc
							(start 0.2794 -0.1778)
							(mid 0.249642 -0.249642)
							(end 0.1778 -0.2794)
						)
					)
					(width 0)
					(fill yes)
				)
			)
		)
		(pad "2" smd custom
			(at 0 0.4445 90)
			(size 0.1397 0.1397)
			(layers "F.Cu" "F.Mask" "F.Paste")
			(net "GND")
			(options
				(clearance outline)
				(anchor circle)
			)
			(primitives
				(gr_poly
					(pts
						(arc
							(start -0.1778 -0.2794)
							(mid -0.249642 -0.249642)
							(end -0.2794 -0.1778)
						)
						(arc
							(start -0.2794 0.1778)
							(mid -0.249642 0.249642)
							(end -0.1778 0.2794)
						)
						(arc
							(start 0.1778 0.2794)
							(mid 0.249642 0.249642)
							(end 0.2794 0.1778)
						)
						(arc
							(start 0.2794 -0.1778)
							(mid 0.249642 -0.249642)
							(end 0.1778 -0.2794)
						)
					)
					(width 0)
					(fill yes)
				)
			)
		)
	)
	(footprint ""
		(layer "F.Cu")
		(at 23.622 -367.411 -90)
		(property "Reference" "PR3"
			(at 0 0 270)
			(layer "F.SilkS")
			(hide yes)
			(effects
				(font
					(size 1.27 1.27)
				)
			)
		)
		(property "Value" "51K1R2F-GP"
			(at 0.064008 -3.993896 270)
			(unlocked yes)
			(layer "F.Fab")
			(hide yes)
			(effects
				(font
					(size 1.016 1.016)
					(thickness 0.1524)
				)
			)
		)
		(property "Device Type" "R402H16"
			(at 0.064008 -5.517896 270)
			(unlocked yes)
			(layer "F.Fab")
			(hide yes)
			(effects
				(font
					(size 1.016 1.016)
					(thickness 0.1524)
				)
			)
		)
		(duplicate_pad_numbers_are_jumpers no)
		(fp_line
			(start -0.508 -0.9398)
			(end -0.508 0.9398)
			(stroke
				(width 0.1524)
				(type default)
			)
			(layer "F.SilkS")
		)
		(fp_line
			(start 0.508 -0.9398)
			(end -0.508 -0.9398)
			(stroke
				(width 0.1524)
				(type default)
			)
			(layer "F.SilkS")
		)
		(fp_rect
			(start -0.508 0.9398)
			(end 0.508 -0.9398)
			(stroke
				(width 0)
				(type default)
			)
			(fill no)
			(layer "F.CrtYd")
		)
		(fp_rect
			(start -0.508 0.9398)
			(end 0.508 -0.9398)
			(stroke
				(width 0)
				(type default)
			)
			(fill no)
			(layer "F.Fab")
		)
		(pad "1" smd custom
			(at 0 -0.4445 270)
			(size 0.1397 0.1397)
			(layers "F.Cu" "F.Mask" "F.Paste")
			(net "ADM1276_ISET")
			(options
				(clearance outline)
				(anchor circle)
			)
			(primitives
				(gr_poly
					(pts
						(arc
							(start -0.1778 -0.2794)
							(mid -0.249642 -0.249642)
							(end -0.2794 -0.1778)
						)
						(arc
							(start -0.2794 0.1778)
							(mid -0.249642 0.249642)
							(end -0.1778 0.2794)
						)
						(arc
							(start 0.1778 0.2794)
							(mid 0.249642 0.249642)
							(end 0.2794 0.1778)
						)
						(arc
							(start 0.2794 -0.1778)
							(mid 0.249642 -0.249642)
							(end 0.1778 -0.2794)
						)
					)
					(width 0)
					(fill yes)
				)
			)
		)
		(pad "2" smd custom
			(at 0 0.4445 270)
			(size 0.1397 0.1397)
			(layers "F.Cu" "F.Mask" "F.Paste")
			(net "GND")
			(options
				(clearance outline)
				(anchor circle)
			)
			(primitives
				(gr_poly
					(pts
						(arc
							(start -0.1778 -0.2794)
							(mid -0.249642 -0.249642)
							(end -0.2794 -0.1778)
						)
						(arc
							(start -0.2794 0.1778)
							(mid -0.249642 0.249642)
							(end -0.1778 0.2794)
						)
						(arc
							(start 0.1778 0.2794)
							(mid 0.249642 0.249642)
							(end 0.2794 0.1778)
						)
						(arc
							(start 0.2794 -0.1778)
							(mid 0.249642 -0.249642)
							(end 0.1778 -0.2794)
						)
					)
					(width 0)
					(fill yes)
				)
			)
		)
	)
	(footprint ""
		(layer "F.Cu")
		(at 43.2308 -158.8516)
		(property "Reference" "R51"
			(at 0 0 0)
			(layer "F.SilkS")
			(hide yes)
			(effects
				(font
					(size 1.27 1.27)
				)
			)
		)
		(property "Value" "0R2J-2-GP"
			(at 0.064008 -3.993896 0)
			(unlocked yes)
			(layer "F.Fab")
			(hide yes)
			(effects
				(font
					(size 1.016 1.016)
					(thickness 0.1524)
				)
			)
		)
		(property "Device Type" "R402H16"
			(at 0.064008 -5.517896 0)
			(unlocked yes)
			(layer "F.Fab")
			(hide yes)
			(effects
				(font
					(size 1.016 1.016)
					(thickness 0.1524)
				)
			)
		)
		(duplicate_pad_numbers_are_jumpers no)
		(fp_line
			(start -0.508 -0.9398)
			(end -0.508 0.9398)
			(stroke
				(width 0.1524)
				(type default)
			)
			(layer "F.SilkS")
		)
		(fp_line
			(start 0.508 -0.9398)
			(end -0.508 -0.9398)
			(stroke
				(width 0.1524)
				(type default)
			)
			(layer "F.SilkS")
		)
		(fp_rect
			(start -0.508 0.9398)
			(end 0.508 -0.9398)
			(stroke
				(width 0)
				(type default)
			)
			(fill no)
			(layer "F.CrtYd")
		)
		(fp_rect
			(start -0.508 0.9398)
			(end 0.508 -0.9398)
			(stroke
				(width 0)
				(type default)
			)
			(fill no)
			(layer "F.Fab")
		)
		(pad "1" smd custom
			(at 0 -0.4445)
			(size 0.1397 0.1397)
			(layers "F.Cu" "F.Mask" "F.Paste")
			(net "NCT7904_VSEN_P12V_AUX")
			(options
				(clearance outline)
				(anchor circle)
			)
			(primitives
				(gr_poly
					(pts
						(arc
							(start -0.1778 -0.2794)
							(mid -0.249642 -0.249642)
							(end -0.2794 -0.1778)
						)
						(arc
							(start -0.2794 0.1778)
							(mid -0.249642 0.249642)
							(end -0.1778 0.2794)
						)
						(arc
							(start 0.1778 0.2794)
							(mid 0.249642 0.249642)
							(end 0.2794 0.1778)
						)
						(arc
							(start 0.2794 -0.1778)
							(mid 0.249642 -0.249642)
							(end 0.1778 -0.2794)
						)
					)
					(width 0)
					(fill yes)
				)
			)
		)
		(pad "2" smd custom
			(at 0 0.4445)
			(size 0.1397 0.1397)
			(layers "F.Cu" "F.Mask" "F.Paste")
			(net "NCT7904_VSEN9")
			(options
				(clearance outline)
				(anchor circle)
			)
			(primitives
				(gr_poly
					(pts
						(arc
							(start -0.1778 -0.2794)
							(mid -0.249642 -0.249642)
							(end -0.2794 -0.1778)
						)
						(arc
							(start -0.2794 0.1778)
							(mid -0.249642 0.249642)
							(end -0.1778 0.2794)
						)
						(arc
							(start 0.1778 0.2794)
							(mid 0.249642 0.249642)
							(end 0.2794 0.1778)
						)
						(arc
							(start 0.2794 -0.1778)
							(mid 0.249642 -0.249642)
							(end 0.1778 -0.2794)
						)
					)
					(width 0)
					(fill yes)
				)
			)
		)
	)
	(footprint ""
		(layer "F.Cu")
		(at 33.069784 -353.6442 -90)
		(property "Reference" "C259"
			(at 0 0 270)
			(layer "F.SilkS")
			(hide yes)
			(effects
				(font
					(size 1.27 1.27)
				)
			)
		)
		(property "Value" "SC10U25V6KX-1GP"
			(at -0.0762 -5.1308 270)
			(unlocked yes)
			(layer "F.Fab")
			(hide yes)
			(effects
				(font
					(size 1.016 1.016)
					(thickness 0.1524)
				)
			)
		)
		(property "Device Type" "C1206H71"
			(at -0.127 -6.6548 270)
			(unlocked yes)
			(layer "F.Fab")
			(hide yes)
			(effects
				(font
					(size 1.016 1.016)
					(thickness 0.1524)
				)
			)
		)
		(duplicate_pad_numbers_are_jumpers no)
		(fp_line
			(start -1.016 2.2352)
			(end -1.016 0.8382)
			(stroke
				(width 0.1524)
				(type default)
			)
			(layer "F.SilkS")
		)
		(fp_line
			(start 1.016 2.2352)
			(end -1.016 2.2352)
			(stroke
				(width 0.1524)
				(type default)
			)
			(layer "F.SilkS")
		)
		(fp_line
			(start 1.016 0.8382)
			(end 1.016 2.2352)
			(stroke
				(width 0.1524)
				(type default)
			)
			(layer "F.SilkS")
		)
		(fp_line
			(start -1.016 -0.8382)
			(end -1.016 -2.2352)
			(stroke
				(width 0.1524)
				(type default)
			)
			(layer "F.SilkS")
		)
		(fp_line
			(start -1.016 -2.2352)
			(end 1.016 -2.2352)
			(stroke
				(width 0.1524)
				(type default)
			)
			(layer "F.SilkS")
		)
		(fp_line
			(start 1.016 -2.2352)
			(end 1.016 -0.8382)
			(stroke
				(width 0.1524)
				(type default)
			)
			(layer "F.SilkS")
		)
		(fp_rect
			(start -1.0922 2.3114)
			(end 1.0922 -2.3114)
			(stroke
				(width 0)
				(type default)
			)
			(fill no)
			(layer "F.CrtYd")
		)
		(fp_poly
			(pts
				(xy 1.0922 -2.3114) (xy 1.0922 2.3114) (xy -1.0922 2.3114) (xy -1.0922 -2.3114)
			)
			(stroke
				(width 0)
				(type default)
			)
			(fill no)
			(layer "F.Fab")
		)
		(pad "1" smd rect
			(at 0 -1.397 270)
			(size 1.651 1.27)
			(layers "F.Cu" "F.Mask" "F.Paste")
			(net "OTP_RETRY_G")
		)
		(pad "2" smd rect
			(at 0 1.397 270)
			(size 1.651 1.27)
			(layers "F.Cu" "F.Mask" "F.Paste")
			(net "GND")
		)
	)
	(footprint ""
		(layer "F.Cu")
		(at 41.91 -350.647 90)
		(property "Reference" "JP1"
			(at 0 0 90)
			(layer "F.SilkS")
			(hide yes)
			(effects
				(font
					(size 1.27 1.27)
				)
			)
		)
		(property "Value" "PIN-CON3-S3-GP"
			(at -5.8039 -0.0889 90)
			(unlocked yes)
			(layer "F.Fab")
			(hide yes)
			(effects
				(font
					(size 1.016 1.016)
					(thickness 0.1524)
				)
			)
		)
		(property "Device Type" "21S-H91-03GB31"
			(at -5.8039 -1.6129 90)
			(unlocked yes)
			(layer "F.Fab")
			(hide yes)
			(effects
				(font
					(size 1.016 1.016)
					(thickness 0.1524)
				)
			)
		)
		(duplicate_pad_numbers_are_jumpers no)
		(fp_line
			(start -4.064 -1.6256)
			(end -2.794 -1.6256)
			(stroke
				(width 0.4064)
				(type default)
			)
			(layer "F.SilkS")
		)
		(fp_line
			(start 3.937 -1.4986)
			(end -3.937 -1.4986)
			(stroke
				(width 0.1524)
				(type default)
			)
			(layer "F.SilkS")
		)
		(fp_line
			(start -3.937 -1.4986)
			(end -3.937 1.4986)
			(stroke
				(width 0.1524)
				(type default)
			)
			(layer "F.SilkS")
		)
		(fp_line
			(start -4.064 -0.3556)
			(end -4.064 -1.6256)
			(stroke
				(width 0.4064)
				(type default)
			)
			(layer "F.SilkS")
		)
		(fp_line
			(start 3.937 1.4986)
			(end 3.937 -1.4986)
			(stroke
				(width 0.1524)
				(type default)
			)
			(layer "F.SilkS")
		)
		(fp_line
			(start -3.937 1.4986)
			(end 3.937 1.4986)
			(stroke
				(width 0.1524)
				(type default)
			)
			(layer "F.SilkS")
		)
		(fp_circle
			(center 2.54 0)
			(end 2.54 1.0668)
			(stroke
				(width 0.3048)
				(type default)
			)
			(fill no)
			(layer "F.SilkS")
		)
		(fp_circle
			(center 0 0)
			(end 0 1.0668)
			(stroke
				(width 0.3048)
				(type default)
			)
			(fill no)
			(layer "F.SilkS")
		)
		(fp_circle
			(center -2.54 0)
			(end -2.54 1.0668)
			(stroke
				(width 0.3048)
				(type default)
			)
			(fill no)
			(layer "F.SilkS")
		)
		(fp_rect
			(start -3.683 1.2446)
			(end 3.683 -1.2446)
			(stroke
				(width 0)
				(type default)
			)
			(fill no)
			(layer "F.CrtYd")
		)
		(fp_poly
			(pts
				(xy 4.191 -1.2446) (xy -3.683 -1.2446) (xy -3.683 1.2446) (xy 3.683 1.2446) (xy 3.683 -1.2319) (xy 4.191 -1.2319)
				(xy 4.191 1.7526) (xy -4.191 1.7526) (xy -4.191 -1.7526) (xy 4.191 -1.7526)
			)
			(stroke
				(width 0)
				(type default)
			)
			(fill no)
			(layer "F.CrtYd")
		)
		(fp_rect
			(start -4.191 1.7526)
			(end 4.191 -1.7526)
			(stroke
				(width 0)
				(type default)
			)
			(fill no)
			(layer "F.Fab")
		)
		(pad "1" thru_hole circle
			(at -2.54 0 90)
			(size 1.4224 1.4224)
			(drill 1.016)
			(layers "*.Cu" "*.Mask")
			(remove_unused_layers no)
			(net "TEMP_ALM#_JP_1")
			(clearance 0.1524)
			(thermal_gap 0.1524)
		)
		(pad "2" thru_hole circle
			(at 0 0 90)
			(size 1.4224 1.4224)
			(drill 1.016)
			(layers "*.Cu" "*.Mask")
			(remove_unused_layers no)
			(net "TEMP_ALM#_JP_2")
			(clearance 0.1524)
			(thermal_gap 0.1524)
		)
		(pad "3" thru_hole circle
			(at 2.54 0 90)
			(size 1.4224 1.4224)
			(drill 1.016)
			(layers "*.Cu" "*.Mask")
			(remove_unused_layers no)
			(net "OTP_RETRY_B")
			(clearance 0.1524)
			(thermal_gap 0.1524)
		)
	)
	(footprint ""
		(layer "F.Cu")
		(at 38.354 -378.333 180)
		(property "Reference" "PR28"
			(at 0 0 180)
			(layer "F.SilkS")
			(hide yes)
			(effects
				(font
					(size 1.27 1.27)
				)
			)
		)
		(property "Value" "10R2F-L-GP"
			(at 0.064008 -3.993896 180)
			(unlocked yes)
			(layer "F.Fab")
			(hide yes)
			(effects
				(font
					(size 1.016 1.016)
					(thickness 0.1524)
				)
			)
		)
		(property "Device Type" "R402H14"
			(at 0.064008 -5.517896 180)
			(unlocked yes)
			(layer "F.Fab")
			(hide yes)
			(effects
				(font
					(size 1.016 1.016)
					(thickness 0.1524)
				)
			)
		)
		(duplicate_pad_numbers_are_jumpers no)
		(fp_line
			(start 0.508 -0.9398)
			(end -0.508 -0.9398)
			(stroke
				(width 0.1524)
				(type default)
			)
			(layer "F.SilkS")
		)
		(fp_line
			(start -0.508 -0.9398)
			(end -0.508 0.9398)
			(stroke
				(width 0.1524)
				(type default)
			)
			(layer "F.SilkS")
		)
		(fp_rect
			(start -0.508 0.9398)
			(end 0.508 -0.9398)
			(stroke
				(width 0)
				(type default)
			)
			(fill no)
			(layer "F.CrtYd")
		)
		(fp_rect
			(start -0.508 0.9398)
			(end 0.508 -0.9398)
			(stroke
				(width 0)
				(type default)
			)
			(fill no)
			(layer "F.Fab")
		)
		(pad "1" smd custom
			(at 0 -0.4445 180)
			(size 0.1397 0.1397)
			(layers "F.Cu" "F.Mask" "F.Paste")
			(net "ADM1276_GATE")
			(options
				(clearance outline)
				(anchor circle)
			)
			(primitives
				(gr_poly
					(pts
						(arc
							(start -0.1778 -0.2794)
							(mid -0.249642 -0.249642)
							(end -0.2794 -0.1778)
						)
						(arc
							(start -0.2794 0.1778)
							(mid -0.249642 0.249642)
							(end -0.1778 0.2794)
						)
						(arc
							(start 0.1778 0.2794)
							(mid 0.249642 0.249642)
							(end 0.2794 0.1778)
						)
						(arc
							(start 0.2794 -0.1778)
							(mid 0.249642 -0.249642)
							(end 0.1778 -0.2794)
						)
					)
					(width 0)
					(fill yes)
				)
			)
		)
		(pad "2" smd custom
			(at 0 0.4445 180)
			(size 0.1397 0.1397)
			(layers "F.Cu" "F.Mask" "F.Paste")
			(net "ADM1276_GATE_DRV3")
			(options
				(clearance outline)
				(anchor circle)
			)
			(primitives
				(gr_poly
					(pts
						(arc
							(start -0.1778 -0.2794)
							(mid -0.249642 -0.249642)
							(end -0.2794 -0.1778)
						)
						(arc
							(start -0.2794 0.1778)
							(mid -0.249642 0.249642)
							(end -0.1778 0.2794)
						)
						(arc
							(start 0.1778 0.2794)
							(mid 0.249642 0.249642)
							(end 0.2794 0.1778)
						)
						(arc
							(start 0.2794 -0.1778)
							(mid 0.249642 -0.249642)
							(end 0.1778 -0.2794)
						)
					)
					(width 0)
					(fill yes)
				)
			)
		)
	)
	(footprint ""
		(layer "F.Cu")
		(at 26.227024 -173.96841 90)
		(property "Reference" "U2"
			(at 0 0 90)
			(layer "F.SilkS")
			(hide yes)
			(effects
				(font
					(size 1.27 1.27)
				)
			)
		)
		(property "Value" "NCT7368S-GP"
			(at 3.8989 1.5748 90)
			(unlocked yes)
			(layer "F.Fab")
			(hide yes)
			(effects
				(font
					(size 1.016 1.016)
					(thickness 0.1524)
				)
			)
		)
		(property "Device Type" "SOIC8-G3627H69"
			(at 3.8989 0.0508 90)
			(unlocked yes)
			(layer "F.Fab")
			(hide yes)
			(effects
				(font
					(size 1.016 1.016)
					(thickness 0.1524)
				)
			)
		)
		(duplicate_pad_numbers_are_jumpers no)
		(fp_line
			(start 2.7178 -3.6322)
			(end 2.7178 3.6322)
			(stroke
				(width 0.1524)
				(type default)
			)
			(layer "F.SilkS")
		)
		(fp_line
			(start -2.8829 -3.6322)
			(end 2.7178 -3.6322)
			(stroke
				(width 0.1524)
				(type default)
			)
			(layer "F.SilkS")
		)
		(fp_line
			(start -2.8829 -0.6223)
			(end -2.2479 0.0127)
			(stroke
				(width 0.1524)
				(type default)
			)
			(layer "F.SilkS")
		)
		(fp_line
			(start -2.2479 0.0127)
			(end -2.8829 0.6477)
			(stroke
				(width 0.1524)
				(type default)
			)
			(layer "F.SilkS")
		)
		(fp_line
			(start -2.8829 0.6477)
			(end -2.8829 -0.6223)
			(stroke
				(width 0.1524)
				(type default)
			)
			(layer "F.SilkS")
		)
		(fp_line
			(start 2.7178 3.6322)
			(end -2.8829 3.6322)
			(stroke
				(width 0.1524)
				(type default)
			)
			(layer "F.SilkS")
		)
		(fp_line
			(start -2.7051 3.6322)
			(end -2.7051 1.5494)
			(stroke
				(width 0.508)
				(type default)
			)
			(layer "F.SilkS")
		)
		(fp_line
			(start -2.8829 3.6322)
			(end -2.8829 -3.6322)
			(stroke
				(width 0.1524)
				(type default)
			)
			(layer "F.SilkS")
		)
		(fp_poly
			(pts
				(xy 0.2794 -0.2794) (xy 1.8034 -0.2794) (xy 1.8034 -1.3462) (xy 0.2794 -1.3462)
			)
			(stroke
				(width 0)
				(type default)
			)
			(fill yes)
			(layer "F.Paste")
		)
		(fp_poly
			(pts
				(xy -1.8034 -0.2794) (xy -0.2794 -0.2794) (xy -0.2794 -1.3462) (xy -1.8034 -1.3462)
			)
			(stroke
				(width 0)
				(type default)
			)
			(fill yes)
			(layer "F.Paste")
		)
		(fp_poly
			(pts
				(xy 0.2794 1.3462) (xy 1.8034 1.3462) (xy 1.8034 0.2794) (xy 0.2794 0.2794)
			)
			(stroke
				(width 0)
				(type default)
			)
			(fill yes)
			(layer "F.Paste")
		)
		(fp_poly
			(pts
				(xy -1.8034 1.3462) (xy -0.2794 1.3462) (xy -0.2794 0.2794) (xy -1.8034 0.2794)
			)
			(stroke
				(width 0)
				(type default)
			)
			(fill yes)
			(layer "F.Paste")
		)
		(fp_poly
			(pts
				(xy -2.1209 2.9972) (xy -2.1209 1.9558) (xy -2.4511 1.9558) (xy -2.4511 -1.9558) (xy -2.1209 -1.9558)
				(xy -2.1209 -2.9972) (xy 2.1209 -2.9972) (xy 2.1209 -1.9558) (xy 2.4511 -1.9558) (xy 2.4511 1.9558)
				(xy 2.1209 1.9558) (xy 2.1209 2.9972)
			)
			(stroke
				(width 0)
				(type default)
			)
			(fill no)
			(layer "F.CrtYd")
		)
		(fp_poly
			(pts
				(xy -2.9591 3.8862) (xy -2.9591 -3.8862) (xy 2.9591 -3.8862) (xy 2.9591 1.95072) (xy 2.4511 1.95072)
				(xy 2.4511 -1.9558) (xy 2.1209 -1.9558) (xy 2.1209 -2.9972) (xy -2.1209 -2.9972) (xy -2.1209 -1.9558)
				(xy -2.4511 -1.9558) (xy -2.4511 1.9558) (xy -2.1209 1.9558) (xy -2.1209 2.9972) (xy 2.1209 2.9972)
				(xy 2.1209 1.9558) (xy 2.9591 1.9558) (xy 2.9591 3.8862)
			)
			(stroke
				(width 0)
				(type default)
			)
			(fill no)
			(layer "F.CrtYd")
		)
		(fp_rect
			(start -2.9591 3.8862)
			(end 2.9591 -3.8862)
			(stroke
				(width 0)
				(type default)
			)
			(fill no)
			(layer "F.Fab")
		)
		(pad "1" smd rect
			(at -1.905 2.5527 90)
			(size 0.635 1.651)
			(layers "F.Cu" "F.Mask" "F.Paste")
			(net "P3V3")
		)
		(pad "2" smd rect
			(at -0.635 2.5527 90)
			(size 0.635 1.651)
			(layers "F.Cu" "F.Mask" "F.Paste")
			(net "PWM_EXP_1A")
		)
		(pad "3" smd rect
			(at 0.635 2.5527 90)
			(size 0.635 1.651)
			(layers "F.Cu" "F.Mask" "F.Paste")
			(net "PWM_EXP_1B")
		)
		(pad "4" smd rect
			(at 1.905 2.5527 90)
			(size 0.635 1.651)
			(layers "F.Cu" "F.Mask" "F.Paste")
			(net "PWM_EXP_2A")
		)
		(pad "5" smd rect
			(at 1.905 -2.5527 90)
			(size 0.635 1.651)
			(layers "F.Cu" "F.Mask" "F.Paste")
			(net "NCT7368S_SEL")
		)
		(pad "6" smd rect
			(at 0.635 -2.5527 90)
			(size 0.635 1.651)
			(layers "F.Cu" "F.Mask" "F.Paste")
			(net "THERMHOT#")
		)
		(pad "7" smd rect
			(at -0.635 -2.5527 90)
			(size 0.635 1.651)
			(layers "F.Cu" "F.Mask" "F.Paste")
			(net "PWM_OUT")
		)
		(pad "8" smd rect
			(at -1.905 -2.5527 90)
			(size 0.635 1.651)
			(layers "F.Cu" "F.Mask" "F.Paste")
			(net "PWM_EXP_2B")
		)
		(pad "9" smd rect
			(at 0 0 90)
			(size 3.6068 2.6924)
			(layers "F.Cu" "F.Mask" "F.Paste")
			(net "GND")
		)
	)
	(footprint ""
		(layer "F.Cu")
		(at 37.719 -111.633)
		(property "Reference" "PQ8"
			(at 0 0 0)
			(layer "F.SilkS")
			(hide yes)
			(effects
				(font
					(size 1.27 1.27)
				)
			)
		)
		(property "Value" "PH0925CL-GP"
			(at -4.2799 -0.4572 0)
			(unlocked yes)
			(layer "F.Fab")
			(hide yes)
			(effects
				(font
					(size 1.016 1.016)
					(thickness 0.1524)
				)
			)
		)
		(property "Device Type" "LFPAK-5PH48-U"
			(at -4.2799 -1.9812 0)
			(unlocked yes)
			(layer "F.Fab")
			(hide yes)
			(effects
				(font
					(size 1.016 1.016)
					(thickness 0.1524)
				)
			)
		)
		(duplicate_pad_numbers_are_jumpers no)
		(fp_line
			(start -2.7559 -6.5532)
			(end -2.7559 1.0668)
			(stroke
				(width 0.1524)
				(type default)
			)
			(layer "F.SilkS")
		)
		(fp_line
			(start -2.7559 1.0668)
			(end 2.7559 1.0668)
			(stroke
				(width 0.1524)
				(type default)
			)
			(layer "F.SilkS")
		)
		(fp_line
			(start -1.7272 1.1684)
			(end -2.1082 1.1684)
			(stroke
				(width 0.3302)
				(type default)
			)
			(layer "F.SilkS")
		)
		(fp_line
			(start 2.7559 -6.5532)
			(end -2.7559 -6.5532)
			(stroke
				(width 0.1524)
				(type default)
			)
			(layer "F.SilkS")
		)
		(fp_line
			(start 2.7559 1.0668)
			(end 2.7559 -6.5532)
			(stroke
				(width 0.1524)
				(type default)
			)
			(layer "F.SilkS")
		)
		(fp_poly
			(pts
				(xy -2.3368 1.5748) (xy -1.905 1.143) (xy -1.4732 1.5748)
			)
			(stroke
				(width 0)
				(type default)
			)
			(fill yes)
			(layer "F.SilkS")
		)
		(fp_poly
			(pts
				(xy -2.5019 -4.02971) (xy -0.3302 -4.02971) (xy -0.3302 -6.30301) (xy -2.5019 -6.30301)
			)
			(stroke
				(width 0)
				(type default)
			)
			(fill yes)
			(layer "F.Paste")
		)
		(fp_poly
			(pts
				(xy -2.5019 -1.09601) (xy -0.3302 -1.09601) (xy -0.3302 -3.36931) (xy -2.5019 -3.36931)
			)
			(stroke
				(width 0)
				(type default)
			)
			(fill yes)
			(layer "F.Paste")
		)
		(fp_poly
			(pts
				(xy 0.3302 -4.02971) (xy 2.5019 -4.02971) (xy 2.5019 -6.30301) (xy 0.3302 -6.30301)
			)
			(stroke
				(width 0)
				(type default)
			)
			(fill yes)
			(layer "F.Paste")
		)
		(fp_poly
			(pts
				(xy 0.3302 -1.09601) (xy 2.5019 -1.09601) (xy 2.5019 -3.36931) (xy 0.3302 -3.36931)
			)
			(stroke
				(width 0)
				(type default)
			)
			(fill yes)
			(layer "F.Paste")
		)
		(fp_rect
			(start -2.4511 0.3048)
			(end 2.4511 -5.6896)
			(stroke
				(width 0)
				(type default)
			)
			(fill no)
			(layer "F.CrtYd")
		)
		(fp_poly
			(pts
				(xy -3.0099 1.3208) (xy -3.0099 -6.8072) (xy 3.0099 -6.8072) (xy 3.0099 -1.016) (xy 2.4511 -1.016)
				(xy 2.4511 -5.6896) (xy -2.4511 -5.6896) (xy -2.4511 0.3048) (xy 2.4511 0.3048) (xy 2.4511 -1.0033)
				(xy 3.0099 -1.0033) (xy 3.0099 1.3208)
			)
			(stroke
				(width 0)
				(type default)
			)
			(fill no)
			(layer "F.CrtYd")
		)
		(fp_rect
			(start -3.0099 1.3208)
			(end 3.0099 -6.8072)
			(stroke
				(width 0)
				(type default)
			)
			(fill no)
			(layer "F.Fab")
		)
		(pad "1" smd rect
			(at -1.905 0)
			(size 0.762 1.6256)
			(layers "F.Cu" "F.Mask" "F.Paste")
			(net "P12VL")
		)
		(pad "2" smd rect
			(at -0.635 0)
			(size 0.762 1.6256)
			(layers "F.Cu" "F.Mask" "F.Paste")
			(net "P12VL")
		)
		(pad "3" smd rect
			(at 0.635 0)
			(size 0.762 1.6256)
			(layers "F.Cu" "F.Mask" "F.Paste")
			(net "P12VL")
		)
		(pad "4" smd rect
			(at 1.905 0)
			(size 0.762 1.6256)
			(layers "F.Cu" "F.Mask" "F.Paste")
			(net "P12VL_2490_GATE_DRV")
		)
		(pad "5" smd rect
			(at 0 -3.69951)
			(size 5.0038 5.207)
			(layers "F.Cu" "F.Mask" "F.Paste")
			(net "P12VL_NET")
		)
	)
	(footprint ""
		(layer "F.Cu")
		(at 15.494 -168.2242 90)
		(property "Reference" "C34"
			(at 0 0 90)
			(layer "F.SilkS")
			(hide yes)
			(effects
				(font
					(size 1.27 1.27)
				)
			)
		)
		(property "Value" "SC1U25V3KX-1-GP"
			(at 0 -2.8194 90)
			(unlocked yes)
			(layer "F.Fab")
			(hide yes)
			(effects
				(font
					(size 1.016 1.016)
					(thickness 0.1524)
				)
			)
		)
		(property "Device Type" "C603H36"
			(at 0 -4.3434 90)
			(unlocked yes)
			(layer "F.Fab")
			(hide yes)
			(effects
				(font
					(size 1.016 1.016)
					(thickness 0.1524)
				)
			)
		)
		(duplicate_pad_numbers_are_jumpers no)
		(fp_line
			(start 0.508 0)
			(end -0.508 0)
			(stroke
				(width 0.2032)
				(type default)
			)
			(layer "F.SilkS")
		)
		(fp_rect
			(start -0.5842 1.3335)
			(end 0.5842 -1.3335)
			(stroke
				(width 0)
				(type default)
			)
			(fill no)
			(layer "F.CrtYd")
		)
		(fp_rect
			(start -0.5842 1.3335)
			(end 0.5842 -1.3335)
			(stroke
				(width 0)
				(type default)
			)
			(fill no)
			(layer "F.Fab")
		)
		(pad "1" smd custom
			(at 0 -0.762 90)
			(size 0.2159 0.2159)
			(layers "F.Cu" "F.Mask" "F.Paste")
			(net "P12V")
			(options
				(clearance outline)
				(anchor circle)
			)
			(primitives
				(gr_poly
					(pts
						(arc
							(start -0.3302 -0.4318)
							(mid -0.402042 -0.402042)
							(end -0.4318 -0.3302)
						)
						(arc
							(start -0.4318 0.3302)
							(mid -0.402042 0.402042)
							(end -0.3302 0.4318)
						)
						(arc
							(start 0.3302 0.4318)
							(mid 0.402042 0.402042)
							(end 0.4318 0.3302)
						)
						(arc
							(start 0.4318 -0.3302)
							(mid 0.402042 -0.402042)
							(end 0.3302 -0.4318)
						)
					)
					(width 0)
					(fill yes)
				)
			)
		)
		(pad "2" smd custom
			(at 0 0.762 90)
			(size 0.2159 0.2159)
			(layers "F.Cu" "F.Mask" "F.Paste")
			(net "GND")
			(options
				(clearance outline)
				(anchor circle)
			)
			(primitives
				(gr_poly
					(pts
						(arc
							(start -0.3302 -0.4318)
							(mid -0.402042 -0.402042)
							(end -0.4318 -0.3302)
						)
						(arc
							(start -0.4318 0.3302)
							(mid -0.402042 0.402042)
							(end -0.3302 0.4318)
						)
						(arc
							(start 0.3302 0.4318)
							(mid 0.402042 0.402042)
							(end 0.4318 0.3302)
						)
						(arc
							(start 0.4318 -0.3302)
							(mid 0.402042 -0.402042)
							(end 0.3302 -0.4318)
						)
					)
					(width 0)
					(fill yes)
				)
			)
		)
	)
	(footprint ""
		(layer "F.Cu")
		(at 18.3388 -179.8828 180)
		(property "Reference" "C55"
			(at 0 0 180)
			(layer "F.SilkS")
			(hide yes)
			(effects
				(font
					(size 1.27 1.27)
				)
			)
		)
		(property "Value" "SC1U16V3KX-5GP"
			(at 0 -2.8194 180)
			(unlocked yes)
			(layer "F.Fab")
			(hide yes)
			(effects
				(font
					(size 1.016 1.016)
					(thickness 0.1524)
				)
			)
		)
		(property "Device Type" "C603H36"
			(at 0 -4.3434 180)
			(unlocked yes)
			(layer "F.Fab")
			(hide yes)
			(effects
				(font
					(size 1.016 1.016)
					(thickness 0.1524)
				)
			)
		)
		(duplicate_pad_numbers_are_jumpers no)
		(fp_line
			(start 0.508 0)
			(end -0.508 0)
			(stroke
				(width 0.2032)
				(type default)
			)
			(layer "F.SilkS")
		)
		(fp_rect
			(start -0.5842 1.3335)
			(end 0.5842 -1.3335)
			(stroke
				(width 0)
				(type default)
			)
			(fill no)
			(layer "F.CrtYd")
		)
		(fp_rect
			(start -0.5842 1.3335)
			(end 0.5842 -1.3335)
			(stroke
				(width 0)
				(type default)
			)
			(fill no)
			(layer "F.Fab")
		)
		(pad "1" smd custom
			(at 0 -0.762 180)
			(size 0.2159 0.2159)
			(layers "F.Cu" "F.Mask" "F.Paste")
			(net "P3V3")
			(options
				(clearance outline)
				(anchor circle)
			)
			(primitives
				(gr_poly
					(pts
						(arc
							(start -0.3302 -0.4318)
							(mid -0.402042 -0.402042)
							(end -0.4318 -0.3302)
						)
						(arc
							(start -0.4318 0.3302)
							(mid -0.402042 0.402042)
							(end -0.3302 0.4318)
						)
						(arc
							(start 0.3302 0.4318)
							(mid 0.402042 0.402042)
							(end 0.4318 0.3302)
						)
						(arc
							(start 0.4318 -0.3302)
							(mid 0.402042 -0.402042)
							(end 0.3302 -0.4318)
						)
					)
					(width 0)
					(fill yes)
				)
			)
		)
		(pad "2" smd custom
			(at 0 0.762 180)
			(size 0.2159 0.2159)
			(layers "F.Cu" "F.Mask" "F.Paste")
			(net "GND")
			(options
				(clearance outline)
				(anchor circle)
			)
			(primitives
				(gr_poly
					(pts
						(arc
							(start -0.3302 -0.4318)
							(mid -0.402042 -0.402042)
							(end -0.4318 -0.3302)
						)
						(arc
							(start -0.4318 0.3302)
							(mid -0.402042 0.402042)
							(end -0.3302 0.4318)
						)
						(arc
							(start 0.3302 0.4318)
							(mid 0.402042 0.402042)
							(end 0.4318 0.3302)
						)
						(arc
							(start 0.4318 -0.3302)
							(mid 0.402042 -0.402042)
							(end 0.3302 -0.4318)
						)
					)
					(width 0)
					(fill yes)
				)
			)
		)
	)
	(footprint ""
		(layer "F.Cu")
		(at 18.669 -410.591)
		(property "Reference" "PR29"
			(at 0 0 0)
			(layer "F.SilkS")
			(hide yes)
			(effects
				(font
					(size 1.27 1.27)
				)
			)
		)
		(property "Value" "D0005RL1632F-GP-U"
			(at 3.2258 1.2954 0)
			(unlocked yes)
			(layer "F.Fab")
			(hide yes)
			(effects
				(font
					(size 1.016 1.016)
					(thickness 0.1524)
				)
			)
		)
		(property "Device Type" "RL3115-4PH45"
			(at 3.2258 -0.2286 0)
			(unlocked yes)
			(layer "F.Fab")
			(hide yes)
			(effects
				(font
					(size 1.016 1.016)
					(thickness 0.1524)
				)
			)
		)
		(duplicate_pad_numbers_are_jumpers no)
		(fp_line
			(start -2.0574 -1.7653)
			(end -2.0574 -0.4064)
			(stroke
				(width 0.3302)
				(type default)
			)
			(layer "F.SilkS")
		)
		(fp_line
			(start -1.9685 -1.651)
			(end 1.9685 -1.651)
			(stroke
				(width 0.1524)
				(type default)
			)
			(layer "F.SilkS")
		)
		(fp_line
			(start -1.9685 1.651)
			(end -1.9685 -1.651)
			(stroke
				(width 0.1524)
				(type default)
			)
			(layer "F.SilkS")
		)
		(fp_line
			(start -0.5334 -1.7653)
			(end -2.0574 -1.7653)
			(stroke
				(width 0.3302)
				(type default)
			)
			(layer "F.SilkS")
		)
		(fp_line
			(start 1.9685 -1.651)
			(end 1.9685 1.651)
			(stroke
				(width 0.1524)
				(type default)
			)
			(layer "F.SilkS")
		)
		(fp_line
			(start 1.9685 1.651)
			(end -1.9685 1.651)
			(stroke
				(width 0.1524)
				(type default)
			)
			(layer "F.SilkS")
		)
		(fp_poly
			(pts
				(xy -0.561594 -1.726946) (xy -0.053594 -2.234946) (xy -1.069594 -2.234946)
			)
			(stroke
				(width 0)
				(type default)
			)
			(fill yes)
			(layer "F.SilkS")
		)
		(fp_rect
			(start -1.524 0.7493)
			(end 1.524 -0.7493)
			(stroke
				(width 0)
				(type default)
			)
			(fill no)
			(layer "F.CrtYd")
		)
		(fp_poly
			(pts
				(xy -2.2225 1.905) (xy -2.2225 -1.905) (xy 2.2225 -1.905) (xy 2.2225 -0.7493) (xy -1.524 -0.7493)
				(xy -1.524 0.7493) (xy 1.524 0.7493) (xy 1.524 -0.7366) (xy 2.2225 -0.7366) (xy 2.2225 1.905)
			)
			(stroke
				(width 0)
				(type default)
			)
			(fill no)
			(layer "F.CrtYd")
		)
		(fp_rect
			(start -2.2225 1.905)
			(end 2.2225 -1.905)
			(stroke
				(width 0)
				(type default)
			)
			(fill no)
			(layer "F.Fab")
		)
		(pad "1" smd rect
			(at -0.5715 -0.813562)
			(size 2.286 1.143)
			(layers "F.Cu" "F.Mask" "F.Paste")
			(net "P12V_AUX")
		)
		(pad "2" smd rect
			(at -0.5715 0.813562)
			(size 2.286 1.143)
			(layers "F.Cu" "F.Mask" "F.Paste")
			(net "P12V_SENSE_TRACE")
		)
		(pad "3" smd rect
			(at 1.334008 -0.813562)
			(size 0.762 1.143)
			(layers "F.Cu" "F.Mask" "F.Paste")
			(net "SENSE+_R1")
		)
		(pad "4" smd rect
			(at 1.334008 0.813562)
			(size 0.762 1.143)
			(layers "F.Cu" "F.Mask" "F.Paste")
			(net "SENSE-_R1")
		)
		(zone
			(layer "F.Cu")
			(hatch none 0.5)
			(connect_pads
				(clearance 0)
			)
			(min_thickness 0.25)
			(keepout
				(tracks allowed)
				(vias not_allowed)
				(pads allowed)
				(copperpour not_allowed)
				(footprints allowed)
			)
			(placement
				(enabled no)
				(sheetname "")
			)
			(fill
				(thermal_gap 0.5)
				(thermal_bridge_width 0.5)
				(island_removal_mode 0)
			)
			(polygon
				(pts
					(xy 19.2405 -410.833062) (xy 19.622008 -410.833062) (xy 19.622008 -411.3403) (xy 19.2405 -411.3403)
				)
			)
		)
		(zone
			(layer "F.Cu")
			(hatch none 0.5)
			(connect_pads
				(clearance 0)
			)
			(min_thickness 0.25)
			(keepout
				(tracks not_allowed)
				(vias allowed)
				(pads allowed)
				(copperpour not_allowed)
				(footprints allowed)
			)
			(placement
				(enabled no)
				(sheetname "")
			)
			(fill
				(thermal_gap 0.5)
				(thermal_bridge_width 0.5)
				(island_removal_mode 0)
			)
			(polygon
				(pts
					(xy 19.2405 -410.833062) (xy 19.622008 -410.833062) (xy 19.622008 -411.3403) (xy 19.2405 -411.3403)
				)
			)
		)
		(zone
			(layer "F.Cu")
			(hatch none 0.5)
			(connect_pads
				(clearance 0)
			)
			(min_thickness 0.25)
			(keepout
				(tracks not_allowed)
				(vias allowed)
				(pads allowed)
				(copperpour not_allowed)
				(footprints allowed)
			)
			(placement
				(enabled no)
				(sheetname "")
			)
			(fill
				(thermal_gap 0.5)
				(thermal_bridge_width 0.5)
				(island_removal_mode 0)
			)
			(polygon
				(pts
					(xy 19.2405 -409.8417) (xy 19.622008 -409.8417) (xy 19.622008 -410.348938) (xy 19.2405 -410.348938)
				)
			)
		)
		(zone
			(layer "F.Cu")
			(hatch none 0.5)
			(connect_pads
				(clearance 0)
			)
			(min_thickness 0.25)
			(keepout
				(tracks allowed)
				(vias not_allowed)
				(pads allowed)
				(copperpour not_allowed)
				(footprints allowed)
			)
			(placement
				(enabled no)
				(sheetname "")
			)
			(fill
				(thermal_gap 0.5)
				(thermal_bridge_width 0.5)
				(island_removal_mode 0)
			)
			(polygon
				(pts
					(xy 19.2405 -409.8417) (xy 19.622008 -409.8417) (xy 19.622008 -410.348938) (xy 19.2405 -410.348938)
				)
			)
		)
	)
	(footprint ""
		(layer "F.Cu")
		(at 39.123366 -156.22651 90)
		(property "Reference" "R6"
			(at 0 0 90)
			(layer "F.SilkS")
			(hide yes)
			(effects
				(font
					(size 1.27 1.27)
				)
			)
		)
		(property "Value" "0R2J-2-GP"
			(at 0.064008 -3.993896 90)
			(unlocked yes)
			(layer "F.Fab")
			(hide yes)
			(effects
				(font
					(size 1.016 1.016)
					(thickness 0.1524)
				)
			)
		)
		(property "Device Type" "R402H16"
			(at 0.064008 -5.517896 90)
			(unlocked yes)
			(layer "F.Fab")
			(hide yes)
			(effects
				(font
					(size 1.016 1.016)
					(thickness 0.1524)
				)
			)
		)
		(duplicate_pad_numbers_are_jumpers no)
		(fp_line
			(start 0.508 -0.9398)
			(end -0.508 -0.9398)
			(stroke
				(width 0.1524)
				(type default)
			)
			(layer "F.SilkS")
		)
		(fp_line
			(start -0.508 -0.9398)
			(end -0.508 0.9398)
			(stroke
				(width 0.1524)
				(type default)
			)
			(layer "F.SilkS")
		)
		(fp_rect
			(start -0.508 0.9398)
			(end 0.508 -0.9398)
			(stroke
				(width 0)
				(type default)
			)
			(fill no)
			(layer "F.CrtYd")
		)
		(fp_rect
			(start -0.508 0.9398)
			(end 0.508 -0.9398)
			(stroke
				(width 0)
				(type default)
			)
			(fill no)
			(layer "F.Fab")
		)
		(pad "1" smd custom
			(at 0 -0.4445 90)
			(size 0.1397 0.1397)
			(layers "F.Cu" "F.Mask" "F.Paste")
			(net "NCT7904_SMI")
			(options
				(clearance outline)
				(anchor circle)
			)
			(primitives
				(gr_poly
					(pts
						(arc
							(start -0.1778 -0.2794)
							(mid -0.249642 -0.249642)
							(end -0.2794 -0.1778)
						)
						(arc
							(start -0.2794 0.1778)
							(mid -0.249642 0.249642)
							(end -0.1778 0.2794)
						)
						(arc
							(start 0.1778 0.2794)
							(mid 0.249642 0.249642)
							(end 0.2794 0.1778)
						)
						(arc
							(start 0.2794 -0.1778)
							(mid 0.249642 -0.249642)
							(end 0.1778 -0.2794)
						)
					)
					(width 0)
					(fill yes)
				)
			)
		)
		(pad "2" smd custom
			(at 0 0.4445 90)
			(size 0.1397 0.1397)
			(layers "F.Cu" "F.Mask" "F.Paste")
			(net "TEMP_ALM#")
			(options
				(clearance outline)
				(anchor circle)
			)
			(primitives
				(gr_poly
					(pts
						(arc
							(start -0.1778 -0.2794)
							(mid -0.249642 -0.249642)
							(end -0.2794 -0.1778)
						)
						(arc
							(start -0.2794 0.1778)
							(mid -0.249642 0.249642)
							(end -0.1778 0.2794)
						)
						(arc
							(start 0.1778 0.2794)
							(mid 0.249642 0.249642)
							(end 0.2794 0.1778)
						)
						(arc
							(start 0.2794 -0.1778)
							(mid 0.249642 -0.249642)
							(end 0.1778 -0.2794)
						)
					)
					(width 0)
					(fill yes)
				)
			)
		)
	)
	(footprint ""
		(layer "F.Cu")
		(at 40.513 -252.984)
		(property "Reference" "R129"
			(at 0 0 0)
			(layer "F.SilkS")
			(hide yes)
			(effects
				(font
					(size 1.27 1.27)
				)
			)
		)
		(property "Value" "330R2J-3-GP"
			(at 0.064008 -3.993896 0)
			(unlocked yes)
			(layer "F.Fab")
			(hide yes)
			(effects
				(font
					(size 1.016 1.016)
					(thickness 0.1524)
				)
			)
		)
		(property "Device Type" "R402H16"
			(at 0.064008 -5.517896 0)
			(unlocked yes)
			(layer "F.Fab")
			(hide yes)
			(effects
				(font
					(size 1.016 1.016)
					(thickness 0.1524)
				)
			)
		)
		(duplicate_pad_numbers_are_jumpers no)
		(fp_line
			(start -0.508 -0.9398)
			(end -0.508 0.9398)
			(stroke
				(width 0.1524)
				(type default)
			)
			(layer "F.SilkS")
		)
		(fp_line
			(start 0.508 -0.9398)
			(end -0.508 -0.9398)
			(stroke
				(width 0.1524)
				(type default)
			)
			(layer "F.SilkS")
		)
		(fp_rect
			(start -0.508 0.9398)
			(end 0.508 -0.9398)
			(stroke
				(width 0)
				(type default)
			)
			(fill no)
			(layer "F.CrtYd")
		)
		(fp_rect
			(start -0.508 0.9398)
			(end 0.508 -0.9398)
			(stroke
				(width 0)
				(type default)
			)
			(fill no)
			(layer "F.Fab")
		)
		(pad "1" smd custom
			(at 0 -0.4445)
			(size 0.1397 0.1397)
			(layers "F.Cu" "F.Mask" "F.Paste")
			(net "P3V3")
			(options
				(clearance outline)
				(anchor circle)
			)
			(primitives
				(gr_poly
					(pts
						(arc
							(start -0.1778 -0.2794)
							(mid -0.249642 -0.249642)
							(end -0.2794 -0.1778)
						)
						(arc
							(start -0.2794 0.1778)
							(mid -0.249642 0.249642)
							(end -0.1778 0.2794)
						)
						(arc
							(start 0.1778 0.2794)
							(mid 0.249642 0.249642)
							(end 0.2794 0.1778)
						)
						(arc
							(start 0.2794 -0.1778)
							(mid 0.249642 -0.249642)
							(end 0.1778 -0.2794)
						)
					)
					(width 0)
					(fill yes)
				)
			)
		)
		(pad "2" smd custom
			(at 0 0.4445)
			(size 0.1397 0.1397)
			(layers "F.Cu" "F.Mask" "F.Paste")
			(net "LED_DR_LED5")
			(options
				(clearance outline)
				(anchor circle)
			)
			(primitives
				(gr_poly
					(pts
						(arc
							(start -0.1778 -0.2794)
							(mid -0.249642 -0.249642)
							(end -0.2794 -0.1778)
						)
						(arc
							(start -0.2794 0.1778)
							(mid -0.249642 0.249642)
							(end -0.1778 0.2794)
						)
						(arc
							(start 0.1778 0.2794)
							(mid 0.249642 0.249642)
							(end 0.2794 0.1778)
						)
						(arc
							(start 0.2794 -0.1778)
							(mid 0.249642 -0.249642)
							(end 0.1778 -0.2794)
						)
					)
					(width 0)
					(fill yes)
				)
			)
		)
	)
	(footprint ""
		(layer "F.Cu")
		(at 29.1084 -170.3324 90)
		(property "Reference" "R176"
			(at 0 0 90)
			(layer "F.SilkS")
			(hide yes)
			(effects
				(font
					(size 1.27 1.27)
				)
			)
		)
		(property "Value" "0R2J-2-GP"
			(at 0.064008 -3.993896 90)
			(unlocked yes)
			(layer "F.Fab")
			(hide yes)
			(effects
				(font
					(size 1.016 1.016)
					(thickness 0.1524)
				)
			)
		)
		(property "Device Type" "R402H16"
			(at 0.064008 -5.517896 90)
			(unlocked yes)
			(layer "F.Fab")
			(hide yes)
			(effects
				(font
					(size 1.016 1.016)
					(thickness 0.1524)
				)
			)
		)
		(duplicate_pad_numbers_are_jumpers no)
		(fp_line
			(start 0.508 -0.9398)
			(end -0.508 -0.9398)
			(stroke
				(width 0.1524)
				(type default)
			)
			(layer "F.SilkS")
		)
		(fp_line
			(start -0.508 -0.9398)
			(end -0.508 0.9398)
			(stroke
				(width 0.1524)
				(type default)
			)
			(layer "F.SilkS")
		)
		(fp_rect
			(start -0.508 0.9398)
			(end 0.508 -0.9398)
			(stroke
				(width 0)
				(type default)
			)
			(fill no)
			(layer "F.CrtYd")
		)
		(fp_rect
			(start -0.508 0.9398)
			(end 0.508 -0.9398)
			(stroke
				(width 0)
				(type default)
			)
			(fill no)
			(layer "F.Fab")
		)
		(pad "1" smd custom
			(at 0 -0.4445 90)
			(size 0.1397 0.1397)
			(layers "F.Cu" "F.Mask" "F.Paste")
			(net "PWM_OUT")
			(options
				(clearance outline)
				(anchor circle)
			)
			(primitives
				(gr_poly
					(pts
						(arc
							(start -0.1778 -0.2794)
							(mid -0.249642 -0.249642)
							(end -0.2794 -0.1778)
						)
						(arc
							(start -0.2794 0.1778)
							(mid -0.249642 0.249642)
							(end -0.1778 0.2794)
						)
						(arc
							(start 0.1778 0.2794)
							(mid 0.249642 0.249642)
							(end 0.2794 0.1778)
						)
						(arc
							(start 0.2794 -0.1778)
							(mid 0.249642 -0.249642)
							(end 0.1778 -0.2794)
						)
					)
					(width 0)
					(fill yes)
				)
			)
		)
		(pad "2" smd custom
			(at 0 0.4445 90)
			(size 0.1397 0.1397)
			(layers "F.Cu" "F.Mask" "F.Paste")
			(net "PWM_BUFFER_IN_FAN1_FAN2")
			(options
				(clearance outline)
				(anchor circle)
			)
			(primitives
				(gr_poly
					(pts
						(arc
							(start -0.1778 -0.2794)
							(mid -0.249642 -0.249642)
							(end -0.2794 -0.1778)
						)
						(arc
							(start -0.2794 0.1778)
							(mid -0.249642 0.249642)
							(end -0.1778 0.2794)
						)
						(arc
							(start 0.1778 0.2794)
							(mid 0.249642 0.249642)
							(end 0.2794 0.1778)
						)
						(arc
							(start 0.2794 -0.1778)
							(mid 0.249642 -0.249642)
							(end 0.1778 -0.2794)
						)
					)
					(width 0)
					(fill yes)
				)
			)
		)
	)
	(footprint ""
		(layer "F.Cu")
		(at 21.7424 -21.8948)
		(property "Reference" "F1"
			(at 0 0 0)
			(layer "F.SilkS")
			(hide yes)
			(effects
				(font
					(size 1.27 1.27)
				)
			)
		)
		(property "Value" "FUSE-3A15V-GP"
			(at 0.2286 -10.5918 0)
			(unlocked yes)
			(layer "F.Fab")
			(hide yes)
			(effects
				(font
					(size 1.016 1.016)
					(thickness 0.1524)
				)
			)
		)
		(property "Device Type" "FUSE-7452-UH50"
			(at 0.2286 -12.4968 0)
			(unlocked yes)
			(layer "F.Fab")
			(hide yes)
			(effects
				(font
					(size 1.016 1.016)
					(thickness 0.1524)
				)
			)
		)
		(duplicate_pad_numbers_are_jumpers no)
		(fp_line
			(start -4.9276 -2.921)
			(end 4.9276 -2.921)
			(stroke
				(width 0.1524)
				(type default)
			)
			(layer "F.SilkS")
		)
		(fp_line
			(start -4.9276 2.921)
			(end -4.9276 -2.921)
			(stroke
				(width 0.1524)
				(type default)
			)
			(layer "F.SilkS")
		)
		(fp_line
			(start 4.9276 -2.921)
			(end 4.9276 2.921)
			(stroke
				(width 0.1524)
				(type default)
			)
			(layer "F.SilkS")
		)
		(fp_line
			(start 4.9276 2.921)
			(end -4.9276 2.921)
			(stroke
				(width 0.1524)
				(type default)
			)
			(layer "F.SilkS")
		)
		(fp_poly
			(pts
				(xy -5.08 3.0988) (xy 5.08 3.0988) (xy 5.08 -3.0988) (xy -5.08 -3.0988)
			)
			(stroke
				(width 0)
				(type default)
			)
			(fill no)
			(layer "F.CrtYd")
		)
		(fp_poly
			(pts
				(xy -5.08 -3.0988) (xy 5.08 -3.0988) (xy 5.08 3.0988) (xy -5.08 3.0988)
			)
			(stroke
				(width 0)
				(type default)
			)
			(fill no)
			(layer "F.Fab")
		)
		(pad "1" smd rect
			(at -3.4036 0)
			(size 2.2098 5.2832)
			(layers "F.Cu" "F.Mask" "F.Paste")
			(net "P12V_FAN6")
		)
		(pad "2" smd rect
			(at 3.4036 0)
			(size 2.2098 5.2832)
			(layers "F.Cu" "F.Mask" "F.Paste")
			(net "P12V")
		)
	)
	(footprint ""
		(layer "F.Cu")
		(at 26.67 -153.2128 180)
		(property "Reference" "TP1"
			(at 0 0 180)
			(layer "F.SilkS")
			(hide yes)
			(effects
				(font
					(size 1.27 1.27)
				)
			)
		)
		(property "Value" "TPAD32-GP"
			(at 0 -3.166364 180)
			(unlocked yes)
			(layer "F.Fab")
			(hide yes)
			(effects
				(font
					(size 1.016 1.016)
					(thickness 0.1524)
				)
			)
		)
		(property "Device Type" "TPAD32"
			(at 0 -4.690618 180)
			(unlocked yes)
			(layer "F.Fab")
			(hide yes)
			(effects
				(font
					(size 1.016 1.016)
					(thickness 0.1524)
				)
			)
		)
		(duplicate_pad_numbers_are_jumpers no)
		(fp_poly
			(pts
				(arc
					(start -0.7112 0)
					(mid 0.7112 0)
					(end -0.7112 0)
				)
			)
			(stroke
				(width 0)
				(type default)
			)
			(fill no)
			(layer "F.CrtYd")
		)
		(fp_poly
			(pts
				(arc
					(start -0.7112 0)
					(mid 0.7112 0)
					(end -0.7112 0)
				)
			)
			(stroke
				(width 0)
				(type default)
			)
			(fill no)
			(layer "F.Fab")
		)
		(pad "1" smd circle
			(at 0 0 180)
			(size 0.8128 0.8128)
			(layers "F.Cu" "F.Mask" "F.Paste")
			(net "NCT7904_VREF")
		)
	)
	(footprint ""
		(layer "F.Cu")
		(at 21.0058 -247.9802 90)
		(property "Reference" "U4"
			(at 0 0 90)
			(layer "F.SilkS")
			(hide yes)
			(effects
				(font
					(size 1.27 1.27)
				)
			)
		)
		(property "Value" "SY8201ABC-GP"
			(at -0.0254 -11.9634 90)
			(unlocked yes)
			(layer "F.Fab")
			(hide yes)
			(effects
				(font
					(size 1.016 1.016)
					(thickness 0.1524)
				)
			)
		)
		(property "Device Type" "SOT-6H56"
			(at -0.0254 -13.5636 90)
			(unlocked yes)
			(layer "F.Fab")
			(hide yes)
			(effects
				(font
					(size 1.016 1.016)
					(thickness 0.1524)
				)
			)
		)
		(duplicate_pad_numbers_are_jumpers no)
		(fp_line
			(start 1.7145 -0.5842)
			(end -1.9685 -0.5842)
			(stroke
				(width 0.1524)
				(type default)
			)
			(layer "F.SilkS")
		)
		(fp_line
			(start -1.9685 -0.5842)
			(end -1.9685 0.5842)
			(stroke
				(width 0.1524)
				(type default)
			)
			(layer "F.SilkS")
		)
		(fp_line
			(start -1.9685 -0.4064)
			(end -1.5621 0)
			(stroke
				(width 0.1524)
				(type default)
			)
			(layer "F.SilkS")
		)
		(fp_line
			(start -1.5621 0)
			(end -1.9685 0.4064)
			(stroke
				(width 0.1524)
				(type default)
			)
			(layer "F.SilkS")
		)
		(fp_line
			(start 1.7145 0.5842)
			(end 1.7145 -0.5842)
			(stroke
				(width 0.1524)
				(type default)
			)
			(layer "F.SilkS")
		)
		(fp_line
			(start -1.9685 0.5842)
			(end 1.7145 0.5842)
			(stroke
				(width 0.1524)
				(type default)
			)
			(layer "F.SilkS")
		)
		(fp_line
			(start -1.9685 0.5842)
			(end -1.9685 2.3622)
			(stroke
				(width 0.508)
				(type default)
			)
			(layer "F.SilkS")
		)
		(fp_poly
			(pts
				(xy -1.27 -0.635) (xy 1.27 -0.635) (xy 1.27 0.635) (xy -1.27 0.635)
			)
			(stroke
				(width 0)
				(type default)
			)
			(fill yes)
			(layer "F.SilkS")
		)
		(fp_rect
			(start -1.9685 2.3622)
			(end 1.9685 -2.3622)
			(stroke
				(width 0)
				(type default)
			)
			(fill no)
			(layer "F.CrtYd")
		)
		(fp_poly
			(pts
				(xy -1.9685 -2.3622) (xy 1.9685 -2.3622) (xy 1.9685 2.3622) (xy -1.9685 2.3622)
			)
			(stroke
				(width 0)
				(type default)
			)
			(fill no)
			(layer "F.Fab")
		)
		(pad "1" smd rect
			(at -0.9525 1.3462 90)
			(size 0.5842 1.016)
			(layers "F.Cu" "F.Mask" "F.Paste")
			(net "P3V3_BS_NET")
		)
		(pad "2" smd rect
			(at 0 1.3462 90)
			(size 0.5842 1.016)
			(layers "F.Cu" "F.Mask" "F.Paste")
			(net "GND")
		)
		(pad "3" smd rect
			(at 0.9525 1.3462 90)
			(size 0.5842 1.016)
			(layers "F.Cu" "F.Mask" "F.Paste")
			(net "P3V3_FB")
		)
		(pad "4" smd rect
			(at 0.9525 -1.3462 90)
			(size 0.5842 1.016)
			(layers "F.Cu" "F.Mask" "F.Paste")
			(net "P3V3_EN")
		)
		(pad "5" smd rect
			(at 0 -1.3462 90)
			(size 0.5842 1.016)
			(layers "F.Cu" "F.Mask" "F.Paste")
			(net "P3V3_IN")
		)
		(pad "6" smd rect
			(at -0.9525 -1.3462 90)
			(size 0.5842 1.016)
			(layers "F.Cu" "F.Mask" "F.Paste")
			(net "P3V3_LX")
		)
	)
	(footprint ""
		(layer "F.Cu")
		(at 23.622 -364.4646 -90)
		(property "Reference" "PC3"
			(at 0 0 270)
			(layer "F.SilkS")
			(hide yes)
			(effects
				(font
					(size 1.27 1.27)
				)
			)
		)
		(property "Value" "SCD01U25V2KX-3GP"
			(at 1.1811 -2.7051 270)
			(unlocked yes)
			(layer "F.Fab")
			(hide yes)
			(effects
				(font
					(size 1.016 1.016)
					(thickness 0.1524)
				)
			)
		)
		(property "Device Type" "C402H22"
			(at 1.1811 -4.2291 270)
			(unlocked yes)
			(layer "F.Fab")
			(hide yes)
			(effects
				(font
					(size 1.016 1.016)
					(thickness 0.1524)
				)
			)
		)
		(duplicate_pad_numbers_are_jumpers no)
		(fp_rect
			(start -0.4318 0.9525)
			(end 0.4318 -0.9525)
			(stroke
				(width 0)
				(type default)
			)
			(fill no)
			(layer "F.CrtYd")
		)
		(fp_rect
			(start -0.4318 0.9525)
			(end 0.4318 -0.9525)
			(stroke
				(width 0)
				(type default)
			)
			(fill no)
			(layer "F.Fab")
		)
		(pad "1" smd custom
			(at 0 -0.4445 270)
			(size 0.1524 0.1524)
			(layers "F.Cu" "F.Mask" "F.Paste")
			(net "ADM1276_SS")
			(options
				(clearance outline)
				(anchor circle)
			)
			(primitives
				(gr_poly
					(pts
						(arc
							(start 0.3048 -0.2032)
							(mid 0.275042 -0.275042)
							(end 0.2032 -0.3048)
						)
						(arc
							(start -0.2032 -0.3048)
							(mid -0.275042 -0.275042)
							(end -0.3048 -0.2032)
						)
						(arc
							(start -0.3048 0.2032)
							(mid -0.275042 0.275042)
							(end -0.2032 0.3048)
						)
						(arc
							(start 0.2032 0.3048)
							(mid 0.275042 0.275042)
							(end 0.3048 0.2032)
						)
					)
					(width 0)
					(fill yes)
				)
			)
		)
		(pad "2" smd custom
			(at 0 0.4445 270)
			(size 0.1524 0.1524)
			(layers "F.Cu" "F.Mask" "F.Paste")
			(net "GND")
			(options
				(clearance outline)
				(anchor circle)
			)
			(primitives
				(gr_poly
					(pts
						(arc
							(start 0.3048 -0.2032)
							(mid 0.275042 -0.275042)
							(end 0.2032 -0.3048)
						)
						(arc
							(start -0.2032 -0.3048)
							(mid -0.275042 -0.275042)
							(end -0.3048 -0.2032)
						)
						(arc
							(start -0.3048 0.2032)
							(mid -0.275042 0.275042)
							(end -0.2032 0.3048)
						)
						(arc
							(start 0.2032 0.3048)
							(mid 0.275042 0.275042)
							(end 0.3048 0.2032)
						)
					)
					(width 0)
					(fill yes)
				)
			)
		)
	)
	(footprint ""
		(layer "F.Cu")
		(at 16.51 -148.336 -90)
		(property "Reference" "D4"
			(at 0 0 270)
			(layer "F.SilkS")
			(hide yes)
			(effects
				(font
					(size 1.27 1.27)
				)
			)
		)
		(property "Value" "BAS16H-GP"
			(at 0 -5.5372 270)
			(unlocked yes)
			(layer "F.Fab")
			(hide yes)
			(effects
				(font
					(size 1.016 1.016)
					(thickness 0.1524)
				)
			)
		)
		(property "Device Type" "SOD123AKH48"
			(at 0 -7.0612 270)
			(unlocked yes)
			(layer "F.Fab")
			(hide yes)
			(effects
				(font
					(size 1.016 1.016)
					(thickness 0.1524)
				)
			)
		)
		(duplicate_pad_numbers_are_jumpers no)
		(fp_line
			(start 0.889 2.921)
			(end -0.889 2.921)
			(stroke
				(width 0.508)
				(type default)
			)
			(layer "F.SilkS")
		)
		(fp_line
			(start -1.016 2.667)
			(end 1.016 2.667)
			(stroke
				(width 0.1524)
				(type default)
			)
			(layer "F.SilkS")
		)
		(fp_line
			(start 1.016 2.667)
			(end 1.016 -2.667)
			(stroke
				(width 0.1524)
				(type default)
			)
			(layer "F.SilkS")
		)
		(fp_line
			(start -1.016 -2.667)
			(end -1.016 2.667)
			(stroke
				(width 0.1524)
				(type default)
			)
			(layer "F.SilkS")
		)
		(fp_line
			(start 1.016 -2.667)
			(end -1.016 -2.667)
			(stroke
				(width 0.1524)
				(type default)
			)
			(layer "F.SilkS")
		)
		(fp_rect
			(start -1.143 3.175)
			(end 1.143 -2.794)
			(stroke
				(width 0)
				(type default)
			)
			(fill no)
			(layer "F.CrtYd")
		)
		(fp_poly
			(pts
				(xy -1.143 -2.794) (xy 1.143 -2.794) (xy 1.143 3.175) (xy -1.143 3.175)
			)
			(stroke
				(width 0)
				(type default)
			)
			(fill no)
			(layer "F.Fab")
		)
		(pad "A" smd rect
			(at 0 -1.6891 270)
			(size 0.889 1.397)
			(layers "F.Cu" "F.Mask" "F.Paste")
			(net "FAN_TACH9")
		)
		(pad "K" smd rect
			(at 0 1.6891 270)
			(size 0.889 1.397)
			(layers "F.Cu" "F.Mask" "F.Paste")
			(net "P12V")
		)
	)
	(footprint ""
		(layer "F.Cu")
		(at 9.906 -147.2184 180)
		(property "Reference" "R66"
			(at 0 0 180)
			(layer "F.SilkS")
			(hide yes)
			(effects
				(font
					(size 1.27 1.27)
				)
			)
		)
		(property "Value" "4K7R2F-GP"
			(at 0.064008 -3.993896 180)
			(unlocked yes)
			(layer "F.Fab")
			(hide yes)
			(effects
				(font
					(size 1.016 1.016)
					(thickness 0.1524)
				)
			)
		)
		(property "Device Type" "R402H16"
			(at 0.064008 -5.517896 180)
			(unlocked yes)
			(layer "F.Fab")
			(hide yes)
			(effects
				(font
					(size 1.016 1.016)
					(thickness 0.1524)
				)
			)
		)
		(duplicate_pad_numbers_are_jumpers no)
		(fp_line
			(start 0.508 -0.9398)
			(end -0.508 -0.9398)
			(stroke
				(width 0.1524)
				(type default)
			)
			(layer "F.SilkS")
		)
		(fp_line
			(start -0.508 -0.9398)
			(end -0.508 0.9398)
			(stroke
				(width 0.1524)
				(type default)
			)
			(layer "F.SilkS")
		)
		(fp_rect
			(start -0.508 0.9398)
			(end 0.508 -0.9398)
			(stroke
				(width 0)
				(type default)
			)
			(fill no)
			(layer "F.CrtYd")
		)
		(fp_rect
			(start -0.508 0.9398)
			(end 0.508 -0.9398)
			(stroke
				(width 0)
				(type default)
			)
			(fill no)
			(layer "F.Fab")
		)
		(pad "1" smd custom
			(at 0 -0.4445 180)
			(size 0.1397 0.1397)
			(layers "F.Cu" "F.Mask" "F.Paste")
			(net "P12V")
			(options
				(clearance outline)
				(anchor circle)
			)
			(primitives
				(gr_poly
					(pts
						(arc
							(start -0.1778 -0.2794)
							(mid -0.249642 -0.249642)
							(end -0.2794 -0.1778)
						)
						(arc
							(start -0.2794 0.1778)
							(mid -0.249642 0.249642)
							(end -0.1778 0.2794)
						)
						(arc
							(start 0.1778 0.2794)
							(mid 0.249642 0.249642)
							(end 0.2794 0.1778)
						)
						(arc
							(start 0.2794 -0.1778)
							(mid 0.249642 -0.249642)
							(end 0.1778 -0.2794)
						)
					)
					(width 0)
					(fill yes)
				)
			)
		)
		(pad "2" smd custom
			(at 0 0.4445 180)
			(size 0.1397 0.1397)
			(layers "F.Cu" "F.Mask" "F.Paste")
			(net "FAN_TACH10")
			(options
				(clearance outline)
				(anchor circle)
			)
			(primitives
				(gr_poly
					(pts
						(arc
							(start -0.1778 -0.2794)
							(mid -0.249642 -0.249642)
							(end -0.2794 -0.1778)
						)
						(arc
							(start -0.2794 0.1778)
							(mid -0.249642 0.249642)
							(end -0.1778 0.2794)
						)
						(arc
							(start 0.1778 0.2794)
							(mid 0.249642 0.249642)
							(end 0.2794 0.1778)
						)
						(arc
							(start 0.2794 -0.1778)
							(mid 0.249642 -0.249642)
							(end 0.1778 -0.2794)
						)
					)
					(width 0)
					(fill yes)
				)
			)
		)
	)
	(footprint ""
		(layer "F.Cu")
		(at 20.500086 -56.999886 -90)
		(property "Reference" "CN9"
			(at 0 0 270)
			(layer "F.SilkS")
			(hide yes)
			(effects
				(font
					(size 1.27 1.27)
				)
			)
		)
		(property "Value" "FCI-CONN52-4R-1-GP"
			(at -30.89656 -6.096 270)
			(unlocked yes)
			(layer "F.Fab")
			(hide yes)
			(effects
				(font
					(size 1.016 1.016)
					(thickness 0.1524)
				)
			)
		)
		(property "Device Type" "51952-220LF"
			(at -30.89656 -7.62 270)
			(unlocked yes)
			(layer "F.Fab")
			(hide yes)
			(effects
				(font
					(size 1.016 1.016)
					(thickness 0.1524)
				)
			)
		)
		(duplicate_pad_numbers_are_jumpers no)
		(fp_line
			(start -29.464 3.7338)
			(end -29.464 -3.7338)
			(stroke
				(width 0.1524)
				(type default)
			)
			(layer "F.SilkS")
		)
		(fp_line
			(start 29.464 3.7338)
			(end -29.464 3.7338)
			(stroke
				(width 0.1524)
				(type default)
			)
			(layer "F.SilkS")
		)
		(fp_line
			(start -29.464 -3.7338)
			(end -22.225 -3.7338)
			(stroke
				(width 0.1524)
				(type default)
			)
			(layer "F.SilkS")
		)
		(fp_line
			(start -22.225 -3.7338)
			(end -22.225 -11.3538)
			(stroke
				(width 0.1524)
				(type default)
			)
			(layer "F.SilkS")
		)
		(fp_line
			(start 22.225 -3.7338)
			(end 29.464 -3.7338)
			(stroke
				(width 0.1524)
				(type default)
			)
			(layer "F.SilkS")
		)
		(fp_line
			(start 29.464 -3.7338)
			(end 29.464 3.7338)
			(stroke
				(width 0.1524)
				(type default)
			)
			(layer "F.SilkS")
		)
		(fp_line
			(start -22.225 -11.3538)
			(end 22.225 -11.3538)
			(stroke
				(width 0.1524)
				(type default)
			)
			(layer "F.SilkS")
		)
		(fp_line
			(start 22.225 -11.3538)
			(end 22.225 -3.7338)
			(stroke
				(width 0.1524)
				(type default)
			)
			(layer "F.SilkS")
		)
		(fp_circle
			(center -15.88008 0)
			(end -15.88008 -1.0795)
			(stroke
				(width 0.3048)
				(type default)
			)
			(fill no)
			(layer "F.SilkS")
		)
		(fp_circle
			(center -13.34008 0)
			(end -13.34008 -1.0795)
			(stroke
				(width 0.3048)
				(type default)
			)
			(fill no)
			(layer "F.SilkS")
		)
		(fp_circle
			(center -10.80008 0)
			(end -10.80008 -1.0795)
			(stroke
				(width 0.3048)
				(type default)
			)
			(fill no)
			(layer "F.SilkS")
		)
		(fp_circle
			(center -8.26008 0)
			(end -8.26008 -1.0795)
			(stroke
				(width 0.3048)
				(type default)
			)
			(fill no)
			(layer "F.SilkS")
		)
		(fp_circle
			(center -5.08 0)
			(end -5.08 -1.0795)
			(stroke
				(width 0.3048)
				(type default)
			)
			(fill no)
			(layer "F.SilkS")
		)
		(fp_circle
			(center -2.54 0)
			(end -2.54 -1.0795)
			(stroke
				(width 0.3048)
				(type default)
			)
			(fill no)
			(layer "F.SilkS")
		)
		(fp_circle
			(center 0 0)
			(end 0 -1.0795)
			(stroke
				(width 0.3048)
				(type default)
			)
			(fill no)
			(layer "F.SilkS")
		)
		(fp_circle
			(center 2.54 0)
			(end 2.54 -1.0795)
			(stroke
				(width 0.3048)
				(type default)
			)
			(fill no)
			(layer "F.SilkS")
		)
		(fp_circle
			(center 5.08 0)
			(end 5.08 -1.0795)
			(stroke
				(width 0.3048)
				(type default)
			)
			(fill no)
			(layer "F.SilkS")
		)
		(fp_circle
			(center 8.26008 0)
			(end 8.26008 -1.0795)
			(stroke
				(width 0.3048)
				(type default)
			)
			(fill no)
			(layer "F.SilkS")
		)
		(fp_circle
			(center 10.80008 0)
			(end 10.80008 -1.0795)
			(stroke
				(width 0.3048)
				(type default)
			)
			(fill no)
			(layer "F.SilkS")
		)
		(fp_circle
			(center 13.34008 0)
			(end 13.34008 -1.0795)
			(stroke
				(width 0.3048)
				(type default)
			)
			(fill no)
			(layer "F.SilkS")
		)
		(fp_circle
			(center 15.88008 0)
			(end 15.88008 -1.0795)
			(stroke
				(width 0.3048)
				(type default)
			)
			(fill no)
			(layer "F.SilkS")
		)
		(fp_circle
			(center -15.88008 -2.54)
			(end -15.88008 -3.6195)
			(stroke
				(width 0.3048)
				(type default)
			)
			(fill no)
			(layer "F.SilkS")
		)
		(fp_circle
			(center -13.34008 -2.54)
			(end -13.34008 -3.6195)
			(stroke
				(width 0.3048)
				(type default)
			)
			(fill no)
			(layer "F.SilkS")
		)
		(fp_circle
			(center -10.80008 -2.54)
			(end -10.80008 -3.6195)
			(stroke
				(width 0.3048)
				(type default)
			)
			(fill no)
			(layer "F.SilkS")
		)
		(fp_circle
			(center -8.26008 -2.54)
			(end -8.26008 -3.6195)
			(stroke
				(width 0.3048)
				(type default)
			)
			(fill no)
			(layer "F.SilkS")
		)
		(fp_circle
			(center -5.08 -2.54)
			(end -5.08 -3.6195)
			(stroke
				(width 0.3048)
				(type default)
			)
			(fill no)
			(layer "F.SilkS")
		)
		(fp_circle
			(center -2.54 -2.54)
			(end -2.54 -3.6195)
			(stroke
				(width 0.3048)
				(type default)
			)
			(fill no)
			(layer "F.SilkS")
		)
		(fp_circle
			(center 0 -2.54)
			(end 0 -3.6195)
			(stroke
				(width 0.3048)
				(type default)
			)
			(fill no)
			(layer "F.SilkS")
		)
		(fp_circle
			(center 2.54 -2.54)
			(end 2.54 -3.6195)
			(stroke
				(width 0.3048)
				(type default)
			)
			(fill no)
			(layer "F.SilkS")
		)
		(fp_circle
			(center 5.08 -2.54)
			(end 5.08 -3.6195)
			(stroke
				(width 0.3048)
				(type default)
			)
			(fill no)
			(layer "F.SilkS")
		)
		(fp_circle
			(center 8.26008 -2.54)
			(end 8.26008 -3.6195)
			(stroke
				(width 0.3048)
				(type default)
			)
			(fill no)
			(layer "F.SilkS")
		)
		(fp_circle
			(center 10.80008 -2.54)
			(end 10.80008 -3.6195)
			(stroke
				(width 0.3048)
				(type default)
			)
			(fill no)
			(layer "F.SilkS")
		)
		(fp_circle
			(center 13.34008 -2.54)
			(end 13.34008 -3.6195)
			(stroke
				(width 0.3048)
				(type default)
			)
			(fill no)
			(layer "F.SilkS")
		)
		(fp_circle
			(center 15.88008 -2.54)
			(end 15.88008 -3.6195)
			(stroke
				(width 0.3048)
				(type default)
			)
			(fill no)
			(layer "F.SilkS")
		)
		(fp_circle
			(center -15.88008 -5.08)
			(end -15.88008 -6.1595)
			(stroke
				(width 0.3048)
				(type default)
			)
			(fill no)
			(layer "F.SilkS")
		)
		(fp_circle
			(center -13.34008 -5.08)
			(end -13.34008 -6.1595)
			(stroke
				(width 0.3048)
				(type default)
			)
			(fill no)
			(layer "F.SilkS")
		)
		(fp_circle
			(center -10.80008 -5.08)
			(end -10.80008 -6.1595)
			(stroke
				(width 0.3048)
				(type default)
			)
			(fill no)
			(layer "F.SilkS")
		)
		(fp_circle
			(center -8.26008 -5.08)
			(end -8.26008 -6.1595)
			(stroke
				(width 0.3048)
				(type default)
			)
			(fill no)
			(layer "F.SilkS")
		)
		(fp_circle
			(center -5.08 -5.08)
			(end -5.08 -6.1595)
			(stroke
				(width 0.3048)
				(type default)
			)
			(fill no)
			(layer "F.SilkS")
		)
		(fp_circle
			(center -2.54 -5.08)
			(end -2.54 -6.1595)
			(stroke
				(width 0.3048)
				(type default)
			)
			(fill no)
			(layer "F.SilkS")
		)
		(fp_circle
			(center 0 -5.08)
			(end 0 -6.1595)
			(stroke
				(width 0.3048)
				(type default)
			)
			(fill no)
			(layer "F.SilkS")
		)
		(fp_circle
			(center 2.54 -5.08)
			(end 2.54 -6.1595)
			(stroke
				(width 0.3048)
				(type default)
			)
			(fill no)
			(layer "F.SilkS")
		)
		(fp_circle
			(center 5.08 -5.08)
			(end 5.08 -6.1595)
			(stroke
				(width 0.3048)
				(type default)
			)
			(fill no)
			(layer "F.SilkS")
		)
		(fp_circle
			(center 8.26008 -5.08)
			(end 8.26008 -6.1595)
			(stroke
				(width 0.3048)
				(type default)
			)
			(fill no)
			(layer "F.SilkS")
		)
		(fp_circle
			(center 10.80008 -5.08)
			(end 10.80008 -6.1595)
			(stroke
				(width 0.3048)
				(type default)
			)
			(fill no)
			(layer "F.SilkS")
		)
		(fp_circle
			(center 13.34008 -5.08)
			(end 13.34008 -6.1595)
			(stroke
				(width 0.3048)
				(type default)
			)
			(fill no)
			(layer "F.SilkS")
		)
		(fp_circle
			(center 15.88008 -5.08)
			(end 15.88008 -6.1595)
			(stroke
				(width 0.3048)
				(type default)
			)
			(fill no)
			(layer "F.SilkS")
		)
		(fp_circle
			(center -15.88008 -7.62)
			(end -15.88008 -8.6995)
			(stroke
				(width 0.3048)
				(type default)
			)
			(fill no)
			(layer "F.SilkS")
		)
		(fp_circle
			(center -13.34008 -7.62)
			(end -13.34008 -8.6995)
			(stroke
				(width 0.3048)
				(type default)
			)
			(fill no)
			(layer "F.SilkS")
		)
		(fp_circle
			(center -10.80008 -7.62)
			(end -10.80008 -8.6995)
			(stroke
				(width 0.3048)
				(type default)
			)
			(fill no)
			(layer "F.SilkS")
		)
		(fp_circle
			(center -8.26008 -7.62)
			(end -8.26008 -8.6995)
			(stroke
				(width 0.3048)
				(type default)
			)
			(fill no)
			(layer "F.SilkS")
		)
		(fp_circle
			(center -5.08 -7.62)
			(end -5.08 -8.6995)
			(stroke
				(width 0.3048)
				(type default)
			)
			(fill no)
			(layer "F.SilkS")
		)
		(fp_circle
			(center -2.54 -7.62)
			(end -2.54 -8.6995)
			(stroke
				(width 0.3048)
				(type default)
			)
			(fill no)
			(layer "F.SilkS")
		)
		(fp_circle
			(center 0 -7.62)
			(end 0 -8.6995)
			(stroke
				(width 0.3048)
				(type default)
			)
			(fill no)
			(layer "F.SilkS")
		)
		(fp_circle
			(center 2.54 -7.62)
			(end 2.54 -8.6995)
			(stroke
				(width 0.3048)
				(type default)
			)
			(fill no)
			(layer "F.SilkS")
		)
		(fp_circle
			(center 5.08 -7.62)
			(end 5.08 -8.6995)
			(stroke
				(width 0.3048)
				(type default)
			)
			(fill no)
			(layer "F.SilkS")
		)
		(fp_circle
			(center 8.26008 -7.62)
			(end 8.26008 -8.6995)
			(stroke
				(width 0.3048)
				(type default)
			)
			(fill no)
			(layer "F.SilkS")
		)
		(fp_circle
			(center 10.80008 -7.62)
			(end 10.80008 -8.6995)
			(stroke
				(width 0.3048)
				(type default)
			)
			(fill no)
			(layer "F.SilkS")
		)
		(fp_circle
			(center 13.34008 -7.62)
			(end 13.34008 -8.6995)
			(stroke
				(width 0.3048)
				(type default)
			)
			(fill no)
			(layer "F.SilkS")
		)
		(fp_circle
			(center 15.88008 -7.62)
			(end 15.88008 -8.6995)
			(stroke
				(width 0.3048)
				(type default)
			)
			(fill no)
			(layer "F.SilkS")
		)
		(fp_poly
			(pts
				(xy -29.21 3.4798) (xy -29.21 -3.4798) (xy -21.971 -3.4798) (xy -21.971 -11.0998) (xy 21.971 -11.0998)
				(xy 21.971 -3.4798) (xy 29.21 -3.4798) (xy 29.21 3.4798)
			)
			(stroke
				(width 0)
				(type default)
			)
			(fill no)
			(layer "F.CrtYd")
		)
		(fp_poly
			(pts
				(xy -29.718 3.9878) (xy -29.718 -11.6078) (xy 29.718 -11.6078) (xy 29.718 -0.00635) (xy 29.21 -0.00635)
				(xy 29.21 -3.4798) (xy 21.971 -3.4798) (xy 21.971 -11.0998) (xy -21.971 -11.0998) (xy -21.971 -3.4798)
				(xy -29.21 -3.4798) (xy -29.21 3.4798) (xy 29.21 3.4798) (xy 29.21 0.00635) (xy 29.718 0.00635)
				(xy 29.718 3.9878)
			)
			(stroke
				(width 0)
				(type default)
			)
			(fill no)
			(layer "F.CrtYd")
		)
		(fp_poly
			(pts
				(xy -29.718 3.9878) (xy -29.718 -11.6078) (xy 29.718 -11.6078) (xy 29.718 3.9878)
			)
			(stroke
				(width 0)
				(type default)
			)
			(fill no)
			(layer "F.Fab")
		)
		(pad "" np_thru_hole circle
			(at -26.67 0 270)
			(size 0.254 0.254)
			(drill 3.2004)
			(layers "*.Cu" "*.Mask")
			(clearance 1.8288)
			(thermal_gap 1.8288)
		)
		(pad "" np_thru_hole circle
			(at -21.59 0 270)
			(size 0.254 0.254)
			(drill 2.5146)
			(layers "*.Cu" "*.Mask")
			(clearance 1.4859)
			(thermal_gap 1.4859)
		)
		(pad "" np_thru_hole circle
			(at 21.59 0 270)
			(size 0.254 0.254)
			(drill 2.5146)
			(layers "*.Cu" "*.Mask")
			(clearance 1.4859)
			(thermal_gap 1.4859)
		)
		(pad "" np_thru_hole circle
			(at 26.67 0 270)
			(size 0.254 0.254)
			(drill 3.2004)
			(layers "*.Cu" "*.Mask")
			(clearance 1.8288)
			(thermal_gap 1.8288)
		)
		(pad "A1" thru_hole circle
			(at -5.08 0 270)
			(size 1.4478 1.4478)
			(drill 1.0414)
			(layers "*.Cu" "*.Mask")
			(remove_unused_layers no)
			(net "I2C_C_SDA_CONN_R")
			(clearance 0.1524)
			(thermal_gap 0.1524)
		)
		(pad "A2" thru_hole circle
			(at -2.54 0 270)
			(size 1.4478 1.4478)
			(drill 1.0414)
			(layers "*.Cu" "*.Mask")
			(remove_unused_layers no)
			(net "GND")
			(clearance 0.1524)
			(thermal_gap 0.1524)
		)
		(pad "A3" thru_hole circle
			(at 0 0 270)
			(size 1.4478 1.4478)
			(drill 1.0414)
			(layers "*.Cu" "*.Mask")
			(remove_unused_layers no)
			(net "I2C_C_SCL_CONN_R")
			(clearance 0.1524)
			(thermal_gap 0.1524)
		)
		(pad "A4" thru_hole circle
			(at 2.54 0 270)
			(size 1.4478 1.4478)
			(drill 1.0414)
			(layers "*.Cu" "*.Mask")
			(remove_unused_layers no)
			(net "GND")
			(clearance 0.1524)
			(thermal_gap 0.1524)
		)
		(pad "A5" thru_hole circle
			(at 5.08 0 270)
			(size 1.4478 1.4478)
			(drill 1.0414)
			(layers "*.Cu" "*.Mask")
			(remove_unused_layers no)
			(net "PWM_EXP_1B")
			(clearance 0.1524)
			(thermal_gap 0.1524)
		)
		(pad "B1" thru_hole circle
			(at -5.08 -2.54 270)
			(size 1.4478 1.4478)
			(drill 1.0414)
			(layers "*.Cu" "*.Mask")
			(remove_unused_layers no)
			(net "GND")
			(clearance 0.1524)
			(thermal_gap 0.1524)
		)
		(pad "B2" thru_hole circle
			(at -2.54 -2.54 270)
			(size 1.4478 1.4478)
			(drill 1.0414)
			(layers "*.Cu" "*.Mask")
			(remove_unused_layers no)
			(net "PWM_EXP_1A")
			(clearance 0.1524)
			(thermal_gap 0.1524)
		)
		(pad "B3" thru_hole circle
			(at 0 -2.54 270)
			(size 1.4478 1.4478)
			(drill 1.0414)
			(layers "*.Cu" "*.Mask")
			(remove_unused_layers no)
			(net "GND")
			(clearance 0.1524)
			(thermal_gap 0.1524)
		)
		(pad "B4" thru_hole circle
			(at 2.54 -2.54 270)
			(size 1.4478 1.4478)
			(drill 1.0414)
			(layers "*.Cu" "*.Mask")
			(remove_unused_layers no)
			(net "SELF_1B_HB")
			(clearance 0.1524)
			(thermal_gap 0.1524)
		)
		(pad "B5" thru_hole circle
			(at 5.08 -2.54 270)
			(size 1.4478 1.4478)
			(drill 1.0414)
			(layers "*.Cu" "*.Mask")
			(remove_unused_layers no)
			(net "GND")
			(clearance 0.1524)
			(thermal_gap 0.1524)
		)
		(pad "C1" thru_hole circle
			(at -5.08 -5.08 270)
			(size 1.4478 1.4478)
			(drill 1.0414)
			(layers "*.Cu" "*.Mask")
			(remove_unused_layers no)
			(net "P12VU_2490_EN_1")
			(clearance 0.1524)
			(thermal_gap 0.1524)
		)
		(pad "C2" thru_hole circle
			(at -2.54 -5.08 270)
			(size 1.4478 1.4478)
			(drill 1.0414)
			(layers "*.Cu" "*.Mask")
			(remove_unused_layers no)
			(net "P12VU_2490_EN_2")
			(clearance 0.1524)
			(thermal_gap 0.1524)
		)
		(pad "C3" thru_hole circle
			(at 0 -5.08 270)
			(size 1.4478 1.4478)
			(drill 1.0414)
			(layers "*.Cu" "*.Mask")
			(remove_unused_layers no)
			(net "SELF_1A_HB")
			(clearance 0.1524)
			(thermal_gap 0.1524)
		)
		(pad "C4" thru_hole circle
			(at 2.54 -5.08 270)
			(size 1.4478 1.4478)
			(drill 1.0414)
			(layers "*.Cu" "*.Mask")
			(remove_unused_layers no)
			(net "SEB_PEER_1A_HB")
			(clearance 0.1524)
			(thermal_gap 0.1524)
		)
		(pad "C5" thru_hole circle
			(at 5.08 -5.08 270)
			(size 1.4478 1.4478)
			(drill 1.0414)
			(layers "*.Cu" "*.Mask")
			(remove_unused_layers no)
			(net "SEB_PEER_1B_HB")
			(clearance 0.1524)
			(thermal_gap 0.1524)
		)
		(pad "D1" thru_hole circle
			(at -5.08 -7.62 270)
			(size 1.4478 1.4478)
			(drill 1.0414)
			(layers "*.Cu" "*.Mask")
			(remove_unused_layers no)
			(net "PEER_TRAY PRESENT_UPPER")
			(clearance 0.1524)
			(thermal_gap 0.1524)
		)
		(pad "D2" thru_hole circle
			(at -2.54 -7.62 270)
			(size 1.4478 1.4478)
			(drill 1.0414)
			(layers "*.Cu" "*.Mask")
			(remove_unused_layers no)
			(net "UPPER_TRAY_ID")
			(clearance 0.1524)
			(thermal_gap 0.1524)
		)
		(pad "D3" thru_hole circle
			(at 0 -7.62 270)
			(size 1.4478 1.4478)
			(drill 1.0414)
			(layers "*.Cu" "*.Mask")
			(remove_unused_layers no)
			(net "FCB_HW_REVISION")
			(clearance 0.1524)
			(thermal_gap 0.1524)
		)
		(pad "D4" thru_hole circle
			(at 2.54 -7.62 270)
			(size 1.4478 1.4478)
			(drill 1.0414)
			(layers "*.Cu" "*.Mask")
			(remove_unused_layers no)
			(net "SD_LATCH_RELEASE_U")
			(clearance 0.1524)
			(thermal_gap 0.1524)
		)
		(pad "D5" thru_hole circle
			(at 5.08 -7.62 270)
			(size 1.4478 1.4478)
			(drill 1.0414)
			(layers "*.Cu" "*.Mask")
			(remove_unused_layers no)
			(net "SELF_TRAY_PRESENT_UPPER")
			(clearance 0.1524)
			(thermal_gap 0.1524)
		)
		(pad "P1_1" thru_hole circle
			(at -15.88008 0 270)
			(size 1.4478 1.4478)
			(drill 1.0414)
			(layers "*.Cu" "*.Mask")
			(remove_unused_layers no)
			(net "P12VU")
			(clearance 0.1524)
			(thermal_gap 0.1524)
		)
		(pad "P1_2" thru_hole circle
			(at -15.88008 -2.54 270)
			(size 1.4478 1.4478)
			(drill 1.0414)
			(layers "*.Cu" "*.Mask")
			(remove_unused_layers no)
			(net "P12VU")
			(clearance 0.1524)
			(thermal_gap 0.1524)
		)
		(pad "P1_3" thru_hole circle
			(at -15.88008 -5.08 270)
			(size 1.4478 1.4478)
			(drill 1.0414)
			(layers "*.Cu" "*.Mask")
			(remove_unused_layers no)
			(net "P12VU")
			(clearance 0.1524)
			(thermal_gap 0.1524)
		)
		(pad "P1_4" thru_hole circle
			(at -15.88008 -7.62 270)
			(size 1.4478 1.4478)
			(drill 1.0414)
			(layers "*.Cu" "*.Mask")
			(remove_unused_layers no)
			(net "P12VU")
			(clearance 0.1524)
			(thermal_gap 0.1524)
		)
		(pad "P1_5" thru_hole circle
			(at -13.34008 0 270)
			(size 1.4478 1.4478)
			(drill 1.0414)
			(layers "*.Cu" "*.Mask")
			(remove_unused_layers no)
			(net "P12VU")
			(clearance 0.1524)
			(thermal_gap 0.1524)
		)
		(pad "P1_6" thru_hole circle
			(at -13.34008 -2.54 270)
			(size 1.4478 1.4478)
			(drill 1.0414)
			(layers "*.Cu" "*.Mask")
			(remove_unused_layers no)
			(net "P12VU")
			(clearance 0.1524)
			(thermal_gap 0.1524)
		)
		(pad "P1_7" thru_hole circle
			(at -13.34008 -5.08 270)
			(size 1.4478 1.4478)
			(drill 1.0414)
			(layers "*.Cu" "*.Mask")
			(remove_unused_layers no)
			(net "P12VU")
			(clearance 0.1524)
			(thermal_gap 0.1524)
		)
		(pad "P1_8" thru_hole circle
			(at -13.34008 -7.62 270)
			(size 1.4478 1.4478)
			(drill 1.0414)
			(layers "*.Cu" "*.Mask")
			(remove_unused_layers no)
			(net "P12VU")
			(clearance 0.1524)
			(thermal_gap 0.1524)
		)
		(pad "P2_1" thru_hole circle
			(at -10.80008 0 270)
			(size 1.4478 1.4478)
			(drill 1.0414)
			(layers "*.Cu" "*.Mask")
			(remove_unused_layers no)
			(net "P12VU")
			(clearance 0.1524)
			(thermal_gap 0.1524)
		)
		(pad "P2_2" thru_hole circle
			(at -10.80008 -2.54 270)
			(size 1.4478 1.4478)
			(drill 1.0414)
			(layers "*.Cu" "*.Mask")
			(remove_unused_layers no)
			(net "P12VU")
			(clearance 0.1524)
			(thermal_gap 0.1524)
		)
		(pad "P2_3" thru_hole circle
			(at -10.80008 -5.08 270)
			(size 1.4478 1.4478)
			(drill 1.0414)
			(layers "*.Cu" "*.Mask")
			(remove_unused_layers no)
			(net "P12VU")
			(clearance 0.1524)
			(thermal_gap 0.1524)
		)
		(pad "P2_4" thru_hole circle
			(at -10.80008 -7.62 270)
			(size 1.4478 1.4478)
			(drill 1.0414)
			(layers "*.Cu" "*.Mask")
			(remove_unused_layers no)
			(net "P12VU")
			(clearance 0.1524)
			(thermal_gap 0.1524)
		)
		(pad "P2_5" thru_hole circle
			(at -8.26008 0 270)
			(size 1.4478 1.4478)
			(drill 1.0414)
			(layers "*.Cu" "*.Mask")
			(remove_unused_layers no)
			(net "P12VU")
			(clearance 0.1524)
			(thermal_gap 0.1524)
		)
		(pad "P2_6" thru_hole circle
			(at -8.26008 -2.54 270)
			(size 1.4478 1.4478)
			(drill 1.0414)
			(layers "*.Cu" "*.Mask")
			(remove_unused_layers no)
			(net "P12VU")
			(clearance 0.1524)
			(thermal_gap 0.1524)
		)
		(pad "P2_7" thru_hole circle
			(at -8.26008 -5.08 270)
			(size 1.4478 1.4478)
			(drill 1.0414)
			(layers "*.Cu" "*.Mask")
			(remove_unused_layers no)
			(net "P12VU")
			(clearance 0.1524)
			(thermal_gap 0.1524)
		)
		(pad "P2_8" thru_hole circle
			(at -8.26008 -7.62 270)
			(size 1.4478 1.4478)
			(drill 1.0414)
			(layers "*.Cu" "*.Mask")
			(remove_unused_layers no)
			(net "P12VU")
			(clearance 0.1524)
			(thermal_gap 0.1524)
		)
		(pad "P3_1" thru_hole circle
			(at 8.26008 0 270)
			(size 1.4478 1.4478)
			(drill 1.0414)
			(layers "*.Cu" "*.Mask")
			(remove_unused_layers no)
			(net "GND")
			(clearance 0.1524)
			(thermal_gap 0.1524)
		)
		(pad "P3_2" thru_hole circle
			(at 8.26008 -2.54 270)
			(size 1.4478 1.4478)
			(drill 1.0414)
			(layers "*.Cu" "*.Mask")
			(remove_unused_layers no)
			(net "GND")
			(clearance 0.1524)
			(thermal_gap 0.1524)
		)
		(pad "P3_3" thru_hole circle
			(at 8.26008 -5.08 270)
			(size 1.4478 1.4478)
			(drill 1.0414)
			(layers "*.Cu" "*.Mask")
			(remove_unused_layers no)
			(net "GND")
			(clearance 0.1524)
			(thermal_gap 0.1524)
		)
		(pad "P3_4" thru_hole circle
			(at 8.26008 -7.62 270)
			(size 1.4478 1.4478)
			(drill 1.0414)
			(layers "*.Cu" "*.Mask")
			(remove_unused_layers no)
			(net "GND")
			(clearance 0.1524)
			(thermal_gap 0.1524)
		)
		(pad "P3_5" thru_hole circle
			(at 10.80008 0 270)
			(size 1.4478 1.4478)
			(drill 1.0414)
			(layers "*.Cu" "*.Mask")
			(remove_unused_layers no)
			(net "GND")
			(clearance 0.1524)
			(thermal_gap 0.1524)
		)
		(pad "P3_6" thru_hole circle
			(at 10.80008 -2.54 270)
			(size 1.4478 1.4478)
			(drill 1.0414)
			(layers "*.Cu" "*.Mask")
			(remove_unused_layers no)
			(net "GND")
			(clearance 0.1524)
			(thermal_gap 0.1524)
		)
		(pad "P3_7" thru_hole circle
			(at 10.80008 -5.08 270)
			(size 1.4478 1.4478)
			(drill 1.0414)
			(layers "*.Cu" "*.Mask")
			(remove_unused_layers no)
			(net "GND")
			(clearance 0.1524)
			(thermal_gap 0.1524)
		)
		(pad "P3_8" thru_hole circle
			(at 10.80008 -7.62 270)
			(size 1.4478 1.4478)
			(drill 1.0414)
			(layers "*.Cu" "*.Mask")
			(remove_unused_layers no)
			(net "GND")
			(clearance 0.1524)
			(thermal_gap 0.1524)
		)
		(pad "P4_1" thru_hole circle
			(at 13.34008 0 270)
			(size 1.4478 1.4478)
			(drill 1.0414)
			(layers "*.Cu" "*.Mask")
			(remove_unused_layers no)
			(net "GND")
			(clearance 0.1524)
			(thermal_gap 0.1524)
		)
		(pad "P4_2" thru_hole circle
			(at 13.34008 -2.54 270)
			(size 1.4478 1.4478)
			(drill 1.0414)
			(layers "*.Cu" "*.Mask")
			(remove_unused_layers no)
			(net "GND")
			(clearance 0.1524)
			(thermal_gap 0.1524)
		)
		(pad "P4_3" thru_hole circle
			(at 13.34008 -5.08 270)
			(size 1.4478 1.4478)
			(drill 1.0414)
			(layers "*.Cu" "*.Mask")
			(remove_unused_layers no)
			(net "GND")
			(clearance 0.1524)
			(thermal_gap 0.1524)
		)
		(pad "P4_4" thru_hole circle
			(at 13.34008 -7.62 270)
			(size 1.4478 1.4478)
			(drill 1.0414)
			(layers "*.Cu" "*.Mask")
			(remove_unused_layers no)
			(net "GND")
			(clearance 0.1524)
			(thermal_gap 0.1524)
		)
		(pad "P4_5" thru_hole circle
			(at 15.88008 0 270)
			(size 1.4478 1.4478)
			(drill 1.0414)
			(layers "*.Cu" "*.Mask")
			(remove_unused_layers no)
			(net "GND")
			(clearance 0.1524)
			(thermal_gap 0.1524)
		)
		(pad "P4_6" thru_hole circle
			(at 15.88008 -2.54 270)
			(size 1.4478 1.4478)
			(drill 1.0414)
			(layers "*.Cu" "*.Mask")
			(remove_unused_layers no)
			(net "GND")
			(clearance 0.1524)
			(thermal_gap 0.1524)
		)
		(pad "P4_7" thru_hole circle
			(at 15.88008 -5.08 270)
			(size 1.4478 1.4478)
			(drill 1.0414)
			(layers "*.Cu" "*.Mask")
			(remove_unused_layers no)
			(net "GND")
			(clearance 0.1524)
			(thermal_gap 0.1524)
		)
		(pad "P4_8" thru_hole circle
			(at 15.88008 -7.62 270)
			(size 1.4478 1.4478)
			(drill 1.0414)
			(layers "*.Cu" "*.Mask")
			(remove_unused_layers no)
			(net "GND")
			(clearance 0.1524)
			(thermal_gap 0.1524)
		)
		(zone
			(layers "F.Cu" "B.Cu" "In1.Cu" "In2.Cu")
			(hatch none 0.5)
			(connect_pads
				(clearance 0)
			)
			(min_thickness 0.25)
			(keepout
				(tracks not_allowed)
				(vias allowed)
				(pads allowed)
				(copperpour not_allowed)
				(footprints allowed)
			)
			(placement
				(enabled no)
				(sheetname "")
			)
			(fill
				(thermal_gap 0.5)
				(thermal_bridge_width 0.5)
				(island_removal_mode 0)
			)
			(polygon
				(pts
					(arc
						(start 22.062186 -78.589886)
						(mid 18.937986 -78.589886)
						(end 22.062186 -78.589886)
					)
				)
			)
		)
		(zone
			(layers "F.Cu" "B.Cu" "In1.Cu" "In2.Cu")
			(hatch none 0.5)
			(connect_pads
				(clearance 0)
			)
			(min_thickness 0.25)
			(keepout
				(tracks not_allowed)
				(vias allowed)
				(pads allowed)
				(copperpour not_allowed)
				(footprints allowed)
			)
			(placement
				(enabled no)
				(sheetname "")
			)
			(fill
				(thermal_gap 0.5)
				(thermal_bridge_width 0.5)
				(island_removal_mode 0)
			)
			(polygon
				(pts
					(arc
						(start 22.062186 -35.409886)
						(mid 18.937986 -35.409886)
						(end 22.062186 -35.409886)
					)
				)
			)
		)
		(zone
			(layers "F.Cu" "B.Cu" "In1.Cu" "In2.Cu")
			(hatch none 0.5)
			(connect_pads
				(clearance 0)
			)
			(min_thickness 0.25)
			(keepout
				(tracks not_allowed)
				(vias allowed)
				(pads allowed)
				(copperpour not_allowed)
				(footprints allowed)
			)
			(placement
				(enabled no)
				(sheetname "")
			)
			(fill
				(thermal_gap 0.5)
				(thermal_bridge_width 0.5)
				(island_removal_mode 0)
			)
			(polygon
				(pts
					(arc
						(start 22.405086 -83.669886)
						(mid 18.595086 -83.669886)
						(end 22.405086 -83.669886)
					)
				)
			)
		)
		(zone
			(layers "F.Cu" "B.Cu" "In1.Cu" "In2.Cu")
			(hatch none 0.5)
			(connect_pads
				(clearance 0)
			)
			(min_thickness 0.25)
			(keepout
				(tracks not_allowed)
				(vias allowed)
				(pads allowed)
				(copperpour not_allowed)
				(footprints allowed)
			)
			(placement
				(enabled no)
				(sheetname "")
			)
			(fill
				(thermal_gap 0.5)
				(thermal_bridge_width 0.5)
				(island_removal_mode 0)
			)
			(polygon
				(pts
					(arc
						(start 22.405086 -30.329886)
						(mid 18.595086 -30.329886)
						(end 22.405086 -30.329886)
					)
				)
			)
		)
	)
	(footprint ""
		(layer "F.Cu")
		(at 36.1188 -371.4496 -90)
		(property "Reference" "PR6"
			(at 0 0 270)
			(layer "F.SilkS")
			(hide yes)
			(effects
				(font
					(size 1.27 1.27)
				)
			)
		)
		(property "Value" "100KR2F-L1-GP"
			(at 0.064008 -3.993896 270)
			(unlocked yes)
			(layer "F.Fab")
			(hide yes)
			(effects
				(font
					(size 1.016 1.016)
					(thickness 0.1524)
				)
			)
		)
		(property "Device Type" "R402H16"
			(at 0.064008 -5.517896 270)
			(unlocked yes)
			(layer "F.Fab")
			(hide yes)
			(effects
				(font
					(size 1.016 1.016)
					(thickness 0.1524)
				)
			)
		)
		(duplicate_pad_numbers_are_jumpers no)
		(fp_line
			(start -0.508 -0.9398)
			(end -0.508 0.9398)
			(stroke
				(width 0.1524)
				(type default)
			)
			(layer "F.SilkS")
		)
		(fp_line
			(start 0.508 -0.9398)
			(end -0.508 -0.9398)
			(stroke
				(width 0.1524)
				(type default)
			)
			(layer "F.SilkS")
		)
		(fp_rect
			(start -0.508 0.9398)
			(end 0.508 -0.9398)
			(stroke
				(width 0)
				(type default)
			)
			(fill no)
			(layer "F.CrtYd")
		)
		(fp_rect
			(start -0.508 0.9398)
			(end 0.508 -0.9398)
			(stroke
				(width 0)
				(type default)
			)
			(fill no)
			(layer "F.Fab")
		)
		(pad "1" smd custom
			(at 0 -0.4445 270)
			(size 0.1397 0.1397)
			(layers "F.Cu" "F.Mask" "F.Paste")
			(net "P12V")
			(options
				(clearance outline)
				(anchor circle)
			)
			(primitives
				(gr_poly
					(pts
						(arc
							(start -0.1778 -0.2794)
							(mid -0.249642 -0.249642)
							(end -0.2794 -0.1778)
						)
						(arc
							(start -0.2794 0.1778)
							(mid -0.249642 0.249642)
							(end -0.1778 0.2794)
						)
						(arc
							(start 0.1778 0.2794)
							(mid 0.249642 0.249642)
							(end 0.2794 0.1778)
						)
						(arc
							(start 0.2794 -0.1778)
							(mid 0.249642 -0.249642)
							(end 0.1778 -0.2794)
						)
					)
					(width 0)
					(fill yes)
				)
			)
		)
		(pad "2" smd custom
			(at 0 0.4445 270)
			(size 0.1397 0.1397)
			(layers "F.Cu" "F.Mask" "F.Paste")
			(net "ADM1276_FLB")
			(options
				(clearance outline)
				(anchor circle)
			)
			(primitives
				(gr_poly
					(pts
						(arc
							(start -0.1778 -0.2794)
							(mid -0.249642 -0.249642)
							(end -0.2794 -0.1778)
						)
						(arc
							(start -0.2794 0.1778)
							(mid -0.249642 0.249642)
							(end -0.1778 0.2794)
						)
						(arc
							(start 0.1778 0.2794)
							(mid 0.249642 0.249642)
							(end 0.2794 0.1778)
						)
						(arc
							(start 0.2794 -0.1778)
							(mid 0.249642 -0.249642)
							(end 0.1778 -0.2794)
						)
					)
					(width 0)
					(fill yes)
				)
			)
		)
	)
	(footprint ""
		(layer "F.Cu")
		(at 12.2428 -54.2036 90)
		(property "Reference" "R62"
			(at 0 0 90)
			(layer "F.SilkS")
			(hide yes)
			(effects
				(font
					(size 1.27 1.27)
				)
			)
		)
		(property "Value" "0R2J-2-GP"
			(at 0.064008 -3.993896 90)
			(unlocked yes)
			(layer "F.Fab")
			(hide yes)
			(effects
				(font
					(size 1.016 1.016)
					(thickness 0.1524)
				)
			)
		)
		(property "Device Type" "R402H16"
			(at 0.064008 -5.517896 90)
			(unlocked yes)
			(layer "F.Fab")
			(hide yes)
			(effects
				(font
					(size 1.016 1.016)
					(thickness 0.1524)
				)
			)
		)
		(duplicate_pad_numbers_are_jumpers no)
		(fp_line
			(start 0.508 -0.9398)
			(end -0.508 -0.9398)
			(stroke
				(width 0.1524)
				(type default)
			)
			(layer "F.SilkS")
		)
		(fp_line
			(start -0.508 -0.9398)
			(end -0.508 0.9398)
			(stroke
				(width 0.1524)
				(type default)
			)
			(layer "F.SilkS")
		)
		(fp_rect
			(start -0.508 0.9398)
			(end 0.508 -0.9398)
			(stroke
				(width 0)
				(type default)
			)
			(fill no)
			(layer "F.CrtYd")
		)
		(fp_rect
			(start -0.508 0.9398)
			(end 0.508 -0.9398)
			(stroke
				(width 0)
				(type default)
			)
			(fill no)
			(layer "F.Fab")
		)
		(pad "1" smd custom
			(at 0 -0.4445 90)
			(size 0.1397 0.1397)
			(layers "F.Cu" "F.Mask" "F.Paste")
			(net "SELF_TRAY_PRESENT_UPPER")
			(options
				(clearance outline)
				(anchor circle)
			)
			(primitives
				(gr_poly
					(pts
						(arc
							(start -0.1778 -0.2794)
							(mid -0.249642 -0.249642)
							(end -0.2794 -0.1778)
						)
						(arc
							(start -0.2794 0.1778)
							(mid -0.249642 0.249642)
							(end -0.1778 0.2794)
						)
						(arc
							(start 0.1778 0.2794)
							(mid 0.249642 0.249642)
							(end 0.2794 0.1778)
						)
						(arc
							(start 0.2794 -0.1778)
							(mid 0.249642 -0.249642)
							(end 0.1778 -0.2794)
						)
					)
					(width 0)
					(fill yes)
				)
			)
		)
		(pad "2" smd custom
			(at 0 0.4445 90)
			(size 0.1397 0.1397)
			(layers "F.Cu" "F.Mask" "F.Paste")
			(net "PEER_TRAY PRESENT_LOWER")
			(options
				(clearance outline)
				(anchor circle)
			)
			(primitives
				(gr_poly
					(pts
						(arc
							(start -0.1778 -0.2794)
							(mid -0.249642 -0.249642)
							(end -0.2794 -0.1778)
						)
						(arc
							(start -0.2794 0.1778)
							(mid -0.249642 0.249642)
							(end -0.1778 0.2794)
						)
						(arc
							(start 0.1778 0.2794)
							(mid 0.249642 0.249642)
							(end 0.2794 0.1778)
						)
						(arc
							(start 0.2794 -0.1778)
							(mid 0.249642 -0.249642)
							(end 0.1778 -0.2794)
						)
					)
					(width 0)
					(fill yes)
				)
			)
		)
	)
	(footprint ""
		(layer "F.Cu")
		(at 9.4488 -64.8208 180)
		(property "Reference" "R26"
			(at 0 0 180)
			(layer "F.SilkS")
			(hide yes)
			(effects
				(font
					(size 1.27 1.27)
				)
			)
		)
		(property "Value" "0R2J-2-GP"
			(at 0.064008 -3.993896 180)
			(unlocked yes)
			(layer "F.Fab")
			(hide yes)
			(effects
				(font
					(size 1.016 1.016)
					(thickness 0.1524)
				)
			)
		)
		(property "Device Type" "R402H16"
			(at 0.064008 -5.517896 180)
			(unlocked yes)
			(layer "F.Fab")
			(hide yes)
			(effects
				(font
					(size 1.016 1.016)
					(thickness 0.1524)
				)
			)
		)
		(duplicate_pad_numbers_are_jumpers no)
		(fp_line
			(start 0.508 -0.9398)
			(end -0.508 -0.9398)
			(stroke
				(width 0.1524)
				(type default)
			)
			(layer "F.SilkS")
		)
		(fp_line
			(start -0.508 -0.9398)
			(end -0.508 0.9398)
			(stroke
				(width 0.1524)
				(type default)
			)
			(layer "F.SilkS")
		)
		(fp_rect
			(start -0.508 0.9398)
			(end 0.508 -0.9398)
			(stroke
				(width 0)
				(type default)
			)
			(fill no)
			(layer "F.CrtYd")
		)
		(fp_rect
			(start -0.508 0.9398)
			(end 0.508 -0.9398)
			(stroke
				(width 0)
				(type default)
			)
			(fill no)
			(layer "F.Fab")
		)
		(pad "1" smd custom
			(at 0 -0.4445 180)
			(size 0.1397 0.1397)
			(layers "F.Cu" "F.Mask" "F.Paste")
			(net "LED_DR_LED5_K")
			(options
				(clearance outline)
				(anchor circle)
			)
			(primitives
				(gr_poly
					(pts
						(arc
							(start -0.1778 -0.2794)
							(mid -0.249642 -0.249642)
							(end -0.2794 -0.1778)
						)
						(arc
							(start -0.2794 0.1778)
							(mid -0.249642 0.249642)
							(end -0.1778 0.2794)
						)
						(arc
							(start 0.1778 0.2794)
							(mid 0.249642 0.249642)
							(end 0.2794 0.1778)
						)
						(arc
							(start 0.2794 -0.1778)
							(mid 0.249642 -0.249642)
							(end 0.1778 -0.2794)
						)
					)
					(width 0)
					(fill yes)
				)
			)
		)
		(pad "2" smd custom
			(at 0 0.4445 180)
			(size 0.1397 0.1397)
			(layers "F.Cu" "F.Mask" "F.Paste")
			(net "GND")
			(options
				(clearance outline)
				(anchor circle)
			)
			(primitives
				(gr_poly
					(pts
						(arc
							(start -0.1778 -0.2794)
							(mid -0.249642 -0.249642)
							(end -0.2794 -0.1778)
						)
						(arc
							(start -0.2794 0.1778)
							(mid -0.249642 0.249642)
							(end -0.1778 0.2794)
						)
						(arc
							(start 0.1778 0.2794)
							(mid 0.249642 0.249642)
							(end 0.2794 0.1778)
						)
						(arc
							(start 0.2794 -0.1778)
							(mid 0.249642 -0.249642)
							(end 0.1778 -0.2794)
						)
					)
					(width 0)
					(fill yes)
				)
			)
		)
	)
	(footprint ""
		(layer "F.Cu")
		(at 5.5626 -429.9712 90)
		(property "Reference" "R31"
			(at 0 0 90)
			(layer "F.SilkS")
			(hide yes)
			(effects
				(font
					(size 1.27 1.27)
				)
			)
		)
		(property "Value" "33R2F-3-GP"
			(at 0.064008 -3.993896 90)
			(unlocked yes)
			(layer "F.Fab")
			(hide yes)
			(effects
				(font
					(size 1.016 1.016)
					(thickness 0.1524)
				)
			)
		)
		(property "Device Type" "R402H16"
			(at 0.064008 -5.517896 90)
			(unlocked yes)
			(layer "F.Fab")
			(hide yes)
			(effects
				(font
					(size 1.016 1.016)
					(thickness 0.1524)
				)
			)
		)
		(duplicate_pad_numbers_are_jumpers no)
		(fp_line
			(start 0.508 -0.9398)
			(end -0.508 -0.9398)
			(stroke
				(width 0.1524)
				(type default)
			)
			(layer "F.SilkS")
		)
		(fp_line
			(start -0.508 -0.9398)
			(end -0.508 0.9398)
			(stroke
				(width 0.1524)
				(type default)
			)
			(layer "F.SilkS")
		)
		(fp_rect
			(start -0.508 0.9398)
			(end 0.508 -0.9398)
			(stroke
				(width 0)
				(type default)
			)
			(fill no)
			(layer "F.CrtYd")
		)
		(fp_rect
			(start -0.508 0.9398)
			(end 0.508 -0.9398)
			(stroke
				(width 0)
				(type default)
			)
			(fill no)
			(layer "F.Fab")
		)
		(pad "1" smd custom
			(at 0 -0.4445 90)
			(size 0.1397 0.1397)
			(layers "F.Cu" "F.Mask" "F.Paste")
			(net "P3V3")
			(options
				(clearance outline)
				(anchor circle)
			)
			(primitives
				(gr_poly
					(pts
						(arc
							(start -0.1778 -0.2794)
							(mid -0.249642 -0.249642)
							(end -0.2794 -0.1778)
						)
						(arc
							(start -0.2794 0.1778)
							(mid -0.249642 0.249642)
							(end -0.1778 0.2794)
						)
						(arc
							(start 0.1778 0.2794)
							(mid 0.249642 0.249642)
							(end 0.2794 0.1778)
						)
						(arc
							(start 0.2794 -0.1778)
							(mid 0.249642 -0.249642)
							(end 0.1778 -0.2794)
						)
					)
					(width 0)
					(fill yes)
				)
			)
		)
		(pad "2" smd custom
			(at 0 0.4445 90)
			(size 0.1397 0.1397)
			(layers "F.Cu" "F.Mask" "F.Paste")
			(net "LED_DR_LED0_BLUE")
			(options
				(clearance outline)
				(anchor circle)
			)
			(primitives
				(gr_poly
					(pts
						(arc
							(start -0.1778 -0.2794)
							(mid -0.249642 -0.249642)
							(end -0.2794 -0.1778)
						)
						(arc
							(start -0.2794 0.1778)
							(mid -0.249642 0.249642)
							(end -0.1778 0.2794)
						)
						(arc
							(start 0.1778 0.2794)
							(mid 0.249642 0.249642)
							(end 0.2794 0.1778)
						)
						(arc
							(start 0.2794 -0.1778)
							(mid 0.249642 -0.249642)
							(end 0.1778 -0.2794)
						)
					)
					(width 0)
					(fill yes)
				)
			)
		)
	)
	(footprint ""
		(layer "F.Cu")
		(at 36.068 -252.603 -90)
		(property "Reference" "TP18"
			(at 0 0 270)
			(layer "F.SilkS")
			(hide yes)
			(effects
				(font
					(size 1.27 1.27)
				)
			)
		)
		(property "Value" "TPAD32-GP"
			(at 0 -3.166364 270)
			(unlocked yes)
			(layer "F.Fab")
			(hide yes)
			(effects
				(font
					(size 1.016 1.016)
					(thickness 0.1524)
				)
			)
		)
		(property "Device Type" "TPAD32"
			(at 0 -4.690618 270)
			(unlocked yes)
			(layer "F.Fab")
			(hide yes)
			(effects
				(font
					(size 1.016 1.016)
					(thickness 0.1524)
				)
			)
		)
		(duplicate_pad_numbers_are_jumpers no)
		(fp_poly
			(pts
				(arc
					(start 0.7112 0)
					(mid -0.7112 0)
					(end 0.7112 0)
				)
			)
			(stroke
				(width 0)
				(type default)
			)
			(fill no)
			(layer "F.CrtYd")
		)
		(fp_poly
			(pts
				(arc
					(start 0.7112 0)
					(mid -0.7112 0)
					(end 0.7112 0)
				)
			)
			(stroke
				(width 0)
				(type default)
			)
			(fill no)
			(layer "F.Fab")
		)
		(pad "1" smd circle
			(at 0 0 270)
			(size 0.8128 0.8128)
			(layers "F.Cu" "F.Mask" "F.Paste")
			(net "LED_DRV_RST")
		)
	)
	(footprint ""
		(layer "F.Cu")
		(at 41.4782 -177.6222)
		(property "Reference" "C253"
			(at 0 0 0)
			(layer "F.SilkS")
			(hide yes)
			(effects
				(font
					(size 1.27 1.27)
				)
			)
		)
		(property "Value" "SC4D7U6D3V3KX-GP"
			(at 0 -2.8194 0)
			(unlocked yes)
			(layer "F.Fab")
			(hide yes)
			(effects
				(font
					(size 1.016 1.016)
					(thickness 0.1524)
				)
			)
		)
		(property "Device Type" "C603H36"
			(at 0 -4.3434 0)
			(unlocked yes)
			(layer "F.Fab")
			(hide yes)
			(effects
				(font
					(size 1.016 1.016)
					(thickness 0.1524)
				)
			)
		)
		(duplicate_pad_numbers_are_jumpers no)
		(fp_line
			(start 0.508 0)
			(end -0.508 0)
			(stroke
				(width 0.2032)
				(type default)
			)
			(layer "F.SilkS")
		)
		(fp_rect
			(start -0.5842 1.3335)
			(end 0.5842 -1.3335)
			(stroke
				(width 0)
				(type default)
			)
			(fill no)
			(layer "F.CrtYd")
		)
		(fp_rect
			(start -0.5842 1.3335)
			(end 0.5842 -1.3335)
			(stroke
				(width 0)
				(type default)
			)
			(fill no)
			(layer "F.Fab")
		)
		(pad "1" smd custom
			(at 0 -0.762)
			(size 0.2159 0.2159)
			(layers "F.Cu" "F.Mask" "F.Paste")
			(net "D_LATCH_PRE#")
			(options
				(clearance outline)
				(anchor circle)
			)
			(primitives
				(gr_poly
					(pts
						(arc
							(start -0.3302 -0.4318)
							(mid -0.402042 -0.402042)
							(end -0.4318 -0.3302)
						)
						(arc
							(start -0.4318 0.3302)
							(mid -0.402042 0.402042)
							(end -0.3302 0.4318)
						)
						(arc
							(start 0.3302 0.4318)
							(mid 0.402042 0.402042)
							(end 0.4318 0.3302)
						)
						(arc
							(start 0.4318 -0.3302)
							(mid 0.402042 -0.402042)
							(end 0.3302 -0.4318)
						)
					)
					(width 0)
					(fill yes)
				)
			)
		)
		(pad "2" smd custom
			(at 0 0.762)
			(size 0.2159 0.2159)
			(layers "F.Cu" "F.Mask" "F.Paste")
			(net "GND")
			(options
				(clearance outline)
				(anchor circle)
			)
			(primitives
				(gr_poly
					(pts
						(arc
							(start -0.3302 -0.4318)
							(mid -0.402042 -0.402042)
							(end -0.4318 -0.3302)
						)
						(arc
							(start -0.4318 0.3302)
							(mid -0.402042 0.402042)
							(end -0.3302 0.4318)
						)
						(arc
							(start 0.3302 0.4318)
							(mid 0.402042 0.402042)
							(end 0.4318 0.3302)
						)
						(arc
							(start 0.4318 -0.3302)
							(mid 0.402042 -0.402042)
							(end 0.3302 -0.4318)
						)
					)
					(width 0)
					(fill yes)
				)
			)
		)
	)
	(footprint ""
		(layer "F.Cu")
		(at 5.5118 -420.9034 90)
		(property "Reference" "R126"
			(at 0 0 90)
			(layer "F.SilkS")
			(hide yes)
			(effects
				(font
					(size 1.27 1.27)
				)
			)
		)
		(property "Value" "1K8R6J-GP"
			(at -0.0508 -4.8514 90)
			(unlocked yes)
			(layer "F.Fab")
			(hide yes)
			(effects
				(font
					(size 1.016 1.016)
					(thickness 0.1524)
				)
			)
		)
		(property "Device Type" "R1206H28"
			(at 0 -6.3754 90)
			(unlocked yes)
			(layer "F.Fab")
			(hide yes)
			(effects
				(font
					(size 1.016 1.016)
					(thickness 0.1524)
				)
			)
		)
		(duplicate_pad_numbers_are_jumpers no)
		(fp_line
			(start 1.016 -2.2352)
			(end 1.016 2.2352)
			(stroke
				(width 0.1524)
				(type default)
			)
			(layer "F.SilkS")
		)
		(fp_line
			(start -1.016 -2.2352)
			(end 1.016 -2.2352)
			(stroke
				(width 0.1524)
				(type default)
			)
			(layer "F.SilkS")
		)
		(fp_line
			(start 1.016 2.2352)
			(end -1.016 2.2352)
			(stroke
				(width 0.1524)
				(type default)
			)
			(layer "F.SilkS")
		)
		(fp_line
			(start -1.016 2.2352)
			(end -1.016 -2.2352)
			(stroke
				(width 0.1524)
				(type default)
			)
			(layer "F.SilkS")
		)
		(fp_rect
			(start -1.0922 2.3114)
			(end 1.0922 -2.3114)
			(stroke
				(width 0)
				(type default)
			)
			(fill no)
			(layer "F.CrtYd")
		)
		(fp_poly
			(pts
				(xy -1.0922 -2.3114) (xy 1.0922 -2.3114) (xy 1.0922 2.3114) (xy -1.0922 2.3114)
			)
			(stroke
				(width 0)
				(type default)
			)
			(fill no)
			(layer "F.Fab")
		)
		(pad "1" smd rect
			(at 0 -1.397 90)
			(size 1.651 1.27)
			(layers "F.Cu" "F.Mask" "F.Paste")
			(net "P12V")
		)
		(pad "2" smd rect
			(at 0 1.397 90)
			(size 1.651 1.27)
			(layers "F.Cu" "F.Mask" "F.Paste")
			(net "LED_DR_LED1_BLUE")
		)
	)
	(footprint ""
		(layer "F.Cu")
		(at 18.415 -109.5502 90)
		(property "Reference" "PR118"
			(at 0 0 90)
			(layer "F.SilkS")
			(hide yes)
			(effects
				(font
					(size 1.27 1.27)
				)
			)
		)
		(property "Value" "10R2F-L-GP"
			(at 0.064008 -3.993896 90)
			(unlocked yes)
			(layer "F.Fab")
			(hide yes)
			(effects
				(font
					(size 1.016 1.016)
					(thickness 0.1524)
				)
			)
		)
		(property "Device Type" "R402H14"
			(at 0.064008 -5.517896 90)
			(unlocked yes)
			(layer "F.Fab")
			(hide yes)
			(effects
				(font
					(size 1.016 1.016)
					(thickness 0.1524)
				)
			)
		)
		(duplicate_pad_numbers_are_jumpers no)
		(fp_line
			(start 0.508 -0.9398)
			(end -0.508 -0.9398)
			(stroke
				(width 0.1524)
				(type default)
			)
			(layer "F.SilkS")
		)
		(fp_line
			(start -0.508 -0.9398)
			(end -0.508 0.9398)
			(stroke
				(width 0.1524)
				(type default)
			)
			(layer "F.SilkS")
		)
		(fp_rect
			(start -0.508 0.9398)
			(end 0.508 -0.9398)
			(stroke
				(width 0)
				(type default)
			)
			(fill no)
			(layer "F.CrtYd")
		)
		(fp_rect
			(start -0.508 0.9398)
			(end 0.508 -0.9398)
			(stroke
				(width 0)
				(type default)
			)
			(fill no)
			(layer "F.Fab")
		)
		(pad "1" smd custom
			(at 0 -0.4445 90)
			(size 0.1397 0.1397)
			(layers "F.Cu" "F.Mask" "F.Paste")
			(net "P12VU_2490_GATE_DRV_2")
			(options
				(clearance outline)
				(anchor circle)
			)
			(primitives
				(gr_poly
					(pts
						(arc
							(start -0.1778 -0.2794)
							(mid -0.249642 -0.249642)
							(end -0.2794 -0.1778)
						)
						(arc
							(start -0.2794 0.1778)
							(mid -0.249642 0.249642)
							(end -0.1778 0.2794)
						)
						(arc
							(start 0.1778 0.2794)
							(mid 0.249642 0.249642)
							(end 0.2794 0.1778)
						)
						(arc
							(start 0.2794 -0.1778)
							(mid 0.249642 -0.249642)
							(end 0.1778 -0.2794)
						)
					)
					(width 0)
					(fill yes)
				)
			)
		)
		(pad "2" smd custom
			(at 0 0.4445 90)
			(size 0.1397 0.1397)
			(layers "F.Cu" "F.Mask" "F.Paste")
			(net "P12VU_2490_GATE")
			(options
				(clearance outline)
				(anchor circle)
			)
			(primitives
				(gr_poly
					(pts
						(arc
							(start -0.1778 -0.2794)
							(mid -0.249642 -0.249642)
							(end -0.2794 -0.1778)
						)
						(arc
							(start -0.2794 0.1778)
							(mid -0.249642 0.249642)
							(end -0.1778 0.2794)
						)
						(arc
							(start 0.1778 0.2794)
							(mid 0.249642 0.249642)
							(end 0.2794 0.1778)
						)
						(arc
							(start 0.2794 -0.1778)
							(mid 0.249642 -0.249642)
							(end 0.1778 -0.2794)
						)
					)
					(width 0)
					(fill yes)
				)
			)
		)
	)
	(footprint ""
		(layer "F.Cu")
		(at 29.7434 -363.2454 -90)
		(property "Reference" "TP22"
			(at 0 0 270)
			(layer "F.SilkS")
			(hide yes)
			(effects
				(font
					(size 1.27 1.27)
				)
			)
		)
		(property "Value" "TPAD32-GP"
			(at 0 -3.166364 270)
			(unlocked yes)
			(layer "F.Fab")
			(hide yes)
			(effects
				(font
					(size 1.016 1.016)
					(thickness 0.1524)
				)
			)
		)
		(property "Device Type" "TPAD32"
			(at 0 -4.690618 270)
			(unlocked yes)
			(layer "F.Fab")
			(hide yes)
			(effects
				(font
					(size 1.016 1.016)
					(thickness 0.1524)
				)
			)
		)
		(duplicate_pad_numbers_are_jumpers no)
		(fp_poly
			(pts
				(arc
					(start 0 -0.7112)
					(mid 0 0.7112)
					(end 0 -0.7112)
				)
			)
			(stroke
				(width 0)
				(type default)
			)
			(fill no)
			(layer "F.CrtYd")
		)
		(fp_poly
			(pts
				(arc
					(start 0 -0.7112)
					(mid 0 0.7112)
					(end 0 -0.7112)
				)
			)
			(stroke
				(width 0)
				(type default)
			)
			(fill no)
			(layer "F.Fab")
		)
		(pad "1" smd circle
			(at 0 0 270)
			(size 0.8128 0.8128)
			(layers "F.Cu" "F.Mask" "F.Paste")
			(net "ADM1276_GPIO2")
		)
	)
	(footprint ""
		(layer "F.Cu")
		(at 7.8232 -449.5546 90)
		(property "Reference" "R100"
			(at 0 0 90)
			(layer "F.SilkS")
			(hide yes)
			(effects
				(font
					(size 1.27 1.27)
				)
			)
		)
		(property "Value" "27KR3F-GP"
			(at -0.0254 -2.5146 90)
			(unlocked yes)
			(layer "F.Fab")
			(hide yes)
			(effects
				(font
					(size 1.016 1.016)
					(thickness 0.1524)
				)
			)
		)
		(property "Device Type" "R603H22"
			(at -0.0254 -4.0386 90)
			(unlocked yes)
			(layer "F.Fab")
			(hide yes)
			(effects
				(font
					(size 1.016 1.016)
					(thickness 0.1524)
				)
			)
		)
		(duplicate_pad_numbers_are_jumpers no)
		(fp_line
			(start 0.2032 0)
			(end 0.4826 0)
			(stroke
				(width 0.2032)
				(type default)
			)
			(layer "F.SilkS")
		)
		(fp_line
			(start -0.4826 0)
			(end -0.2032 0)
			(stroke
				(width 0.2032)
				(type default)
			)
			(layer "F.SilkS")
		)
		(fp_rect
			(start -0.5842 1.3335)
			(end 0.5842 -1.3335)
			(stroke
				(width 0)
				(type default)
			)
			(fill no)
			(layer "F.CrtYd")
		)
		(fp_rect
			(start -0.5842 1.3335)
			(end 0.5842 -1.3335)
			(stroke
				(width 0)
				(type default)
			)
			(fill no)
			(layer "F.Fab")
		)
		(pad "1" smd custom
			(at 0 -0.762 90)
			(size 0.2159 0.2159)
			(layers "F.Cu" "F.Mask" "F.Paste")
			(net "FANIN_1")
			(options
				(clearance outline)
				(anchor circle)
			)
			(primitives
				(gr_poly
					(pts
						(arc
							(start -0.3302 -0.4318)
							(mid -0.402042 -0.402042)
							(end -0.4318 -0.3302)
						)
						(arc
							(start -0.4318 0.3302)
							(mid -0.402042 0.402042)
							(end -0.3302 0.4318)
						)
						(arc
							(start 0.3302 0.4318)
							(mid 0.402042 0.402042)
							(end 0.4318 0.3302)
						)
						(arc
							(start 0.4318 -0.3302)
							(mid 0.402042 -0.402042)
							(end 0.3302 -0.4318)
						)
					)
					(width 0)
					(fill yes)
				)
			)
		)
		(pad "2" smd custom
			(at 0 0.762 90)
			(size 0.2159 0.2159)
			(layers "F.Cu" "F.Mask" "F.Paste")
			(net "FAN_TACH1")
			(options
				(clearance outline)
				(anchor circle)
			)
			(primitives
				(gr_poly
					(pts
						(arc
							(start -0.3302 -0.4318)
							(mid -0.402042 -0.402042)
							(end -0.4318 -0.3302)
						)
						(arc
							(start -0.4318 0.3302)
							(mid -0.402042 0.402042)
							(end -0.3302 0.4318)
						)
						(arc
							(start 0.3302 0.4318)
							(mid 0.402042 0.402042)
							(end 0.4318 0.3302)
						)
						(arc
							(start 0.4318 -0.3302)
							(mid 0.402042 -0.402042)
							(end 0.3302 -0.4318)
						)
					)
					(width 0)
					(fill yes)
				)
			)
		)
	)
	(footprint ""
		(layer "F.Cu")
		(at 25.5016 -139.5984 -90)
		(property "Reference" "PR99"
			(at 0 0 270)
			(layer "F.SilkS")
			(hide yes)
			(effects
				(font
					(size 1.27 1.27)
				)
			)
		)
		(property "Value" "100R2F-L1-GP-U"
			(at 0.064008 -3.993896 270)
			(unlocked yes)
			(layer "F.Fab")
			(hide yes)
			(effects
				(font
					(size 1.016 1.016)
					(thickness 0.1524)
				)
			)
		)
		(property "Device Type" "R402H14"
			(at 0.064008 -5.517896 270)
			(unlocked yes)
			(layer "F.Fab")
			(hide yes)
			(effects
				(font
					(size 1.016 1.016)
					(thickness 0.1524)
				)
			)
		)
		(duplicate_pad_numbers_are_jumpers no)
		(fp_line
			(start -0.508 -0.9398)
			(end -0.508 0.9398)
			(stroke
				(width 0.1524)
				(type default)
			)
			(layer "F.SilkS")
		)
		(fp_line
			(start 0.508 -0.9398)
			(end -0.508 -0.9398)
			(stroke
				(width 0.1524)
				(type default)
			)
			(layer "F.SilkS")
		)
		(fp_rect
			(start -0.508 0.9398)
			(end 0.508 -0.9398)
			(stroke
				(width 0)
				(type default)
			)
			(fill no)
			(layer "F.CrtYd")
		)
		(fp_rect
			(start -0.508 0.9398)
			(end 0.508 -0.9398)
			(stroke
				(width 0)
				(type default)
			)
			(fill no)
			(layer "F.Fab")
		)
		(pad "1" smd custom
			(at 0 -0.4445 270)
			(size 0.1397 0.1397)
			(layers "F.Cu" "F.Mask" "F.Paste")
			(net "P12VU_2490_GATE")
			(options
				(clearance outline)
				(anchor circle)
			)
			(primitives
				(gr_poly
					(pts
						(arc
							(start -0.1778 -0.2794)
							(mid -0.249642 -0.249642)
							(end -0.2794 -0.1778)
						)
						(arc
							(start -0.2794 0.1778)
							(mid -0.249642 0.249642)
							(end -0.1778 0.2794)
						)
						(arc
							(start 0.1778 0.2794)
							(mid 0.249642 0.249642)
							(end 0.2794 0.1778)
						)
						(arc
							(start 0.2794 -0.1778)
							(mid 0.249642 -0.249642)
							(end 0.1778 -0.2794)
						)
					)
					(width 0)
					(fill yes)
				)
			)
		)
		(pad "2" smd custom
			(at 0 0.4445 270)
			(size 0.1397 0.1397)
			(layers "F.Cu" "F.Mask" "F.Paste")
			(net "P12VU_2490_RC")
			(options
				(clearance outline)
				(anchor circle)
			)
			(primitives
				(gr_poly
					(pts
						(arc
							(start -0.1778 -0.2794)
							(mid -0.249642 -0.249642)
							(end -0.2794 -0.1778)
						)
						(arc
							(start -0.2794 0.1778)
							(mid -0.249642 0.249642)
							(end -0.1778 0.2794)
						)
						(arc
							(start 0.1778 0.2794)
							(mid 0.249642 0.249642)
							(end 0.2794 0.1778)
						)
						(arc
							(start 0.2794 -0.1778)
							(mid 0.249642 -0.249642)
							(end 0.1778 -0.2794)
						)
					)
					(width 0)
					(fill yes)
				)
			)
		)
	)
	(footprint ""
		(layer "F.Cu")
		(at 8.89 -148.1074 180)
		(property "Reference" "C28"
			(at 0 0 180)
			(layer "F.SilkS")
			(hide yes)
			(effects
				(font
					(size 1.27 1.27)
				)
			)
		)
		(property "Value" "SCD1U16V2KX-3GP"
			(at 1.1811 -2.7051 180)
			(unlocked yes)
			(layer "F.Fab")
			(hide yes)
			(effects
				(font
					(size 1.016 1.016)
					(thickness 0.1524)
				)
			)
		)
		(property "Device Type" "C402H22"
			(at 1.1811 -4.2291 180)
			(unlocked yes)
			(layer "F.Fab")
			(hide yes)
			(effects
				(font
					(size 1.016 1.016)
					(thickness 0.1524)
				)
			)
		)
		(duplicate_pad_numbers_are_jumpers no)
		(fp_rect
			(start -0.4318 0.9525)
			(end 0.4318 -0.9525)
			(stroke
				(width 0)
				(type default)
			)
			(fill no)
			(layer "F.CrtYd")
		)
		(fp_rect
			(start -0.4318 0.9525)
			(end 0.4318 -0.9525)
			(stroke
				(width 0)
				(type default)
			)
			(fill no)
			(layer "F.Fab")
		)
		(pad "1" smd custom
			(at 0 -0.4445 180)
			(size 0.1524 0.1524)
			(layers "F.Cu" "F.Mask" "F.Paste")
			(net "FAN_TACH10")
			(options
				(clearance outline)
				(anchor circle)
			)
			(primitives
				(gr_poly
					(pts
						(arc
							(start 0.3048 -0.2032)
							(mid 0.275042 -0.275042)
							(end 0.2032 -0.3048)
						)
						(arc
							(start -0.2032 -0.3048)
							(mid -0.275042 -0.275042)
							(end -0.3048 -0.2032)
						)
						(arc
							(start -0.3048 0.2032)
							(mid -0.275042 0.275042)
							(end -0.2032 0.3048)
						)
						(arc
							(start 0.2032 0.3048)
							(mid 0.275042 0.275042)
							(end 0.3048 0.2032)
						)
					)
					(width 0)
					(fill yes)
				)
			)
		)
		(pad "2" smd custom
			(at 0 0.4445 180)
			(size 0.1524 0.1524)
			(layers "F.Cu" "F.Mask" "F.Paste")
			(net "GND")
			(options
				(clearance outline)
				(anchor circle)
			)
			(primitives
				(gr_poly
					(pts
						(arc
							(start 0.3048 -0.2032)
							(mid 0.275042 -0.275042)
							(end 0.2032 -0.3048)
						)
						(arc
							(start -0.2032 -0.3048)
							(mid -0.275042 -0.275042)
							(end -0.3048 -0.2032)
						)
						(arc
							(start -0.3048 0.2032)
							(mid -0.275042 0.275042)
							(end -0.2032 0.3048)
						)
						(arc
							(start 0.2032 0.3048)
							(mid 0.275042 0.275042)
							(end 0.3048 0.2032)
						)
					)
					(width 0)
					(fill yes)
				)
			)
		)
	)
	(footprint ""
		(layer "F.Cu")
		(at 25.8826 -166.1414 180)
		(property "Reference" "TP5"
			(at 0 0 180)
			(layer "F.SilkS")
			(hide yes)
			(effects
				(font
					(size 1.27 1.27)
				)
			)
		)
		(property "Value" "TPAD32-GP"
			(at 0 -3.166364 180)
			(unlocked yes)
			(layer "F.Fab")
			(hide yes)
			(effects
				(font
					(size 1.016 1.016)
					(thickness 0.1524)
				)
			)
		)
		(property "Device Type" "TPAD32"
			(at 0 -4.690618 180)
			(unlocked yes)
			(layer "F.Fab")
			(hide yes)
			(effects
				(font
					(size 1.016 1.016)
					(thickness 0.1524)
				)
			)
		)
		(duplicate_pad_numbers_are_jumpers no)
		(fp_poly
			(pts
				(arc
					(start -0.7112 0)
					(mid 0.7112 0)
					(end -0.7112 0)
				)
			)
			(stroke
				(width 0)
				(type default)
			)
			(fill no)
			(layer "F.CrtYd")
		)
		(fp_poly
			(pts
				(arc
					(start -0.7112 0)
					(mid 0.7112 0)
					(end -0.7112 0)
				)
			)
			(stroke
				(width 0)
				(type default)
			)
			(fill no)
			(layer "F.Fab")
		)
		(pad "1" smd circle
			(at 0 0 180)
			(size 0.8128 0.8128)
			(layers "F.Cu" "F.Mask" "F.Paste")
			(net "NCT7904D_PWM4")
		)
	)
	(footprint ""
		(layer "F.Cu")
		(at 36.1188 -372.4656 -90)
		(property "Reference" "PR7"
			(at 0 0 270)
			(layer "F.SilkS")
			(hide yes)
			(effects
				(font
					(size 1.27 1.27)
				)
			)
		)
		(property "Value" "1KR2F-3-GP"
			(at 0.064008 -3.993896 270)
			(unlocked yes)
			(layer "F.Fab")
			(hide yes)
			(effects
				(font
					(size 1.016 1.016)
					(thickness 0.1524)
				)
			)
		)
		(property "Device Type" "R402H16"
			(at 0.064008 -5.517896 270)
			(unlocked yes)
			(layer "F.Fab")
			(hide yes)
			(effects
				(font
					(size 1.016 1.016)
					(thickness 0.1524)
				)
			)
		)
		(duplicate_pad_numbers_are_jumpers no)
		(fp_line
			(start -0.508 -0.9398)
			(end -0.508 0.9398)
			(stroke
				(width 0.1524)
				(type default)
			)
			(layer "F.SilkS")
		)
		(fp_line
			(start 0.508 -0.9398)
			(end -0.508 -0.9398)
			(stroke
				(width 0.1524)
				(type default)
			)
			(layer "F.SilkS")
		)
		(fp_rect
			(start -0.508 0.9398)
			(end 0.508 -0.9398)
			(stroke
				(width 0)
				(type default)
			)
			(fill no)
			(layer "F.CrtYd")
		)
		(fp_rect
			(start -0.508 0.9398)
			(end 0.508 -0.9398)
			(stroke
				(width 0)
				(type default)
			)
			(fill no)
			(layer "F.Fab")
		)
		(pad "1" smd custom
			(at 0 -0.4445 270)
			(size 0.1397 0.1397)
			(layers "F.Cu" "F.Mask" "F.Paste")
			(net "P12V")
			(options
				(clearance outline)
				(anchor circle)
			)
			(primitives
				(gr_poly
					(pts
						(arc
							(start -0.1778 -0.2794)
							(mid -0.249642 -0.249642)
							(end -0.2794 -0.1778)
						)
						(arc
							(start -0.2794 0.1778)
							(mid -0.249642 0.249642)
							(end -0.1778 0.2794)
						)
						(arc
							(start 0.1778 0.2794)
							(mid 0.249642 0.249642)
							(end 0.2794 0.1778)
						)
						(arc
							(start 0.2794 -0.1778)
							(mid 0.249642 -0.249642)
							(end 0.1778 -0.2794)
						)
					)
					(width 0)
					(fill yes)
				)
			)
		)
		(pad "2" smd custom
			(at 0 0.4445 270)
			(size 0.1397 0.1397)
			(layers "F.Cu" "F.Mask" "F.Paste")
			(net "ADM1276_VOUT")
			(options
				(clearance outline)
				(anchor circle)
			)
			(primitives
				(gr_poly
					(pts
						(arc
							(start -0.1778 -0.2794)
							(mid -0.249642 -0.249642)
							(end -0.2794 -0.1778)
						)
						(arc
							(start -0.2794 0.1778)
							(mid -0.249642 0.249642)
							(end -0.1778 0.2794)
						)
						(arc
							(start 0.1778 0.2794)
							(mid 0.249642 0.249642)
							(end 0.2794 0.1778)
						)
						(arc
							(start 0.2794 -0.1778)
							(mid 0.249642 -0.249642)
							(end 0.1778 -0.2794)
						)
					)
					(width 0)
					(fill yes)
				)
			)
		)
	)
	(footprint ""
		(layer "F.Cu")
		(at 29.972 -361.315 180)
		(property "Reference" "PR15"
			(at 0 0 180)
			(layer "F.SilkS")
			(hide yes)
			(effects
				(font
					(size 1.27 1.27)
				)
			)
		)
		(property "Value" "4K7R2J-2-GP"
			(at 0.064008 -3.993896 180)
			(unlocked yes)
			(layer "F.Fab")
			(hide yes)
			(effects
				(font
					(size 1.016 1.016)
					(thickness 0.1524)
				)
			)
		)
		(property "Device Type" "R402H16"
			(at 0.064008 -5.517896 180)
			(unlocked yes)
			(layer "F.Fab")
			(hide yes)
			(effects
				(font
					(size 1.016 1.016)
					(thickness 0.1524)
				)
			)
		)
		(duplicate_pad_numbers_are_jumpers no)
		(fp_line
			(start 0.508 -0.9398)
			(end -0.508 -0.9398)
			(stroke
				(width 0.1524)
				(type default)
			)
			(layer "F.SilkS")
		)
		(fp_line
			(start -0.508 -0.9398)
			(end -0.508 0.9398)
			(stroke
				(width 0.1524)
				(type default)
			)
			(layer "F.SilkS")
		)
		(fp_rect
			(start -0.508 0.9398)
			(end 0.508 -0.9398)
			(stroke
				(width 0)
				(type default)
			)
			(fill no)
			(layer "F.CrtYd")
		)
		(fp_rect
			(start -0.508 0.9398)
			(end 0.508 -0.9398)
			(stroke
				(width 0)
				(type default)
			)
			(fill no)
			(layer "F.Fab")
		)
		(pad "1" smd custom
			(at 0 -0.4445 180)
			(size 0.1397 0.1397)
			(layers "F.Cu" "F.Mask" "F.Paste")
			(net "P3V3")
			(options
				(clearance outline)
				(anchor circle)
			)
			(primitives
				(gr_poly
					(pts
						(arc
							(start -0.1778 -0.2794)
							(mid -0.249642 -0.249642)
							(end -0.2794 -0.1778)
						)
						(arc
							(start -0.2794 0.1778)
							(mid -0.249642 0.249642)
							(end -0.1778 0.2794)
						)
						(arc
							(start 0.1778 0.2794)
							(mid 0.249642 0.249642)
							(end 0.2794 0.1778)
						)
						(arc
							(start 0.2794 -0.1778)
							(mid 0.249642 -0.249642)
							(end 0.1778 -0.2794)
						)
					)
					(width 0)
					(fill yes)
				)
			)
		)
		(pad "2" smd custom
			(at 0 0.4445 180)
			(size 0.1397 0.1397)
			(layers "F.Cu" "F.Mask" "F.Paste")
			(net "ADM1276_GPIO2")
			(options
				(clearance outline)
				(anchor circle)
			)
			(primitives
				(gr_poly
					(pts
						(arc
							(start -0.1778 -0.2794)
							(mid -0.249642 -0.249642)
							(end -0.2794 -0.1778)
						)
						(arc
							(start -0.2794 0.1778)
							(mid -0.249642 0.249642)
							(end -0.1778 0.2794)
						)
						(arc
							(start 0.1778 0.2794)
							(mid 0.249642 0.249642)
							(end 0.2794 0.1778)
						)
						(arc
							(start 0.2794 -0.1778)
							(mid 0.249642 -0.249642)
							(end 0.1778 -0.2794)
						)
					)
					(width 0)
					(fill yes)
				)
			)
		)
	)
	(footprint ""
		(layer "F.Cu")
		(at 40.386 -370.332 -90)
		(property "Reference" "PR48"
			(at 0 0 270)
			(layer "F.SilkS")
			(hide yes)
			(effects
				(font
					(size 1.27 1.27)
				)
			)
		)
		(property "Value" "5K1R2F-2-GP"
			(at 0.064008 -3.993896 270)
			(unlocked yes)
			(layer "F.Fab")
			(hide yes)
			(effects
				(font
					(size 1.016 1.016)
					(thickness 0.1524)
				)
			)
		)
		(property "Device Type" "R402H16"
			(at 0.064008 -5.517896 270)
			(unlocked yes)
			(layer "F.Fab")
			(hide yes)
			(effects
				(font
					(size 1.016 1.016)
					(thickness 0.1524)
				)
			)
		)
		(duplicate_pad_numbers_are_jumpers no)
		(fp_line
			(start -0.508 -0.9398)
			(end -0.508 0.9398)
			(stroke
				(width 0.1524)
				(type default)
			)
			(layer "F.SilkS")
		)
		(fp_line
			(start 0.508 -0.9398)
			(end -0.508 -0.9398)
			(stroke
				(width 0.1524)
				(type default)
			)
			(layer "F.SilkS")
		)
		(fp_rect
			(start -0.508 0.9398)
			(end 0.508 -0.9398)
			(stroke
				(width 0)
				(type default)
			)
			(fill no)
			(layer "F.CrtYd")
		)
		(fp_rect
			(start -0.508 0.9398)
			(end 0.508 -0.9398)
			(stroke
				(width 0)
				(type default)
			)
			(fill no)
			(layer "F.Fab")
		)
		(pad "1" smd custom
			(at 0 -0.4445 270)
			(size 0.1397 0.1397)
			(layers "F.Cu" "F.Mask" "F.Paste")
			(net "ADM1276_EN_NET")
			(options
				(clearance outline)
				(anchor circle)
			)
			(primitives
				(gr_poly
					(pts
						(arc
							(start -0.1778 -0.2794)
							(mid -0.249642 -0.249642)
							(end -0.2794 -0.1778)
						)
						(arc
							(start -0.2794 0.1778)
							(mid -0.249642 0.249642)
							(end -0.1778 0.2794)
						)
						(arc
							(start 0.1778 0.2794)
							(mid 0.249642 0.249642)
							(end 0.2794 0.1778)
						)
						(arc
							(start 0.2794 -0.1778)
							(mid 0.249642 -0.249642)
							(end 0.1778 -0.2794)
						)
					)
					(width 0)
					(fill yes)
				)
			)
		)
		(pad "2" smd custom
			(at 0 0.4445 270)
			(size 0.1397 0.1397)
			(layers "F.Cu" "F.Mask" "F.Paste")
			(net "ADM1276_LATCH_B")
			(options
				(clearance outline)
				(anchor circle)
			)
			(primitives
				(gr_poly
					(pts
						(arc
							(start -0.1778 -0.2794)
							(mid -0.249642 -0.249642)
							(end -0.2794 -0.1778)
						)
						(arc
							(start -0.2794 0.1778)
							(mid -0.249642 0.249642)
							(end -0.1778 0.2794)
						)
						(arc
							(start 0.1778 0.2794)
							(mid 0.249642 0.249642)
							(end 0.2794 0.1778)
						)
						(arc
							(start 0.2794 -0.1778)
							(mid 0.249642 -0.249642)
							(end 0.1778 -0.2794)
						)
					)
					(width 0)
					(fill yes)
				)
			)
		)
	)
	(footprint ""
		(layer "F.Cu")
		(at 22.352 -186.2836 -90)
		(property "Reference" "R81"
			(at 0 0 270)
			(layer "F.SilkS")
			(hide yes)
			(effects
				(font
					(size 1.27 1.27)
				)
			)
		)
		(property "Value" "4K7R2F-GP"
			(at 0.064008 -3.993896 270)
			(unlocked yes)
			(layer "F.Fab")
			(hide yes)
			(effects
				(font
					(size 1.016 1.016)
					(thickness 0.1524)
				)
			)
		)
		(property "Device Type" "R402H16"
			(at 0.064008 -5.517896 270)
			(unlocked yes)
			(layer "F.Fab")
			(hide yes)
			(effects
				(font
					(size 1.016 1.016)
					(thickness 0.1524)
				)
			)
		)
		(duplicate_pad_numbers_are_jumpers no)
		(fp_line
			(start -0.508 -0.9398)
			(end -0.508 0.9398)
			(stroke
				(width 0.1524)
				(type default)
			)
			(layer "F.SilkS")
		)
		(fp_line
			(start 0.508 -0.9398)
			(end -0.508 -0.9398)
			(stroke
				(width 0.1524)
				(type default)
			)
			(layer "F.SilkS")
		)
		(fp_rect
			(start -0.508 0.9398)
			(end 0.508 -0.9398)
			(stroke
				(width 0)
				(type default)
			)
			(fill no)
			(layer "F.CrtYd")
		)
		(fp_rect
			(start -0.508 0.9398)
			(end 0.508 -0.9398)
			(stroke
				(width 0)
				(type default)
			)
			(fill no)
			(layer "F.Fab")
		)
		(pad "1" smd custom
			(at 0 -0.4445 270)
			(size 0.1397 0.1397)
			(layers "F.Cu" "F.Mask" "F.Paste")
			(net "P12V")
			(options
				(clearance outline)
				(anchor circle)
			)
			(primitives
				(gr_poly
					(pts
						(arc
							(start -0.1778 -0.2794)
							(mid -0.249642 -0.249642)
							(end -0.2794 -0.1778)
						)
						(arc
							(start -0.2794 0.1778)
							(mid -0.249642 0.249642)
							(end -0.1778 0.2794)
						)
						(arc
							(start 0.1778 0.2794)
							(mid 0.249642 0.249642)
							(end 0.2794 0.1778)
						)
						(arc
							(start 0.2794 -0.1778)
							(mid 0.249642 -0.249642)
							(end 0.1778 -0.2794)
						)
					)
					(width 0)
					(fill yes)
				)
			)
		)
		(pad "2" smd custom
			(at 0 0.4445 270)
			(size 0.1397 0.1397)
			(layers "F.Cu" "F.Mask" "F.Paste")
			(net "FAN_TACH8")
			(options
				(clearance outline)
				(anchor circle)
			)
			(primitives
				(gr_poly
					(pts
						(arc
							(start -0.1778 -0.2794)
							(mid -0.249642 -0.249642)
							(end -0.2794 -0.1778)
						)
						(arc
							(start -0.2794 0.1778)
							(mid -0.249642 0.249642)
							(end -0.1778 0.2794)
						)
						(arc
							(start 0.1778 0.2794)
							(mid 0.249642 0.249642)
							(end 0.2794 0.1778)
						)
						(arc
							(start 0.2794 -0.1778)
							(mid 0.249642 -0.249642)
							(end 0.1778 -0.2794)
						)
					)
					(width 0)
					(fill yes)
				)
			)
		)
	)
	(footprint ""
		(layer "F.Cu")
		(at 34.2138 -356.185216)
		(property "Reference" "R365"
			(at 0 0 0)
			(layer "F.SilkS")
			(hide yes)
			(effects
				(font
					(size 1.27 1.27)
				)
			)
		)
		(property "Value" "10MR2J-L-GP"
			(at 0.064008 -3.993896 0)
			(unlocked yes)
			(layer "F.Fab")
			(hide yes)
			(effects
				(font
					(size 1.016 1.016)
					(thickness 0.1524)
				)
			)
		)
		(property "Device Type" "R402H16"
			(at 0.064008 -5.517896 0)
			(unlocked yes)
			(layer "F.Fab")
			(hide yes)
			(effects
				(font
					(size 1.016 1.016)
					(thickness 0.1524)
				)
			)
		)
		(duplicate_pad_numbers_are_jumpers no)
		(fp_line
			(start -0.508 -0.9398)
			(end -0.508 0.9398)
			(stroke
				(width 0.1524)
				(type default)
			)
			(layer "F.SilkS")
		)
		(fp_line
			(start 0.508 -0.9398)
			(end -0.508 -0.9398)
			(stroke
				(width 0.1524)
				(type default)
			)
			(layer "F.SilkS")
		)
		(fp_rect
			(start -0.508 0.9398)
			(end 0.508 -0.9398)
			(stroke
				(width 0)
				(type default)
			)
			(fill no)
			(layer "F.CrtYd")
		)
		(fp_rect
			(start -0.508 0.9398)
			(end 0.508 -0.9398)
			(stroke
				(width 0)
				(type default)
			)
			(fill no)
			(layer "F.Fab")
		)
		(pad "1" smd custom
			(at 0 -0.4445)
			(size 0.1397 0.1397)
			(layers "F.Cu" "F.Mask" "F.Paste")
			(net "OTP_RETRY_G")
			(options
				(clearance outline)
				(anchor circle)
			)
			(primitives
				(gr_poly
					(pts
						(arc
							(start -0.1778 -0.2794)
							(mid -0.249642 -0.249642)
							(end -0.2794 -0.1778)
						)
						(arc
							(start -0.2794 0.1778)
							(mid -0.249642 0.249642)
							(end -0.1778 0.2794)
						)
						(arc
							(start 0.1778 0.2794)
							(mid 0.249642 0.249642)
							(end 0.2794 0.1778)
						)
						(arc
							(start 0.2794 -0.1778)
							(mid 0.249642 -0.249642)
							(end 0.1778 -0.2794)
						)
					)
					(width 0)
					(fill yes)
				)
			)
		)
		(pad "2" smd custom
			(at 0 0.4445)
			(size 0.1397 0.1397)
			(layers "F.Cu" "F.Mask" "F.Paste")
			(net "GND")
			(options
				(clearance outline)
				(anchor circle)
			)
			(primitives
				(gr_poly
					(pts
						(arc
							(start -0.1778 -0.2794)
							(mid -0.249642 -0.249642)
							(end -0.2794 -0.1778)
						)
						(arc
							(start -0.2794 0.1778)
							(mid -0.249642 0.249642)
							(end -0.1778 0.2794)
						)
						(arc
							(start 0.1778 0.2794)
							(mid 0.249642 0.249642)
							(end 0.2794 0.1778)
						)
						(arc
							(start 0.2794 -0.1778)
							(mid 0.249642 -0.249642)
							(end 0.1778 -0.2794)
						)
					)
					(width 0)
					(fill yes)
				)
			)
		)
	)
	(footprint ""
		(layer "F.Cu")
		(at 8.001 -417.9062 180)
		(property "Reference" "Q7"
			(at 0 0 180)
			(layer "F.SilkS")
			(hide yes)
			(effects
				(font
					(size 1.27 1.27)
				)
			)
		)
		(property "Value" "PMBS3904-1-GP"
			(at 0 -9.0932 180)
			(unlocked yes)
			(layer "F.Fab")
			(hide yes)
			(effects
				(font
					(size 1.016 1.016)
					(thickness 0.1524)
				)
			)
		)
		(property "Device Type" "SOT-23-10H44"
			(at 0 -10.6172 180)
			(unlocked yes)
			(layer "F.Fab")
			(hide yes)
			(effects
				(font
					(size 1.016 1.016)
					(thickness 0.1524)
				)
			)
		)
		(duplicate_pad_numbers_are_jumpers no)
		(fp_line
			(start 1.651 1.778)
			(end 1.651 -1.778)
			(stroke
				(width 0.1524)
				(type default)
			)
			(layer "F.SilkS")
		)
		(fp_line
			(start 1.651 -1.778)
			(end -1.651 -1.778)
			(stroke
				(width 0.1524)
				(type default)
			)
			(layer "F.SilkS")
		)
		(fp_line
			(start -0.635 1.8796)
			(end -1.7526 1.8796)
			(stroke
				(width 0.3302)
				(type default)
			)
			(layer "F.SilkS")
		)
		(fp_line
			(start -0.71628 2.15265)
			(end -1.26492 2.15265)
			(stroke
				(width 0.0127)
				(type default)
			)
			(layer "F.SilkS")
		)
		(fp_line
			(start -0.719074 2.145538)
			(end -1.265936 2.14122)
			(stroke
				(width 0.0127)
				(type default)
			)
			(layer "F.SilkS")
		)
		(fp_line
			(start -0.9906 1.86309)
			(end -0.701294 2.15265)
			(stroke
				(width 0.0127)
				(type default)
			)
			(layer "F.SilkS")
		)
		(fp_line
			(start -0.994156 1.8669)
			(end -0.987044 1.8669)
			(stroke
				(width 0.0127)
				(type default)
			)
			(layer "F.SilkS")
		)
		(fp_line
			(start -1.003808 1.876552)
			(end -0.977646 1.876552)
			(stroke
				(width 0.0127)
				(type default)
			)
			(layer "F.SilkS")
		)
		(fp_line
			(start -1.013206 1.88595)
			(end -0.967994 1.88595)
			(stroke
				(width 0.0127)
				(type default)
			)
			(layer "F.SilkS")
		)
		(fp_line
			(start -1.022858 1.895602)
			(end -0.958596 1.895602)
			(stroke
				(width 0.0127)
				(type default)
			)
			(layer "F.SilkS")
		)
		(fp_line
			(start -1.032256 1.905)
			(end -0.948944 1.905)
			(stroke
				(width 0.0127)
				(type default)
			)
			(layer "F.SilkS")
		)
		(fp_line
			(start -1.041908 1.914652)
			(end -0.939546 1.914652)
			(stroke
				(width 0.0127)
				(type default)
			)
			(layer "F.SilkS")
		)
		(fp_line
			(start -1.051306 1.92405)
			(end -0.929894 1.92405)
			(stroke
				(width 0.0127)
				(type default)
			)
			(layer "F.SilkS")
		)
		(fp_line
			(start -1.060958 1.933702)
			(end -0.920496 1.933702)
			(stroke
				(width 0.0127)
				(type default)
			)
			(layer "F.SilkS")
		)
		(fp_line
			(start -1.070356 1.9431)
			(end -0.910844 1.9431)
			(stroke
				(width 0.0127)
				(type default)
			)
			(layer "F.SilkS")
		)
		(fp_line
			(start -1.080008 1.952752)
			(end -0.901446 1.952752)
			(stroke
				(width 0.0127)
				(type default)
			)
			(layer "F.SilkS")
		)
		(fp_line
			(start -1.089406 1.96215)
			(end -0.891794 1.96215)
			(stroke
				(width 0.0127)
				(type default)
			)
			(layer "F.SilkS")
		)
		(fp_line
			(start -1.099058 1.971802)
			(end -0.882396 1.971802)
			(stroke
				(width 0.0127)
				(type default)
			)
			(layer "F.SilkS")
		)
		(fp_line
			(start -1.108456 1.9812)
			(end -0.872744 1.9812)
			(stroke
				(width 0.0127)
				(type default)
			)
			(layer "F.SilkS")
		)
		(fp_line
			(start -1.118108 1.990852)
			(end -0.863346 1.990852)
			(stroke
				(width 0.0127)
				(type default)
			)
			(layer "F.SilkS")
		)
		(fp_line
			(start -1.127506 2.00025)
			(end -0.853694 2.00025)
			(stroke
				(width 0.0127)
				(type default)
			)
			(layer "F.SilkS")
		)
		(fp_line
			(start -1.137158 2.009902)
			(end -0.844296 2.009902)
			(stroke
				(width 0.0127)
				(type default)
			)
			(layer "F.SilkS")
		)
		(fp_line
			(start -1.146556 2.0193)
			(end -0.834644 2.0193)
			(stroke
				(width 0.0127)
				(type default)
			)
			(layer "F.SilkS")
		)
		(fp_line
			(start -1.156208 2.028952)
			(end -0.825246 2.028952)
			(stroke
				(width 0.0127)
				(type default)
			)
			(layer "F.SilkS")
		)
		(fp_line
			(start -1.165606 2.03835)
			(end -0.815594 2.03835)
			(stroke
				(width 0.0127)
				(type default)
			)
			(layer "F.SilkS")
		)
		(fp_line
			(start -1.175258 2.048002)
			(end -0.806196 2.048002)
			(stroke
				(width 0.0127)
				(type default)
			)
			(layer "F.SilkS")
		)
		(fp_line
			(start -1.184656 2.0574)
			(end -0.796544 2.0574)
			(stroke
				(width 0.0127)
				(type default)
			)
			(layer "F.SilkS")
		)
		(fp_line
			(start -1.194308 2.067052)
			(end -0.787146 2.067052)
			(stroke
				(width 0.0127)
				(type default)
			)
			(layer "F.SilkS")
		)
		(fp_line
			(start -1.203706 2.07645)
			(end -0.777494 2.07645)
			(stroke
				(width 0.0127)
				(type default)
			)
			(layer "F.SilkS")
		)
		(fp_line
			(start -1.213358 2.086102)
			(end -0.768096 2.086102)
			(stroke
				(width 0.0127)
				(type default)
			)
			(layer "F.SilkS")
		)
		(fp_line
			(start -1.222756 2.0955)
			(end -0.758444 2.0955)
			(stroke
				(width 0.0127)
				(type default)
			)
			(layer "F.SilkS")
		)
		(fp_line
			(start -1.232408 2.105152)
			(end -0.749046 2.105152)
			(stroke
				(width 0.0127)
				(type default)
			)
			(layer "F.SilkS")
		)
		(fp_line
			(start -1.241806 2.11455)
			(end -0.739394 2.11455)
			(stroke
				(width 0.0127)
				(type default)
			)
			(layer "F.SilkS")
		)
		(fp_line
			(start -1.251458 2.124202)
			(end -0.729996 2.124202)
			(stroke
				(width 0.0127)
				(type default)
			)
			(layer "F.SilkS")
		)
		(fp_line
			(start -1.260856 2.1336)
			(end -0.720344 2.1336)
			(stroke
				(width 0.0127)
				(type default)
			)
			(layer "F.SilkS")
		)
		(fp_line
			(start -1.279144 2.15265)
			(end -0.701294 2.15265)
			(stroke
				(width 0.0127)
				(type default)
			)
			(layer "F.SilkS")
		)
		(fp_line
			(start -1.279398 2.152142)
			(end -0.9906 1.86309)
			(stroke
				(width 0.0127)
				(type default)
			)
			(layer "F.SilkS")
		)
		(fp_line
			(start -1.651 1.778)
			(end 1.651 1.778)
			(stroke
				(width 0.1524)
				(type default)
			)
			(layer "F.SilkS")
		)
		(fp_line
			(start -1.651 -1.778)
			(end -1.651 1.778)
			(stroke
				(width 0.1524)
				(type default)
			)
			(layer "F.SilkS")
		)
		(fp_line
			(start -1.7526 1.8796)
			(end -1.7526 0.9906)
			(stroke
				(width 0.3302)
				(type default)
			)
			(layer "F.SilkS")
		)
		(fp_poly
			(pts
				(xy -1.285748 2.159) (xy -1.285748 1.8796) (xy -1.778 1.8796) (xy -1.778 -1.8796) (xy 1.778 -1.8796)
				(xy 1.778 1.8796) (xy -0.694944 1.8796) (xy -0.694944 2.159)
			)
			(stroke
				(width 0)
				(type default)
			)
			(fill no)
			(layer "F.CrtYd")
		)
		(fp_poly
			(pts
				(xy -1.285748 2.159) (xy -1.285748 1.8796) (xy -1.778 1.8796) (xy -1.778 -1.8796) (xy 1.778 -1.8796)
				(xy 1.778 1.8796) (xy -0.694944 1.8796) (xy -0.694944 2.159)
			)
			(stroke
				(width 0)
				(type default)
			)
			(fill no)
			(layer "F.Fab")
		)
		(pad "1" smd rect
			(at -0.98425 0.9525 180)
			(size 0.762 1.143)
			(layers "F.Cu" "F.Mask" "F.Paste")
			(net "LED_DR_LED1_B")
		)
		(pad "2" smd rect
			(at 0.98425 0.9525 180)
			(size 0.762 1.143)
			(layers "F.Cu" "F.Mask" "F.Paste")
			(net "GND")
		)
		(pad "3" smd rect
			(at 0 -0.9525 180)
			(size 0.762 1.143)
			(layers "F.Cu" "F.Mask" "F.Paste")
			(net "LED_DR_LED1_BLUE")
		)
	)
	(footprint ""
		(layer "F.Cu")
		(at 26.416 -410.591)
		(property "Reference" "PR30"
			(at 0 0 0)
			(layer "F.SilkS")
			(hide yes)
			(effects
				(font
					(size 1.27 1.27)
				)
			)
		)
		(property "Value" "D0005RL1632F-GP-U"
			(at 3.2258 1.2954 0)
			(unlocked yes)
			(layer "F.Fab")
			(hide yes)
			(effects
				(font
					(size 1.016 1.016)
					(thickness 0.1524)
				)
			)
		)
		(property "Device Type" "RL3115-4PH45"
			(at 3.2258 -0.2286 0)
			(unlocked yes)
			(layer "F.Fab")
			(hide yes)
			(effects
				(font
					(size 1.016 1.016)
					(thickness 0.1524)
				)
			)
		)
		(duplicate_pad_numbers_are_jumpers no)
		(fp_line
			(start -2.0574 -1.7653)
			(end -2.0574 -0.4064)
			(stroke
				(width 0.3302)
				(type default)
			)
			(layer "F.SilkS")
		)
		(fp_line
			(start -1.9685 -1.651)
			(end 1.9685 -1.651)
			(stroke
				(width 0.1524)
				(type default)
			)
			(layer "F.SilkS")
		)
		(fp_line
			(start -1.9685 1.651)
			(end -1.9685 -1.651)
			(stroke
				(width 0.1524)
				(type default)
			)
			(layer "F.SilkS")
		)
		(fp_line
			(start -0.5334 -1.7653)
			(end -2.0574 -1.7653)
			(stroke
				(width 0.3302)
				(type default)
			)
			(layer "F.SilkS")
		)
		(fp_line
			(start 1.9685 -1.651)
			(end 1.9685 1.651)
			(stroke
				(width 0.1524)
				(type default)
			)
			(layer "F.SilkS")
		)
		(fp_line
			(start 1.9685 1.651)
			(end -1.9685 1.651)
			(stroke
				(width 0.1524)
				(type default)
			)
			(layer "F.SilkS")
		)
		(fp_poly
			(pts
				(xy -0.561594 -1.726946) (xy -0.053594 -2.234946) (xy -1.069594 -2.234946)
			)
			(stroke
				(width 0)
				(type default)
			)
			(fill yes)
			(layer "F.SilkS")
		)
		(fp_rect
			(start -1.524 0.7493)
			(end 1.524 -0.7493)
			(stroke
				(width 0)
				(type default)
			)
			(fill no)
			(layer "F.CrtYd")
		)
		(fp_poly
			(pts
				(xy -2.2225 1.905) (xy -2.2225 -1.905) (xy 2.2225 -1.905) (xy 2.2225 -0.7493) (xy -1.524 -0.7493)
				(xy -1.524 0.7493) (xy 1.524 0.7493) (xy 1.524 -0.7366) (xy 2.2225 -0.7366) (xy 2.2225 1.905)
			)
			(stroke
				(width 0)
				(type default)
			)
			(fill no)
			(layer "F.CrtYd")
		)
		(fp_rect
			(start -2.2225 1.905)
			(end 2.2225 -1.905)
			(stroke
				(width 0)
				(type default)
			)
			(fill no)
			(layer "F.Fab")
		)
		(pad "1" smd rect
			(at -0.5715 -0.813562)
			(size 2.286 1.143)
			(layers "F.Cu" "F.Mask" "F.Paste")
			(net "P12V_AUX")
		)
		(pad "2" smd rect
			(at -0.5715 0.813562)
			(size 2.286 1.143)
			(layers "F.Cu" "F.Mask" "F.Paste")
			(net "P12V_SENSE_TRACE")
		)
		(pad "3" smd rect
			(at 1.334008 -0.813562)
			(size 0.762 1.143)
			(layers "F.Cu" "F.Mask" "F.Paste")
			(net "SENSE+_R2")
		)
		(pad "4" smd rect
			(at 1.334008 0.813562)
			(size 0.762 1.143)
			(layers "F.Cu" "F.Mask" "F.Paste")
			(net "SENSE-_R2")
		)
		(zone
			(layer "F.Cu")
			(hatch none 0.5)
			(connect_pads
				(clearance 0)
			)
			(min_thickness 0.25)
			(keepout
				(tracks allowed)
				(vias not_allowed)
				(pads allowed)
				(copperpour not_allowed)
				(footprints allowed)
			)
			(placement
				(enabled no)
				(sheetname "")
			)
			(fill
				(thermal_gap 0.5)
				(thermal_bridge_width 0.5)
				(island_removal_mode 0)
			)
			(polygon
				(pts
					(xy 26.9875 -410.833062) (xy 27.369008 -410.833062) (xy 27.369008 -411.3403) (xy 26.9875 -411.3403)
				)
			)
		)
		(zone
			(layer "F.Cu")
			(hatch none 0.5)
			(connect_pads
				(clearance 0)
			)
			(min_thickness 0.25)
			(keepout
				(tracks not_allowed)
				(vias allowed)
				(pads allowed)
				(copperpour not_allowed)
				(footprints allowed)
			)
			(placement
				(enabled no)
				(sheetname "")
			)
			(fill
				(thermal_gap 0.5)
				(thermal_bridge_width 0.5)
				(island_removal_mode 0)
			)
			(polygon
				(pts
					(xy 26.9875 -410.833062) (xy 27.369008 -410.833062) (xy 27.369008 -411.3403) (xy 26.9875 -411.3403)
				)
			)
		)
		(zone
			(layer "F.Cu")
			(hatch none 0.5)
			(connect_pads
				(clearance 0)
			)
			(min_thickness 0.25)
			(keepout
				(tracks not_allowed)
				(vias allowed)
				(pads allowed)
				(copperpour not_allowed)
				(footprints allowed)
			)
			(placement
				(enabled no)
				(sheetname "")
			)
			(fill
				(thermal_gap 0.5)
				(thermal_bridge_width 0.5)
				(island_removal_mode 0)
			)
			(polygon
				(pts
					(xy 26.9875 -409.8417) (xy 27.369008 -409.8417) (xy 27.369008 -410.348938) (xy 26.9875 -410.348938)
				)
			)
		)
		(zone
			(layer "F.Cu")
			(hatch none 0.5)
			(connect_pads
				(clearance 0)
			)
			(min_thickness 0.25)
			(keepout
				(tracks allowed)
				(vias not_allowed)
				(pads allowed)
				(copperpour not_allowed)
				(footprints allowed)
			)
			(placement
				(enabled no)
				(sheetname "")
			)
			(fill
				(thermal_gap 0.5)
				(thermal_bridge_width 0.5)
				(island_removal_mode 0)
			)
			(polygon
				(pts
					(xy 26.9875 -409.8417) (xy 27.369008 -409.8417) (xy 27.369008 -410.348938) (xy 26.9875 -410.348938)
				)
			)
		)
	)
	(footprint ""
		(layer "F.Cu")
		(at 10.0838 -278.384 -90)
		(property "Reference" "R117"
			(at 0 0 270)
			(layer "F.SilkS")
			(hide yes)
			(effects
				(font
					(size 1.27 1.27)
				)
			)
		)
		(property "Value" "2KR2F-3-GP"
			(at 0.064008 -3.993896 270)
			(unlocked yes)
			(layer "F.Fab")
			(hide yes)
			(effects
				(font
					(size 1.016 1.016)
					(thickness 0.1524)
				)
			)
		)
		(property "Device Type" "R402H16"
			(at 0.064008 -5.517896 270)
			(unlocked yes)
			(layer "F.Fab")
			(hide yes)
			(effects
				(font
					(size 1.016 1.016)
					(thickness 0.1524)
				)
			)
		)
		(duplicate_pad_numbers_are_jumpers no)
		(fp_line
			(start -0.508 -0.9398)
			(end -0.508 0.9398)
			(stroke
				(width 0.1524)
				(type default)
			)
			(layer "F.SilkS")
		)
		(fp_line
			(start 0.508 -0.9398)
			(end -0.508 -0.9398)
			(stroke
				(width 0.1524)
				(type default)
			)
			(layer "F.SilkS")
		)
		(fp_rect
			(start -0.508 0.9398)
			(end 0.508 -0.9398)
			(stroke
				(width 0)
				(type default)
			)
			(fill no)
			(layer "F.CrtYd")
		)
		(fp_rect
			(start -0.508 0.9398)
			(end 0.508 -0.9398)
			(stroke
				(width 0)
				(type default)
			)
			(fill no)
			(layer "F.Fab")
		)
		(pad "1" smd custom
			(at 0 -0.4445 270)
			(size 0.1397 0.1397)
			(layers "F.Cu" "F.Mask" "F.Paste")
			(net "LED_DR_LED2")
			(options
				(clearance outline)
				(anchor circle)
			)
			(primitives
				(gr_poly
					(pts
						(arc
							(start -0.1778 -0.2794)
							(mid -0.249642 -0.249642)
							(end -0.2794 -0.1778)
						)
						(arc
							(start -0.2794 0.1778)
							(mid -0.249642 0.249642)
							(end -0.1778 0.2794)
						)
						(arc
							(start 0.1778 0.2794)
							(mid 0.249642 0.249642)
							(end 0.2794 0.1778)
						)
						(arc
							(start 0.2794 -0.1778)
							(mid 0.249642 -0.249642)
							(end 0.1778 -0.2794)
						)
					)
					(width 0)
					(fill yes)
				)
			)
		)
		(pad "2" smd custom
			(at 0 0.4445 270)
			(size 0.1397 0.1397)
			(layers "F.Cu" "F.Mask" "F.Paste")
			(net "LED_DR_LED2_B")
			(options
				(clearance outline)
				(anchor circle)
			)
			(primitives
				(gr_poly
					(pts
						(arc
							(start -0.1778 -0.2794)
							(mid -0.249642 -0.249642)
							(end -0.2794 -0.1778)
						)
						(arc
							(start -0.2794 0.1778)
							(mid -0.249642 0.249642)
							(end -0.1778 0.2794)
						)
						(arc
							(start 0.1778 0.2794)
							(mid 0.249642 0.249642)
							(end 0.2794 0.1778)
						)
						(arc
							(start 0.2794 -0.1778)
							(mid 0.249642 -0.249642)
							(end 0.1778 -0.2794)
						)
					)
					(width 0)
					(fill yes)
				)
			)
		)
	)
	(footprint ""
		(layer "F.Cu")
		(at 14.8844 -71.12 -90)
		(property "Reference" "R167"
			(at 0 0 270)
			(layer "F.SilkS")
			(hide yes)
			(effects
				(font
					(size 1.27 1.27)
				)
			)
		)
		(property "Value" "4K7R2F-GP"
			(at 0.064008 -3.993896 270)
			(unlocked yes)
			(layer "F.Fab")
			(hide yes)
			(effects
				(font
					(size 1.016 1.016)
					(thickness 0.1524)
				)
			)
		)
		(property "Device Type" "R402H16"
			(at 0.064008 -5.517896 270)
			(unlocked yes)
			(layer "F.Fab")
			(hide yes)
			(effects
				(font
					(size 1.016 1.016)
					(thickness 0.1524)
				)
			)
		)
		(duplicate_pad_numbers_are_jumpers no)
		(fp_line
			(start -0.508 -0.9398)
			(end -0.508 0.9398)
			(stroke
				(width 0.1524)
				(type default)
			)
			(layer "F.SilkS")
		)
		(fp_line
			(start 0.508 -0.9398)
			(end -0.508 -0.9398)
			(stroke
				(width 0.1524)
				(type default)
			)
			(layer "F.SilkS")
		)
		(fp_rect
			(start -0.508 0.9398)
			(end 0.508 -0.9398)
			(stroke
				(width 0)
				(type default)
			)
			(fill no)
			(layer "F.CrtYd")
		)
		(fp_rect
			(start -0.508 0.9398)
			(end 0.508 -0.9398)
			(stroke
				(width 0)
				(type default)
			)
			(fill no)
			(layer "F.Fab")
		)
		(pad "1" smd custom
			(at 0 -0.4445 270)
			(size 0.1397 0.1397)
			(layers "F.Cu" "F.Mask" "F.Paste")
			(net "P3V3")
			(options
				(clearance outline)
				(anchor circle)
			)
			(primitives
				(gr_poly
					(pts
						(arc
							(start -0.1778 -0.2794)
							(mid -0.249642 -0.249642)
							(end -0.2794 -0.1778)
						)
						(arc
							(start -0.2794 0.1778)
							(mid -0.249642 0.249642)
							(end -0.1778 0.2794)
						)
						(arc
							(start 0.1778 0.2794)
							(mid 0.249642 0.249642)
							(end 0.2794 0.1778)
						)
						(arc
							(start 0.2794 -0.1778)
							(mid 0.249642 -0.249642)
							(end 0.1778 -0.2794)
						)
					)
					(width 0)
					(fill yes)
				)
			)
		)
		(pad "2" smd custom
			(at 0 0.4445 270)
			(size 0.1397 0.1397)
			(layers "F.Cu" "F.Mask" "F.Paste")
			(net "PWM_BUFFER_IN_FAN1_FAN2")
			(options
				(clearance outline)
				(anchor circle)
			)
			(primitives
				(gr_poly
					(pts
						(arc
							(start -0.1778 -0.2794)
							(mid -0.249642 -0.249642)
							(end -0.2794 -0.1778)
						)
						(arc
							(start -0.2794 0.1778)
							(mid -0.249642 0.249642)
							(end -0.1778 0.2794)
						)
						(arc
							(start 0.1778 0.2794)
							(mid 0.249642 0.249642)
							(end 0.2794 0.1778)
						)
						(arc
							(start 0.2794 -0.1778)
							(mid 0.249642 -0.249642)
							(end 0.1778 -0.2794)
						)
					)
					(width 0)
					(fill yes)
				)
			)
		)
	)
	(footprint ""
		(layer "F.Cu")
		(at 21.7678 -218.821 90)
		(property "Reference" "R134"
			(at 0 0 90)
			(layer "F.SilkS")
			(hide yes)
			(effects
				(font
					(size 1.27 1.27)
				)
			)
		)
		(property "Value" "4K7R2F-GP"
			(at 0.064008 -3.993896 90)
			(unlocked yes)
			(layer "F.Fab")
			(hide yes)
			(effects
				(font
					(size 1.016 1.016)
					(thickness 0.1524)
				)
			)
		)
		(property "Device Type" "R402H16"
			(at 0.064008 -5.517896 90)
			(unlocked yes)
			(layer "F.Fab")
			(hide yes)
			(effects
				(font
					(size 1.016 1.016)
					(thickness 0.1524)
				)
			)
		)
		(duplicate_pad_numbers_are_jumpers no)
		(fp_line
			(start 0.508 -0.9398)
			(end -0.508 -0.9398)
			(stroke
				(width 0.1524)
				(type default)
			)
			(layer "F.SilkS")
		)
		(fp_line
			(start -0.508 -0.9398)
			(end -0.508 0.9398)
			(stroke
				(width 0.1524)
				(type default)
			)
			(layer "F.SilkS")
		)
		(fp_rect
			(start -0.508 0.9398)
			(end 0.508 -0.9398)
			(stroke
				(width 0)
				(type default)
			)
			(fill no)
			(layer "F.CrtYd")
		)
		(fp_rect
			(start -0.508 0.9398)
			(end 0.508 -0.9398)
			(stroke
				(width 0)
				(type default)
			)
			(fill no)
			(layer "F.Fab")
		)
		(pad "1" smd custom
			(at 0 -0.4445 90)
			(size 0.1397 0.1397)
			(layers "F.Cu" "F.Mask" "F.Paste")
			(net "P3V3")
			(options
				(clearance outline)
				(anchor circle)
			)
			(primitives
				(gr_poly
					(pts
						(arc
							(start -0.1778 -0.2794)
							(mid -0.249642 -0.249642)
							(end -0.2794 -0.1778)
						)
						(arc
							(start -0.2794 0.1778)
							(mid -0.249642 0.249642)
							(end -0.1778 0.2794)
						)
						(arc
							(start 0.1778 0.2794)
							(mid 0.249642 0.249642)
							(end 0.2794 0.1778)
						)
						(arc
							(start 0.2794 -0.1778)
							(mid 0.249642 -0.249642)
							(end 0.1778 -0.2794)
						)
					)
					(width 0)
					(fill yes)
				)
			)
		)
		(pad "2" smd custom
			(at 0 0.4445 90)
			(size 0.1397 0.1397)
			(layers "F.Cu" "F.Mask" "F.Paste")
			(net "PWM_OUT_FAN2")
			(options
				(clearance outline)
				(anchor circle)
			)
			(primitives
				(gr_poly
					(pts
						(arc
							(start -0.1778 -0.2794)
							(mid -0.249642 -0.249642)
							(end -0.2794 -0.1778)
						)
						(arc
							(start -0.2794 0.1778)
							(mid -0.249642 0.249642)
							(end -0.1778 0.2794)
						)
						(arc
							(start 0.1778 0.2794)
							(mid 0.249642 0.249642)
							(end 0.2794 0.1778)
						)
						(arc
							(start 0.2794 -0.1778)
							(mid 0.249642 -0.249642)
							(end 0.1778 -0.2794)
						)
					)
					(width 0)
					(fill yes)
				)
			)
		)
	)
	(footprint ""
		(layer "F.Cu")
		(at 17.907 -298.4754 -90)
		(property "Reference" "R92"
			(at 0 0 270)
			(layer "F.SilkS")
			(hide yes)
			(effects
				(font
					(size 1.27 1.27)
				)
			)
		)
		(property "Value" "4K7R2F-GP"
			(at 0.064008 -3.993896 270)
			(unlocked yes)
			(layer "F.Fab")
			(hide yes)
			(effects
				(font
					(size 1.016 1.016)
					(thickness 0.1524)
				)
			)
		)
		(property "Device Type" "R402H16"
			(at 0.064008 -5.517896 270)
			(unlocked yes)
			(layer "F.Fab")
			(hide yes)
			(effects
				(font
					(size 1.016 1.016)
					(thickness 0.1524)
				)
			)
		)
		(duplicate_pad_numbers_are_jumpers no)
		(fp_line
			(start -0.508 -0.9398)
			(end -0.508 0.9398)
			(stroke
				(width 0.1524)
				(type default)
			)
			(layer "F.SilkS")
		)
		(fp_line
			(start 0.508 -0.9398)
			(end -0.508 -0.9398)
			(stroke
				(width 0.1524)
				(type default)
			)
			(layer "F.SilkS")
		)
		(fp_rect
			(start -0.508 0.9398)
			(end 0.508 -0.9398)
			(stroke
				(width 0)
				(type default)
			)
			(fill no)
			(layer "F.CrtYd")
		)
		(fp_rect
			(start -0.508 0.9398)
			(end 0.508 -0.9398)
			(stroke
				(width 0)
				(type default)
			)
			(fill no)
			(layer "F.Fab")
		)
		(pad "1" smd custom
			(at 0 -0.4445 270)
			(size 0.1397 0.1397)
			(layers "F.Cu" "F.Mask" "F.Paste")
			(net "P12V")
			(options
				(clearance outline)
				(anchor circle)
			)
			(primitives
				(gr_poly
					(pts
						(arc
							(start -0.1778 -0.2794)
							(mid -0.249642 -0.249642)
							(end -0.2794 -0.1778)
						)
						(arc
							(start -0.2794 0.1778)
							(mid -0.249642 0.249642)
							(end -0.1778 0.2794)
						)
						(arc
							(start 0.1778 0.2794)
							(mid 0.249642 0.249642)
							(end 0.2794 0.1778)
						)
						(arc
							(start 0.2794 -0.1778)
							(mid 0.249642 -0.249642)
							(end 0.1778 -0.2794)
						)
					)
					(width 0)
					(fill yes)
				)
			)
		)
		(pad "2" smd custom
			(at 0 0.4445 270)
			(size 0.1397 0.1397)
			(layers "F.Cu" "F.Mask" "F.Paste")
			(net "PWM_OUT_FAN2_NET")
			(options
				(clearance outline)
				(anchor circle)
			)
			(primitives
				(gr_poly
					(pts
						(arc
							(start -0.1778 -0.2794)
							(mid -0.249642 -0.249642)
							(end -0.2794 -0.1778)
						)
						(arc
							(start -0.2794 0.1778)
							(mid -0.249642 0.249642)
							(end -0.1778 0.2794)
						)
						(arc
							(start 0.1778 0.2794)
							(mid 0.249642 0.249642)
							(end 0.2794 0.1778)
						)
						(arc
							(start 0.2794 -0.1778)
							(mid 0.249642 -0.249642)
							(end 0.1778 -0.2794)
						)
					)
					(width 0)
					(fill yes)
				)
			)
		)
	)
	(footprint ""
		(layer "F.Cu")
		(at 39.8018 -159.2072 90)
		(property "Reference" "TP12"
			(at 0 0 90)
			(layer "F.SilkS")
			(hide yes)
			(effects
				(font
					(size 1.27 1.27)
				)
			)
		)
		(property "Value" "TPAD32-GP"
			(at 0 -3.166364 90)
			(unlocked yes)
			(layer "F.Fab")
			(hide yes)
			(effects
				(font
					(size 1.016 1.016)
					(thickness 0.1524)
				)
			)
		)
		(property "Device Type" "TPAD32"
			(at 0 -4.690618 90)
			(unlocked yes)
			(layer "F.Fab")
			(hide yes)
			(effects
				(font
					(size 1.016 1.016)
					(thickness 0.1524)
				)
			)
		)
		(duplicate_pad_numbers_are_jumpers no)
		(fp_poly
			(pts
				(arc
					(start 0 0.7112)
					(mid 0 -0.7112)
					(end 0 0.7112)
				)
			)
			(stroke
				(width 0)
				(type default)
			)
			(fill no)
			(layer "F.CrtYd")
		)
		(fp_poly
			(pts
				(arc
					(start 0 0.7112)
					(mid 0 -0.7112)
					(end 0 0.7112)
				)
			)
			(stroke
				(width 0)
				(type default)
			)
			(fill no)
			(layer "F.Fab")
		)
		(pad "1" smd circle
			(at 0 0 90)
			(size 0.8128 0.8128)
			(layers "F.Cu" "F.Mask" "F.Paste")
			(net "NCT7904_PECI")
		)
	)
	(footprint ""
		(layer "F.Cu")
		(at 36.1442 -374.9802 180)
		(property "Reference" "PD1"
			(at 0 0 180)
			(layer "F.SilkS")
			(hide yes)
			(effects
				(font
					(size 1.27 1.27)
				)
			)
		)
		(property "Value" "MM3Z15VT1G-GP"
			(at 0 -6.7818 180)
			(unlocked yes)
			(layer "F.Fab")
			(hide yes)
			(effects
				(font
					(size 1.016 1.016)
					(thickness 0.1524)
				)
			)
		)
		(property "Device Type" "SOD323AKH44"
			(at 0 -8.6868 180)
			(unlocked yes)
			(layer "F.Fab")
			(hide yes)
			(effects
				(font
					(size 1.016 1.016)
					(thickness 0.1524)
				)
			)
		)
		(duplicate_pad_numbers_are_jumpers no)
		(fp_line
			(start 0.889 2.159)
			(end -0.889 2.159)
			(stroke
				(width 0.1524)
				(type default)
			)
			(layer "F.SilkS")
		)
		(fp_line
			(start 0.889 -1.9304)
			(end 0.889 2.159)
			(stroke
				(width 0.1524)
				(type default)
			)
			(layer "F.SilkS")
		)
		(fp_line
			(start 0.762 2.0574)
			(end -0.762 2.0574)
			(stroke
				(width 0.508)
				(type default)
			)
			(layer "F.SilkS")
		)
		(fp_line
			(start -0.889 2.159)
			(end -0.889 -1.9304)
			(stroke
				(width 0.1524)
				(type default)
			)
			(layer "F.SilkS")
		)
		(fp_line
			(start -0.889 -1.9304)
			(end 0.889 -1.9304)
			(stroke
				(width 0.1524)
				(type default)
			)
			(layer "F.SilkS")
		)
		(fp_rect
			(start -1.016 2.3114)
			(end 1.016 -2.0066)
			(stroke
				(width 0)
				(type default)
			)
			(fill no)
			(layer "F.CrtYd")
		)
		(fp_poly
			(pts
				(xy -1.016 -2.0066) (xy 1.016 -2.0066) (xy 1.016 2.3114) (xy -1.016 2.3114)
			)
			(stroke
				(width 0)
				(type default)
			)
			(fill no)
			(layer "F.Fab")
		)
		(pad "A" smd rect
			(at 0 -1.143 180)
			(size 0.5588 1.016)
			(layers "F.Cu" "F.Mask" "F.Paste")
			(net "ADM1276_GATE_RSV")
		)
		(pad "K" smd rect
			(at 0 1.143 180)
			(size 0.5588 1.016)
			(layers "F.Cu" "F.Mask" "F.Paste")
			(net "ADM1276_GATE")
		)
	)
	(footprint ""
		(layer "F.Cu")
		(at 32.7406 -149.071584 180)
		(property "Reference" "R36"
			(at 0 0 180)
			(layer "F.SilkS")
			(hide yes)
			(effects
				(font
					(size 1.27 1.27)
				)
			)
		)
		(property "Value" "110KR2F-L-GP"
			(at 0.064008 -3.993896 180)
			(unlocked yes)
			(layer "F.Fab")
			(hide yes)
			(effects
				(font
					(size 1.016 1.016)
					(thickness 0.1524)
				)
			)
		)
		(property "Device Type" "R402H16"
			(at 0.064008 -5.517896 180)
			(unlocked yes)
			(layer "F.Fab")
			(hide yes)
			(effects
				(font
					(size 1.016 1.016)
					(thickness 0.1524)
				)
			)
		)
		(duplicate_pad_numbers_are_jumpers no)
		(fp_line
			(start 0.508 -0.9398)
			(end -0.508 -0.9398)
			(stroke
				(width 0.1524)
				(type default)
			)
			(layer "F.SilkS")
		)
		(fp_line
			(start -0.508 -0.9398)
			(end -0.508 0.9398)
			(stroke
				(width 0.1524)
				(type default)
			)
			(layer "F.SilkS")
		)
		(fp_rect
			(start -0.508 0.9398)
			(end 0.508 -0.9398)
			(stroke
				(width 0)
				(type default)
			)
			(fill no)
			(layer "F.CrtYd")
		)
		(fp_rect
			(start -0.508 0.9398)
			(end 0.508 -0.9398)
			(stroke
				(width 0)
				(type default)
			)
			(fill no)
			(layer "F.Fab")
		)
		(pad "1" smd custom
			(at 0 -0.4445 180)
			(size 0.1397 0.1397)
			(layers "F.Cu" "F.Mask" "F.Paste")
			(net "P12VU")
			(options
				(clearance outline)
				(anchor circle)
			)
			(primitives
				(gr_poly
					(pts
						(arc
							(start -0.1778 -0.2794)
							(mid -0.249642 -0.249642)
							(end -0.2794 -0.1778)
						)
						(arc
							(start -0.2794 0.1778)
							(mid -0.249642 0.249642)
							(end -0.1778 0.2794)
						)
						(arc
							(start 0.1778 0.2794)
							(mid 0.249642 0.249642)
							(end 0.2794 0.1778)
						)
						(arc
							(start 0.2794 -0.1778)
							(mid 0.249642 -0.249642)
							(end 0.1778 -0.2794)
						)
					)
					(width 0)
					(fill yes)
				)
			)
		)
		(pad "2" smd custom
			(at 0 0.4445 180)
			(size 0.1397 0.1397)
			(layers "F.Cu" "F.Mask" "F.Paste")
			(net "NCT7904_VSEN7")
			(options
				(clearance outline)
				(anchor circle)
			)
			(primitives
				(gr_poly
					(pts
						(arc
							(start -0.1778 -0.2794)
							(mid -0.249642 -0.249642)
							(end -0.2794 -0.1778)
						)
						(arc
							(start -0.2794 0.1778)
							(mid -0.249642 0.249642)
							(end -0.1778 0.2794)
						)
						(arc
							(start 0.1778 0.2794)
							(mid 0.249642 0.249642)
							(end 0.2794 0.1778)
						)
						(arc
							(start 0.2794 -0.1778)
							(mid 0.249642 -0.249642)
							(end 0.1778 -0.2794)
						)
					)
					(width 0)
					(fill yes)
				)
			)
		)
	)
	(footprint ""
		(layer "F.Cu")
		(at 38.361366 -159.40151 90)
		(property "Reference" "TP15"
			(at 0 0 90)
			(layer "F.SilkS")
			(hide yes)
			(effects
				(font
					(size 1.27 1.27)
				)
			)
		)
		(property "Value" "TPAD32-GP"
			(at 0 -3.166364 90)
			(unlocked yes)
			(layer "F.Fab")
			(hide yes)
			(effects
				(font
					(size 1.016 1.016)
					(thickness 0.1524)
				)
			)
		)
		(property "Device Type" "TPAD32"
			(at 0 -4.690618 90)
			(unlocked yes)
			(layer "F.Fab")
			(hide yes)
			(effects
				(font
					(size 1.016 1.016)
					(thickness 0.1524)
				)
			)
		)
		(duplicate_pad_numbers_are_jumpers no)
		(fp_poly
			(pts
				(arc
					(start 0 0.7112)
					(mid 0 -0.7112)
					(end 0 0.7112)
				)
			)
			(stroke
				(width 0)
				(type default)
			)
			(fill no)
			(layer "F.CrtYd")
		)
		(fp_poly
			(pts
				(arc
					(start 0 0.7112)
					(mid 0 -0.7112)
					(end 0 0.7112)
				)
			)
			(stroke
				(width 0)
				(type default)
			)
			(fill no)
			(layer "F.Fab")
		)
		(pad "1" smd circle
			(at 0 0 90)
			(size 0.8128 0.8128)
			(layers "F.Cu" "F.Mask" "F.Paste")
			(net "NCT7904_THERMTRIP")
		)
	)
	(footprint ""
		(layer "F.Cu")
		(at 47.0154 -418.592 90)
		(property "Reference" "C25"
			(at 0 0 90)
			(layer "F.SilkS")
			(hide yes)
			(effects
				(font
					(size 1.27 1.27)
				)
			)
		)
		(property "Value" "SCD1U50V3KX-GP"
			(at 0 -2.8194 90)
			(unlocked yes)
			(layer "F.Fab")
			(hide yes)
			(effects
				(font
					(size 1.016 1.016)
					(thickness 0.1524)
				)
			)
		)
		(property "Device Type" "C603H36"
			(at 0 -4.3434 90)
			(unlocked yes)
			(layer "F.Fab")
			(hide yes)
			(effects
				(font
					(size 1.016 1.016)
					(thickness 0.1524)
				)
			)
		)
		(duplicate_pad_numbers_are_jumpers no)
		(fp_line
			(start 0.508 0)
			(end -0.508 0)
			(stroke
				(width 0.2032)
				(type default)
			)
			(layer "F.SilkS")
		)
		(fp_rect
			(start -0.5842 1.3335)
			(end 0.5842 -1.3335)
			(stroke
				(width 0)
				(type default)
			)
			(fill no)
			(layer "F.CrtYd")
		)
		(fp_rect
			(start -0.5842 1.3335)
			(end 0.5842 -1.3335)
			(stroke
				(width 0)
				(type default)
			)
			(fill no)
			(layer "F.Fab")
		)
		(pad "1" smd custom
			(at 0 -0.762 90)
			(size 0.2159 0.2159)
			(layers "F.Cu" "F.Mask" "F.Paste")
			(net "P12V_AUX")
			(options
				(clearance outline)
				(anchor circle)
			)
			(primitives
				(gr_poly
					(pts
						(arc
							(start -0.3302 -0.4318)
							(mid -0.402042 -0.402042)
							(end -0.4318 -0.3302)
						)
						(arc
							(start -0.4318 0.3302)
							(mid -0.402042 0.402042)
							(end -0.3302 0.4318)
						)
						(arc
							(start 0.3302 0.4318)
							(mid 0.402042 0.402042)
							(end 0.4318 0.3302)
						)
						(arc
							(start 0.4318 -0.3302)
							(mid 0.402042 -0.402042)
							(end 0.3302 -0.4318)
						)
					)
					(width 0)
					(fill yes)
				)
			)
		)
		(pad "2" smd custom
			(at 0 0.762 90)
			(size 0.2159 0.2159)
			(layers "F.Cu" "F.Mask" "F.Paste")
			(net "GND")
			(options
				(clearance outline)
				(anchor circle)
			)
			(primitives
				(gr_poly
					(pts
						(arc
							(start -0.3302 -0.4318)
							(mid -0.402042 -0.402042)
							(end -0.4318 -0.3302)
						)
						(arc
							(start -0.4318 0.3302)
							(mid -0.402042 0.402042)
							(end -0.3302 0.4318)
						)
						(arc
							(start 0.3302 0.4318)
							(mid 0.402042 0.402042)
							(end 0.4318 0.3302)
						)
						(arc
							(start 0.4318 -0.3302)
							(mid 0.402042 -0.402042)
							(end 0.3302 -0.4318)
						)
					)
					(width 0)
					(fill yes)
				)
			)
		)
	)
	(footprint ""
		(layer "F.Cu")
		(at 14.8844 -44.5262 90)
		(property "Reference" "R171"
			(at 0 0 90)
			(layer "F.SilkS")
			(hide yes)
			(effects
				(font
					(size 1.27 1.27)
				)
			)
		)
		(property "Value" "0R2J-2-GP"
			(at 0.064008 -3.993896 90)
			(unlocked yes)
			(layer "F.Fab")
			(hide yes)
			(effects
				(font
					(size 1.016 1.016)
					(thickness 0.1524)
				)
			)
		)
		(property "Device Type" "R402H16"
			(at 0.064008 -5.517896 90)
			(unlocked yes)
			(layer "F.Fab")
			(hide yes)
			(effects
				(font
					(size 1.016 1.016)
					(thickness 0.1524)
				)
			)
		)
		(duplicate_pad_numbers_are_jumpers no)
		(fp_line
			(start 0.508 -0.9398)
			(end -0.508 -0.9398)
			(stroke
				(width 0.1524)
				(type default)
			)
			(layer "F.SilkS")
		)
		(fp_line
			(start -0.508 -0.9398)
			(end -0.508 0.9398)
			(stroke
				(width 0.1524)
				(type default)
			)
			(layer "F.SilkS")
		)
		(fp_rect
			(start -0.508 0.9398)
			(end 0.508 -0.9398)
			(stroke
				(width 0)
				(type default)
			)
			(fill no)
			(layer "F.CrtYd")
		)
		(fp_rect
			(start -0.508 0.9398)
			(end 0.508 -0.9398)
			(stroke
				(width 0)
				(type default)
			)
			(fill no)
			(layer "F.Fab")
		)
		(pad "1" smd custom
			(at 0 -0.4445 90)
			(size 0.1397 0.1397)
			(layers "F.Cu" "F.Mask" "F.Paste")
			(net "SELF_1A_HB")
			(options
				(clearance outline)
				(anchor circle)
			)
			(primitives
				(gr_poly
					(pts
						(arc
							(start -0.1778 -0.2794)
							(mid -0.249642 -0.249642)
							(end -0.2794 -0.1778)
						)
						(arc
							(start -0.2794 0.1778)
							(mid -0.249642 0.249642)
							(end -0.1778 0.2794)
						)
						(arc
							(start 0.1778 0.2794)
							(mid 0.249642 0.249642)
							(end 0.2794 0.1778)
						)
						(arc
							(start 0.2794 -0.1778)
							(mid 0.249642 -0.249642)
							(end 0.1778 -0.2794)
						)
					)
					(width 0)
					(fill yes)
				)
			)
		)
		(pad "2" smd custom
			(at 0 0.4445 90)
			(size 0.1397 0.1397)
			(layers "F.Cu" "F.Mask" "F.Paste")
			(net "SEB_PEER_2A_HB")
			(options
				(clearance outline)
				(anchor circle)
			)
			(primitives
				(gr_poly
					(pts
						(arc
							(start -0.1778 -0.2794)
							(mid -0.249642 -0.249642)
							(end -0.2794 -0.1778)
						)
						(arc
							(start -0.2794 0.1778)
							(mid -0.249642 0.249642)
							(end -0.1778 0.2794)
						)
						(arc
							(start 0.1778 0.2794)
							(mid 0.249642 0.249642)
							(end 0.2794 0.1778)
						)
						(arc
							(start 0.2794 -0.1778)
							(mid 0.249642 -0.249642)
							(end 0.1778 -0.2794)
						)
					)
					(width 0)
					(fill yes)
				)
			)
		)
	)
	(footprint ""
		(layer "F.Cu")
		(at 31.571692 -481.559362 180)
		(property "Reference" "TC18"
			(at 0 0 180)
			(layer "F.SilkS")
			(hide yes)
			(effects
				(font
					(size 1.27 1.27)
				)
			)
		)
		(property "Value" "ST15U25VDM-1-GP"
			(at 0 -9.6012 180)
			(unlocked yes)
			(layer "F.Fab")
			(hide yes)
			(effects
				(font
					(size 1.016 1.016)
					(thickness 0.1524)
				)
			)
		)
		(property "Device Type" "CT7343H79"
			(at 0 -11.1252 180)
			(unlocked yes)
			(layer "F.Fab")
			(hide yes)
			(effects
				(font
					(size 1.016 1.016)
					(thickness 0.1524)
				)
			)
		)
		(duplicate_pad_numbers_are_jumpers no)
		(fp_line
			(start 2.286 4.8768)
			(end -2.286 4.8768)
			(stroke
				(width 0.1524)
				(type default)
			)
			(layer "F.SilkS")
		)
		(fp_line
			(start 2.286 2.032)
			(end 2.286 4.8768)
			(stroke
				(width 0.1524)
				(type default)
			)
			(layer "F.SilkS")
		)
		(fp_line
			(start 2.286 -2.032)
			(end 2.286 -4.8768)
			(stroke
				(width 0.1524)
				(type default)
			)
			(layer "F.SilkS")
		)
		(fp_line
			(start 2.286 -4.8768)
			(end -2.286 -4.8768)
			(stroke
				(width 0.1524)
				(type default)
			)
			(layer "F.SilkS")
		)
		(fp_line
			(start 2.1082 -4.699)
			(end -2.1082 -4.699)
			(stroke
				(width 0.508)
				(type default)
			)
			(layer "F.SilkS")
		)
		(fp_line
			(start -2.286 4.8768)
			(end -2.286 2.032)
			(stroke
				(width 0.1524)
				(type default)
			)
			(layer "F.SilkS")
		)
		(fp_line
			(start -2.286 -4.8768)
			(end -2.286 -2.032)
			(stroke
				(width 0.1524)
				(type default)
			)
			(layer "F.SilkS")
		)
		(fp_rect
			(start -2.1463 3.6449)
			(end 2.1463 -3.6449)
			(stroke
				(width 0)
				(type default)
			)
			(fill no)
			(layer "F.CrtYd")
		)
		(fp_poly
			(pts
				(xy -2.54 4.953) (xy -2.54 4.2926) (xy -3.81 4.2926) (xy -3.81 -4.2926) (xy -2.54 -4.2926) (xy -2.54 -4.953)
				(xy 2.54 -4.953) (xy 2.54 -4.2926) (xy 3.81 -4.2926) (xy 3.81 -1.6256) (xy 2.1463 -1.6256) (xy 2.1463 -3.6449)
				(xy -2.1463 -3.6449) (xy -2.1463 3.6449) (xy 2.1463 3.6449) (xy 2.1463 -1.6129) (xy 3.81 -1.6129)
				(xy 3.81 4.2926) (xy 2.54 4.2926) (xy 2.54 4.953)
			)
			(stroke
				(width 0)
				(type default)
			)
			(fill no)
			(layer "F.CrtYd")
		)
		(fp_rect
			(start 2.54 4.2926)
			(end 3.81 -4.2926)
			(stroke
				(width 0)
				(type default)
			)
			(fill no)
			(layer "F.Fab")
		)
		(fp_rect
			(start -2.54 4.953)
			(end 2.54 -4.953)
			(stroke
				(width 0)
				(type default)
			)
			(fill no)
			(layer "F.Fab")
		)
		(fp_rect
			(start -3.81 4.2926)
			(end -2.54 -4.2926)
			(stroke
				(width 0)
				(type default)
			)
			(fill no)
			(layer "F.Fab")
		)
		(pad "1" smd rect
			(at 0 -3.1496 180)
			(size 2.413 2.286)
			(layers "F.Cu" "F.Mask" "F.Paste")
			(net "P12V")
		)
		(pad "2" smd rect
			(at 0 3.1496 180)
			(size 2.413 2.286)
			(layers "F.Cu" "F.Mask" "F.Paste")
			(net "GND")
		)
		(zone
			(layer "F.Cu")
			(hatch none 0.5)
			(connect_pads
				(clearance 0)
			)
			(min_thickness 0.25)
			(keepout
				(tracks allowed)
				(vias not_allowed)
				(pads allowed)
				(copperpour not_allowed)
				(footprints allowed)
			)
			(placement
				(enabled no)
				(sheetname "")
			)
			(fill
				(thermal_gap 0.5)
				(thermal_bridge_width 0.5)
				(island_removal_mode 0)
			)
			(polygon
				(pts
					(xy 30.060392 -479.870262) (xy 30.060392 -476.961962) (xy 33.082992 -476.961962) (xy 33.082992 -479.857562)
					(xy 33.082992 -480.187762) (xy 30.060392 -480.187762)
				)
			)
		)
		(zone
			(layer "F.Cu")
			(hatch none 0.5)
			(connect_pads
				(clearance 0)
			)
			(min_thickness 0.25)
			(keepout
				(tracks allowed)
				(vias not_allowed)
				(pads allowed)
				(copperpour not_allowed)
				(footprints allowed)
			)
			(placement
				(enabled no)
				(sheetname "")
			)
			(fill
				(thermal_gap 0.5)
				(thermal_bridge_width 0.5)
				(island_removal_mode 0)
			)
			(polygon
				(pts
					(xy 33.082992 -486.156762) (xy 30.060392 -486.156762) (xy 30.060392 -483.261162) (xy 30.060392 -482.930962)
					(xy 33.082992 -482.930962) (xy 33.082992 -483.261162)
				)
			)
		)
	)
	(footprint ""
		(layer "F.Cu")
		(at 40.26789 -154.147266 180)
		(property "Reference" "L1"
			(at 0 0 180)
			(layer "F.SilkS")
			(hide yes)
			(effects
				(font
					(size 1.27 1.27)
				)
			)
		)
		(property "Value" "FCM1608CF-121T03-GP"
			(at -0.0254 -2.8956 180)
			(unlocked yes)
			(layer "F.Fab")
			(hide yes)
			(effects
				(font
					(size 1.016 1.016)
					(thickness 0.1524)
				)
			)
		)
		(property "Device Type" "L1608-UH38"
			(at -0.0254 -4.4196 180)
			(unlocked yes)
			(layer "F.Fab")
			(hide yes)
			(effects
				(font
					(size 1.016 1.016)
					(thickness 0.1524)
				)
			)
		)
		(duplicate_pad_numbers_are_jumpers no)
		(fp_line
			(start 0.254 0)
			(end -0.254 0)
			(stroke
				(width 0.2032)
				(type default)
			)
			(layer "F.SilkS")
		)
		(fp_rect
			(start -0.5842 1.3335)
			(end 0.5842 -1.3335)
			(stroke
				(width 0)
				(type default)
			)
			(fill no)
			(layer "F.CrtYd")
		)
		(fp_rect
			(start -0.5842 1.3335)
			(end 0.5842 -1.3335)
			(stroke
				(width 0)
				(type default)
			)
			(fill no)
			(layer "F.Fab")
		)
		(pad "1" smd custom
			(at 0 -0.762 180)
			(size 0.2159 0.2159)
			(layers "F.Cu" "F.Mask" "F.Paste")
			(net "P3V3")
			(options
				(clearance outline)
				(anchor circle)
			)
			(primitives
				(gr_poly
					(pts
						(arc
							(start -0.3302 -0.4318)
							(mid -0.402042 -0.402042)
							(end -0.4318 -0.3302)
						)
						(arc
							(start -0.4318 0.3302)
							(mid -0.402042 0.402042)
							(end -0.3302 0.4318)
						)
						(arc
							(start 0.3302 0.4318)
							(mid 0.402042 0.402042)
							(end 0.4318 0.3302)
						)
						(arc
							(start 0.4318 -0.3302)
							(mid 0.402042 -0.402042)
							(end 0.3302 -0.4318)
						)
					)
					(width 0)
					(fill yes)
				)
			)
		)
		(pad "2" smd custom
			(at 0 0.762 180)
			(size 0.2159 0.2159)
			(layers "F.Cu" "F.Mask" "F.Paste")
			(net "NCT7904_3VDD")
			(options
				(clearance outline)
				(anchor circle)
			)
			(primitives
				(gr_poly
					(pts
						(arc
							(start -0.3302 -0.4318)
							(mid -0.402042 -0.402042)
							(end -0.4318 -0.3302)
						)
						(arc
							(start -0.4318 0.3302)
							(mid -0.402042 0.402042)
							(end -0.3302 0.4318)
						)
						(arc
							(start 0.3302 0.4318)
							(mid 0.402042 0.402042)
							(end 0.4318 0.3302)
						)
						(arc
							(start 0.4318 -0.3302)
							(mid 0.402042 -0.402042)
							(end 0.3302 -0.4318)
						)
					)
					(width 0)
					(fill yes)
				)
			)
		)
	)
	(footprint ""
		(layer "F.Cu")
		(at 42.05859 -162.643566 180)
		(property "Reference" "OSC1"
			(at 0 0 180)
			(layer "F.SilkS")
			(hide yes)
			(effects
				(font
					(size 1.27 1.27)
				)
			)
		)
		(property "Value" "OSC-33MHZ-7-GP"
			(at 0 -10.1092 180)
			(unlocked yes)
			(layer "F.Fab")
			(hide yes)
			(effects
				(font
					(size 1.016 1.016)
					(thickness 0.1524)
				)
			)
		)
		(property "Device Type" "SMD-OSC8H52"
			(at 0 -11.6332 180)
			(unlocked yes)
			(layer "F.Fab")
			(hide yes)
			(effects
				(font
					(size 1.016 1.016)
					(thickness 0.1524)
				)
			)
		)
		(duplicate_pad_numbers_are_jumpers no)
		(fp_line
			(start 2.7559 2.4638)
			(end -2.7559 2.4638)
			(stroke
				(width 0.1524)
				(type default)
			)
			(layer "F.SilkS")
		)
		(fp_line
			(start 2.7559 -2.4638)
			(end 2.7559 2.4638)
			(stroke
				(width 0.1524)
				(type default)
			)
			(layer "F.SilkS")
		)
		(fp_line
			(start -1.242822 2.55143)
			(end -2.852166 2.55143)
			(stroke
				(width 0.3302)
				(type default)
			)
			(layer "F.SilkS")
		)
		(fp_line
			(start -2.7559 2.4638)
			(end -2.7559 -2.4638)
			(stroke
				(width 0.1524)
				(type default)
			)
			(layer "F.SilkS")
		)
		(fp_line
			(start -2.7559 -2.4638)
			(end 2.7559 -2.4638)
			(stroke
				(width 0.1524)
				(type default)
			)
			(layer "F.SilkS")
		)
		(fp_line
			(start -2.852166 2.55143)
			(end -2.852166 1.131316)
			(stroke
				(width 0.3302)
				(type default)
			)
			(layer "F.SilkS")
		)
		(fp_poly
			(pts
				(xy -1.778 3.0734) (xy -1.2446 2.54) (xy -0.762 3.0734)
			)
			(stroke
				(width 0)
				(type default)
			)
			(fill yes)
			(layer "F.SilkS")
		)
		(fp_poly
			(pts
				(xy -3.0099 2.7178) (xy -3.0099 -2.7178) (xy 3.0099 -2.7178) (xy 3.0099 2.7178)
			)
			(stroke
				(width 0)
				(type default)
			)
			(fill no)
			(layer "F.CrtYd")
		)
		(fp_poly
			(pts
				(xy -3.0099 -2.7178) (xy 3.0099 -2.7178) (xy 3.0099 2.7178) (xy -3.0099 2.7178)
			)
			(stroke
				(width 0)
				(type default)
			)
			(fill no)
			(layer "F.Fab")
		)
		(pad "1" smd rect
			(at -1.46939 1.39954 180)
			(size 1.8034 1.6002)
			(layers "F.Cu" "F.Mask" "F.Paste")
			(net "OSC_TRI_S")
		)
		(pad "2" smd rect
			(at 1.46939 1.39954 180)
			(size 1.8034 1.6002)
			(layers "F.Cu" "F.Mask" "F.Paste")
			(net "GND")
		)
		(pad "3" smd rect
			(at 1.46939 -1.39954 180)
			(size 1.8034 1.6002)
			(layers "F.Cu" "F.Mask" "F.Paste")
			(net "NCT7904_CLK")
		)
		(pad "4" smd rect
			(at -1.46939 -1.39954 180)
			(size 1.8034 1.6002)
			(layers "F.Cu" "F.Mask" "F.Paste")
			(net "P3V3")
		)
		(zone
			(layer "F.Cu")
			(hatch none 0.5)
			(connect_pads
				(clearance 0)
			)
			(min_thickness 0.25)
			(keepout
				(tracks not_allowed)
				(vias allowed)
				(pads allowed)
				(copperpour not_allowed)
				(footprints allowed)
			)
			(placement
				(enabled no)
				(sheetname "")
			)
			(fill
				(thermal_gap 0.5)
				(thermal_bridge_width 0.5)
				(island_removal_mode 0)
			)
			(polygon
				(pts
					(xy 42.302938 -162.367468) (xy 42.302938 -162.919664) (xy 41.814242 -162.919664) (xy 41.814242 -162.367468)
				)
			)
		)
		(zone
			(layer "F.Cu")
			(hatch none 0.5)
			(connect_pads
				(clearance 0)
			)
			(min_thickness 0.25)
			(keepout
				(tracks allowed)
				(vias not_allowed)
				(pads allowed)
				(copperpour not_allowed)
				(footprints allowed)
			)
			(placement
				(enabled no)
				(sheetname "")
			)
			(fill
				(thermal_gap 0.5)
				(thermal_bridge_width 0.5)
				(island_removal_mode 0)
			)
			(polygon
				(pts
					(xy 42.62628 -164.843206) (xy 42.62628 -163.243006) (xy 44.42968 -163.243006) (xy 44.42968 -162.044126)
					(xy 42.62628 -162.044126) (xy 42.62628 -160.443926) (xy 41.4909 -160.443926) (xy 41.4909 -162.044126)
					(xy 39.6875 -162.044126) (xy 39.6875 -163.243006) (xy 41.4909 -163.243006) (xy 41.4909 -164.843206)
				)
			)
		)
	)
	(footprint ""
		(layer "F.Cu")
		(at 46.863 -416.814 90)
		(property "Reference" "PC8"
			(at 0 0 90)
			(layer "F.SilkS")
			(hide yes)
			(effects
				(font
					(size 1.27 1.27)
				)
			)
		)
		(property "Value" "SC1U25V5KX-1GP"
			(at -0.0762 -6.1214 90)
			(unlocked yes)
			(layer "F.Fab")
			(hide yes)
			(effects
				(font
					(size 1.016 1.016)
					(thickness 0.1524)
				)
			)
		)
		(property "Device Type" "C805H58"
			(at -0.0762 -8.1534 90)
			(unlocked yes)
			(layer "F.Fab")
			(hide yes)
			(effects
				(font
					(size 1.016 1.016)
					(thickness 0.1524)
				)
			)
		)
		(duplicate_pad_numbers_are_jumpers no)
		(fp_line
			(start 0.635 0)
			(end -0.635 0)
			(stroke
				(width 0.508)
				(type default)
			)
			(layer "F.SilkS")
		)
		(fp_rect
			(start -0.9652 1.778)
			(end 0.9652 -1.778)
			(stroke
				(width 0)
				(type default)
			)
			(fill no)
			(layer "F.CrtYd")
		)
		(fp_poly
			(pts
				(xy -0.9652 -1.778) (xy 0.9652 -1.778) (xy 0.9652 1.778) (xy -0.9652 1.778)
			)
			(stroke
				(width 0)
				(type default)
			)
			(fill no)
			(layer "F.Fab")
		)
		(pad "1" smd rect
			(at 0 -0.9652 90)
			(size 1.397 1.143)
			(layers "F.Cu" "F.Mask" "F.Paste")
			(net "P12V_AUX")
		)
		(pad "2" smd rect
			(at 0 0.9652 90)
			(size 1.397 1.143)
			(layers "F.Cu" "F.Mask" "F.Paste")
			(net "GND")
		)
	)
	(footprint ""
		(layer "F.Cu")
		(at 34.741866 -137.508234 180)
		(property "Reference" "PR105"
			(at 0 0 180)
			(layer "F.SilkS")
			(hide yes)
			(effects
				(font
					(size 1.27 1.27)
				)
			)
		)
		(property "Value" "2K7R2F-GP"
			(at 0.064008 -3.993896 180)
			(unlocked yes)
			(layer "F.Fab")
			(hide yes)
			(effects
				(font
					(size 1.016 1.016)
					(thickness 0.1524)
				)
			)
		)
		(property "Device Type" "R402H16"
			(at 0.064008 -5.517896 180)
			(unlocked yes)
			(layer "F.Fab")
			(hide yes)
			(effects
				(font
					(size 1.016 1.016)
					(thickness 0.1524)
				)
			)
		)
		(duplicate_pad_numbers_are_jumpers no)
		(fp_line
			(start 0.508 -0.9398)
			(end -0.508 -0.9398)
			(stroke
				(width 0.1524)
				(type default)
			)
			(layer "F.SilkS")
		)
		(fp_line
			(start -0.508 -0.9398)
			(end -0.508 0.9398)
			(stroke
				(width 0.1524)
				(type default)
			)
			(layer "F.SilkS")
		)
		(fp_rect
			(start -0.508 0.9398)
			(end 0.508 -0.9398)
			(stroke
				(width 0)
				(type default)
			)
			(fill no)
			(layer "F.CrtYd")
		)
		(fp_rect
			(start -0.508 0.9398)
			(end 0.508 -0.9398)
			(stroke
				(width 0)
				(type default)
			)
			(fill no)
			(layer "F.Fab")
		)
		(pad "1" smd custom
			(at 0 -0.4445 180)
			(size 0.1397 0.1397)
			(layers "F.Cu" "F.Mask" "F.Paste")
			(net "P12VL")
			(options
				(clearance outline)
				(anchor circle)
			)
			(primitives
				(gr_poly
					(pts
						(arc
							(start -0.1778 -0.2794)
							(mid -0.249642 -0.249642)
							(end -0.2794 -0.1778)
						)
						(arc
							(start -0.2794 0.1778)
							(mid -0.249642 0.249642)
							(end -0.1778 0.2794)
						)
						(arc
							(start 0.1778 0.2794)
							(mid 0.249642 0.249642)
							(end 0.2794 0.1778)
						)
						(arc
							(start 0.2794 -0.1778)
							(mid 0.249642 -0.249642)
							(end 0.1778 -0.2794)
						)
					)
					(width 0)
					(fill yes)
				)
			)
		)
		(pad "2" smd custom
			(at 0 0.4445 180)
			(size 0.1397 0.1397)
			(layers "F.Cu" "F.Mask" "F.Paste")
			(net "P12VL_2490_PG")
			(options
				(clearance outline)
				(anchor circle)
			)
			(primitives
				(gr_poly
					(pts
						(arc
							(start -0.1778 -0.2794)
							(mid -0.249642 -0.249642)
							(end -0.2794 -0.1778)
						)
						(arc
							(start -0.2794 0.1778)
							(mid -0.249642 0.249642)
							(end -0.1778 0.2794)
						)
						(arc
							(start 0.1778 0.2794)
							(mid 0.249642 0.249642)
							(end 0.2794 0.1778)
						)
						(arc
							(start 0.2794 -0.1778)
							(mid 0.249642 -0.249642)
							(end 0.1778 -0.2794)
						)
					)
					(width 0)
					(fill yes)
				)
			)
		)
	)
	(footprint ""
		(layer "F.Cu")
		(at 40.005 -371.475 -90)
		(property "Reference" "C255"
			(at 0 0 270)
			(layer "F.SilkS")
			(hide yes)
			(effects
				(font
					(size 1.27 1.27)
				)
			)
		)
		(property "Value" "SCD1U25V3KX-LL-GP"
			(at 0 -2.8194 270)
			(unlocked yes)
			(layer "F.Fab")
			(hide yes)
			(effects
				(font
					(size 1.016 1.016)
					(thickness 0.1524)
				)
			)
		)
		(property "Device Type" "C603H36"
			(at 0 -4.3434 270)
			(unlocked yes)
			(layer "F.Fab")
			(hide yes)
			(effects
				(font
					(size 1.016 1.016)
					(thickness 0.1524)
				)
			)
		)
		(duplicate_pad_numbers_are_jumpers no)
		(fp_line
			(start 0.508 0)
			(end -0.508 0)
			(stroke
				(width 0.2032)
				(type default)
			)
			(layer "F.SilkS")
		)
		(fp_rect
			(start -0.5842 1.3335)
			(end 0.5842 -1.3335)
			(stroke
				(width 0)
				(type default)
			)
			(fill no)
			(layer "F.CrtYd")
		)
		(fp_rect
			(start -0.5842 1.3335)
			(end 0.5842 -1.3335)
			(stroke
				(width 0)
				(type default)
			)
			(fill no)
			(layer "F.Fab")
		)
		(pad "1" smd custom
			(at 0 -0.762 270)
			(size 0.2159 0.2159)
			(layers "F.Cu" "F.Mask" "F.Paste")
			(net "ADM1276_LATCH_B")
			(options
				(clearance outline)
				(anchor circle)
			)
			(primitives
				(gr_poly
					(pts
						(arc
							(start -0.3302 -0.4318)
							(mid -0.402042 -0.402042)
							(end -0.4318 -0.3302)
						)
						(arc
							(start -0.4318 0.3302)
							(mid -0.402042 0.402042)
							(end -0.3302 0.4318)
						)
						(arc
							(start 0.3302 0.4318)
							(mid 0.402042 0.402042)
							(end 0.4318 0.3302)
						)
						(arc
							(start 0.4318 -0.3302)
							(mid 0.402042 -0.402042)
							(end 0.3302 -0.4318)
						)
					)
					(width 0)
					(fill yes)
				)
			)
		)
		(pad "2" smd custom
			(at 0 0.762 270)
			(size 0.2159 0.2159)
			(layers "F.Cu" "F.Mask" "F.Paste")
			(net "GND")
			(options
				(clearance outline)
				(anchor circle)
			)
			(primitives
				(gr_poly
					(pts
						(arc
							(start -0.3302 -0.4318)
							(mid -0.402042 -0.402042)
							(end -0.4318 -0.3302)
						)
						(arc
							(start -0.4318 0.3302)
							(mid -0.402042 0.402042)
							(end -0.3302 0.4318)
						)
						(arc
							(start 0.3302 0.4318)
							(mid 0.402042 0.402042)
							(end 0.4318 0.3302)
						)
						(arc
							(start 0.4318 -0.3302)
							(mid 0.402042 -0.402042)
							(end 0.3302 -0.4318)
						)
					)
					(width 0)
					(fill yes)
				)
			)
		)
	)
	(footprint ""
		(layer "F.Cu")
		(at 32.78251 -171.677076)
		(property "Reference" "C12"
			(at 0 0 0)
			(layer "F.SilkS")
			(hide yes)
			(effects
				(font
					(size 1.27 1.27)
				)
			)
		)
		(property "Value" "SC1U16V3KX-5GP"
			(at 0 -2.8194 0)
			(unlocked yes)
			(layer "F.Fab")
			(hide yes)
			(effects
				(font
					(size 1.016 1.016)
					(thickness 0.1524)
				)
			)
		)
		(property "Device Type" "C603H36"
			(at 0 -4.3434 0)
			(unlocked yes)
			(layer "F.Fab")
			(hide yes)
			(effects
				(font
					(size 1.016 1.016)
					(thickness 0.1524)
				)
			)
		)
		(duplicate_pad_numbers_are_jumpers no)
		(fp_line
			(start 0.508 0)
			(end -0.508 0)
			(stroke
				(width 0.2032)
				(type default)
			)
			(layer "F.SilkS")
		)
		(fp_rect
			(start -0.5842 1.3335)
			(end 0.5842 -1.3335)
			(stroke
				(width 0)
				(type default)
			)
			(fill no)
			(layer "F.CrtYd")
		)
		(fp_rect
			(start -0.5842 1.3335)
			(end 0.5842 -1.3335)
			(stroke
				(width 0)
				(type default)
			)
			(fill no)
			(layer "F.Fab")
		)
		(pad "1" smd custom
			(at 0 -0.762)
			(size 0.2159 0.2159)
			(layers "F.Cu" "F.Mask" "F.Paste")
			(net "P3V3")
			(options
				(clearance outline)
				(anchor circle)
			)
			(primitives
				(gr_poly
					(pts
						(arc
							(start -0.3302 -0.4318)
							(mid -0.402042 -0.402042)
							(end -0.4318 -0.3302)
						)
						(arc
							(start -0.4318 0.3302)
							(mid -0.402042 0.402042)
							(end -0.3302 0.4318)
						)
						(arc
							(start 0.3302 0.4318)
							(mid 0.402042 0.402042)
							(end 0.4318 0.3302)
						)
						(arc
							(start 0.4318 -0.3302)
							(mid 0.402042 -0.402042)
							(end 0.3302 -0.4318)
						)
					)
					(width 0)
					(fill yes)
				)
			)
		)
		(pad "2" smd custom
			(at 0 0.762)
			(size 0.2159 0.2159)
			(layers "F.Cu" "F.Mask" "F.Paste")
			(net "GND")
			(options
				(clearance outline)
				(anchor circle)
			)
			(primitives
				(gr_poly
					(pts
						(arc
							(start -0.3302 -0.4318)
							(mid -0.402042 -0.402042)
							(end -0.4318 -0.3302)
						)
						(arc
							(start -0.4318 0.3302)
							(mid -0.402042 0.402042)
							(end -0.3302 0.4318)
						)
						(arc
							(start 0.3302 0.4318)
							(mid 0.402042 0.402042)
							(end 0.4318 0.3302)
						)
						(arc
							(start 0.4318 -0.3302)
							(mid 0.402042 -0.402042)
							(end 0.3302 -0.4318)
						)
					)
					(width 0)
					(fill yes)
				)
			)
		)
	)
	(footprint ""
		(layer "F.Cu")
		(at 35.3314 -254.3556 180)
		(property "Reference" "R107"
			(at 0 0 180)
			(layer "F.SilkS")
			(hide yes)
			(effects
				(font
					(size 1.27 1.27)
				)
			)
		)
		(property "Value" "0R2J-2-GP"
			(at 0.064008 -3.993896 180)
			(unlocked yes)
			(layer "F.Fab")
			(hide yes)
			(effects
				(font
					(size 1.016 1.016)
					(thickness 0.1524)
				)
			)
		)
		(property "Device Type" "R402H16"
			(at 0.064008 -5.517896 180)
			(unlocked yes)
			(layer "F.Fab")
			(hide yes)
			(effects
				(font
					(size 1.016 1.016)
					(thickness 0.1524)
				)
			)
		)
		(duplicate_pad_numbers_are_jumpers no)
		(fp_line
			(start 0.508 -0.9398)
			(end -0.508 -0.9398)
			(stroke
				(width 0.1524)
				(type default)
			)
			(layer "F.SilkS")
		)
		(fp_line
			(start -0.508 -0.9398)
			(end -0.508 0.9398)
			(stroke
				(width 0.1524)
				(type default)
			)
			(layer "F.SilkS")
		)
		(fp_rect
			(start -0.508 0.9398)
			(end 0.508 -0.9398)
			(stroke
				(width 0)
				(type default)
			)
			(fill no)
			(layer "F.CrtYd")
		)
		(fp_rect
			(start -0.508 0.9398)
			(end 0.508 -0.9398)
			(stroke
				(width 0)
				(type default)
			)
			(fill no)
			(layer "F.Fab")
		)
		(pad "1" smd custom
			(at 0 -0.4445 180)
			(size 0.1397 0.1397)
			(layers "F.Cu" "F.Mask" "F.Paste")
			(net "I2C_C_SCL_LEDDRV")
			(options
				(clearance outline)
				(anchor circle)
			)
			(primitives
				(gr_poly
					(pts
						(arc
							(start -0.1778 -0.2794)
							(mid -0.249642 -0.249642)
							(end -0.2794 -0.1778)
						)
						(arc
							(start -0.2794 0.1778)
							(mid -0.249642 0.249642)
							(end -0.1778 0.2794)
						)
						(arc
							(start 0.1778 0.2794)
							(mid 0.249642 0.249642)
							(end 0.2794 0.1778)
						)
						(arc
							(start 0.2794 -0.1778)
							(mid 0.249642 -0.249642)
							(end 0.1778 -0.2794)
						)
					)
					(width 0)
					(fill yes)
				)
			)
		)
		(pad "2" smd custom
			(at 0 0.4445 180)
			(size 0.1397 0.1397)
			(layers "F.Cu" "F.Mask" "F.Paste")
			(net "I2C_C_SCL")
			(options
				(clearance outline)
				(anchor circle)
			)
			(primitives
				(gr_poly
					(pts
						(arc
							(start -0.1778 -0.2794)
							(mid -0.249642 -0.249642)
							(end -0.2794 -0.1778)
						)
						(arc
							(start -0.2794 0.1778)
							(mid -0.249642 0.249642)
							(end -0.1778 0.2794)
						)
						(arc
							(start 0.1778 0.2794)
							(mid 0.249642 0.249642)
							(end 0.2794 0.1778)
						)
						(arc
							(start 0.2794 -0.1778)
							(mid 0.249642 -0.249642)
							(end 0.1778 -0.2794)
						)
					)
					(width 0)
					(fill yes)
				)
			)
		)
	)
	(footprint ""
		(layer "F.Cu")
		(at 29.1338 -153.289 90)
		(property "Reference" "C8"
			(at 0 0 90)
			(layer "F.SilkS")
			(hide yes)
			(effects
				(font
					(size 1.27 1.27)
				)
			)
		)
		(property "Value" "SC2200P50V2KX-2GP"
			(at 1.1811 -2.7051 90)
			(unlocked yes)
			(layer "F.Fab")
			(hide yes)
			(effects
				(font
					(size 1.016 1.016)
					(thickness 0.1524)
				)
			)
		)
		(property "Device Type" "C402H22"
			(at 1.1811 -4.2291 90)
			(unlocked yes)
			(layer "F.Fab")
			(hide yes)
			(effects
				(font
					(size 1.016 1.016)
					(thickness 0.1524)
				)
			)
		)
		(duplicate_pad_numbers_are_jumpers no)
		(fp_rect
			(start -0.4318 0.9525)
			(end 0.4318 -0.9525)
			(stroke
				(width 0)
				(type default)
			)
			(fill no)
			(layer "F.CrtYd")
		)
		(fp_rect
			(start -0.4318 0.9525)
			(end 0.4318 -0.9525)
			(stroke
				(width 0)
				(type default)
			)
			(fill no)
			(layer "F.Fab")
		)
		(pad "1" smd custom
			(at 0 -0.4445 90)
			(size 0.1524 0.1524)
			(layers "F.Cu" "F.Mask" "F.Paste")
			(net "NCT7904_D2+")
			(options
				(clearance outline)
				(anchor circle)
			)
			(primitives
				(gr_poly
					(pts
						(arc
							(start 0.3048 -0.2032)
							(mid 0.275042 -0.275042)
							(end 0.2032 -0.3048)
						)
						(arc
							(start -0.2032 -0.3048)
							(mid -0.275042 -0.275042)
							(end -0.3048 -0.2032)
						)
						(arc
							(start -0.3048 0.2032)
							(mid -0.275042 0.275042)
							(end -0.2032 0.3048)
						)
						(arc
							(start 0.2032 0.3048)
							(mid 0.275042 0.275042)
							(end 0.3048 0.2032)
						)
					)
					(width 0)
					(fill yes)
				)
			)
		)
		(pad "2" smd custom
			(at 0 0.4445 90)
			(size 0.1524 0.1524)
			(layers "F.Cu" "F.Mask" "F.Paste")
			(net "NCT7904_D2-")
			(options
				(clearance outline)
				(anchor circle)
			)
			(primitives
				(gr_poly
					(pts
						(arc
							(start 0.3048 -0.2032)
							(mid 0.275042 -0.275042)
							(end 0.2032 -0.3048)
						)
						(arc
							(start -0.2032 -0.3048)
							(mid -0.275042 -0.275042)
							(end -0.3048 -0.2032)
						)
						(arc
							(start -0.3048 0.2032)
							(mid -0.275042 0.275042)
							(end -0.2032 0.3048)
						)
						(arc
							(start 0.2032 0.3048)
							(mid 0.275042 0.275042)
							(end 0.3048 0.2032)
						)
					)
					(width 0)
					(fill yes)
				)
			)
		)
	)
	(footprint ""
		(layer "F.Cu")
		(at 36.195 -176.657 -90)
		(property "Reference" "C256"
			(at 0 0 270)
			(layer "F.SilkS")
			(hide yes)
			(effects
				(font
					(size 1.27 1.27)
				)
			)
		)
		(property "Value" "SCD1U16V2KX-3GP"
			(at 1.1811 -2.7051 270)
			(unlocked yes)
			(layer "F.Fab")
			(hide yes)
			(effects
				(font
					(size 1.016 1.016)
					(thickness 0.1524)
				)
			)
		)
		(property "Device Type" "C402H22"
			(at 1.1811 -4.2291 270)
			(unlocked yes)
			(layer "F.Fab")
			(hide yes)
			(effects
				(font
					(size 1.016 1.016)
					(thickness 0.1524)
				)
			)
		)
		(duplicate_pad_numbers_are_jumpers no)
		(fp_rect
			(start -0.4318 0.9525)
			(end 0.4318 -0.9525)
			(stroke
				(width 0)
				(type default)
			)
			(fill no)
			(layer "F.CrtYd")
		)
		(fp_rect
			(start -0.4318 0.9525)
			(end 0.4318 -0.9525)
			(stroke
				(width 0)
				(type default)
			)
			(fill no)
			(layer "F.Fab")
		)
		(pad "1" smd custom
			(at 0 -0.4445 270)
			(size 0.1524 0.1524)
			(layers "F.Cu" "F.Mask" "F.Paste")
			(net "TEMP_ALM#_IN_D")
			(options
				(clearance outline)
				(anchor circle)
			)
			(primitives
				(gr_poly
					(pts
						(arc
							(start 0.3048 -0.2032)
							(mid 0.275042 -0.275042)
							(end 0.2032 -0.3048)
						)
						(arc
							(start -0.2032 -0.3048)
							(mid -0.275042 -0.275042)
							(end -0.3048 -0.2032)
						)
						(arc
							(start -0.3048 0.2032)
							(mid -0.275042 0.275042)
							(end -0.2032 0.3048)
						)
						(arc
							(start 0.2032 0.3048)
							(mid 0.275042 0.275042)
							(end 0.3048 0.2032)
						)
					)
					(width 0)
					(fill yes)
				)
			)
		)
		(pad "2" smd custom
			(at 0 0.4445 270)
			(size 0.1524 0.1524)
			(layers "F.Cu" "F.Mask" "F.Paste")
			(net "GND")
			(options
				(clearance outline)
				(anchor circle)
			)
			(primitives
				(gr_poly
					(pts
						(arc
							(start 0.3048 -0.2032)
							(mid 0.275042 -0.275042)
							(end 0.2032 -0.3048)
						)
						(arc
							(start -0.2032 -0.3048)
							(mid -0.275042 -0.275042)
							(end -0.3048 -0.2032)
						)
						(arc
							(start -0.3048 0.2032)
							(mid -0.275042 0.275042)
							(end -0.2032 0.3048)
						)
						(arc
							(start 0.2032 0.3048)
							(mid 0.275042 0.275042)
							(end 0.3048 0.2032)
						)
					)
					(width 0)
					(fill yes)
				)
			)
		)
	)
	(footprint ""
		(layer "F.Cu")
		(at 13.081 -448.2338 90)
		(property "Reference" "R101"
			(at 0 0 90)
			(layer "F.SilkS")
			(hide yes)
			(effects
				(font
					(size 1.27 1.27)
				)
			)
		)
		(property "Value" "27KR3F-GP"
			(at -0.0254 -2.5146 90)
			(unlocked yes)
			(layer "F.Fab")
			(hide yes)
			(effects
				(font
					(size 1.016 1.016)
					(thickness 0.1524)
				)
			)
		)
		(property "Device Type" "R603H22"
			(at -0.0254 -4.0386 90)
			(unlocked yes)
			(layer "F.Fab")
			(hide yes)
			(effects
				(font
					(size 1.016 1.016)
					(thickness 0.1524)
				)
			)
		)
		(duplicate_pad_numbers_are_jumpers no)
		(fp_line
			(start 0.2032 0)
			(end 0.4826 0)
			(stroke
				(width 0.2032)
				(type default)
			)
			(layer "F.SilkS")
		)
		(fp_line
			(start -0.4826 0)
			(end -0.2032 0)
			(stroke
				(width 0.2032)
				(type default)
			)
			(layer "F.SilkS")
		)
		(fp_rect
			(start -0.5842 1.3335)
			(end 0.5842 -1.3335)
			(stroke
				(width 0)
				(type default)
			)
			(fill no)
			(layer "F.CrtYd")
		)
		(fp_rect
			(start -0.5842 1.3335)
			(end 0.5842 -1.3335)
			(stroke
				(width 0)
				(type default)
			)
			(fill no)
			(layer "F.Fab")
		)
		(pad "1" smd custom
			(at 0 -0.762 90)
			(size 0.2159 0.2159)
			(layers "F.Cu" "F.Mask" "F.Paste")
			(net "FAN_TACH2")
			(options
				(clearance outline)
				(anchor circle)
			)
			(primitives
				(gr_poly
					(pts
						(arc
							(start -0.3302 -0.4318)
							(mid -0.402042 -0.402042)
							(end -0.4318 -0.3302)
						)
						(arc
							(start -0.4318 0.3302)
							(mid -0.402042 0.402042)
							(end -0.3302 0.4318)
						)
						(arc
							(start 0.3302 0.4318)
							(mid 0.402042 0.402042)
							(end 0.4318 0.3302)
						)
						(arc
							(start 0.4318 -0.3302)
							(mid 0.402042 -0.402042)
							(end 0.3302 -0.4318)
						)
					)
					(width 0)
					(fill yes)
				)
			)
		)
		(pad "2" smd custom
			(at 0 0.762 90)
			(size 0.2159 0.2159)
			(layers "F.Cu" "F.Mask" "F.Paste")
			(net "FANIN_2")
			(options
				(clearance outline)
				(anchor circle)
			)
			(primitives
				(gr_poly
					(pts
						(arc
							(start -0.3302 -0.4318)
							(mid -0.402042 -0.402042)
							(end -0.4318 -0.3302)
						)
						(arc
							(start -0.4318 0.3302)
							(mid -0.402042 0.402042)
							(end -0.3302 0.4318)
						)
						(arc
							(start 0.3302 0.4318)
							(mid 0.402042 0.402042)
							(end 0.4318 0.3302)
						)
						(arc
							(start 0.4318 -0.3302)
							(mid 0.402042 -0.402042)
							(end 0.3302 -0.4318)
						)
					)
					(width 0)
					(fill yes)
				)
			)
		)
	)
	(footprint ""
		(layer "F.Cu")
		(at 28.321 -352.425 -90)
		(property "Reference" "C260"
			(at 0 0 270)
			(layer "F.SilkS")
			(hide yes)
			(effects
				(font
					(size 1.27 1.27)
				)
			)
		)
		(property "Value" "SC10U25V6KX-1GP"
			(at -0.0762 -5.1308 270)
			(unlocked yes)
			(layer "F.Fab")
			(hide yes)
			(effects
				(font
					(size 1.016 1.016)
					(thickness 0.1524)
				)
			)
		)
		(property "Device Type" "C1206H71"
			(at -0.127 -6.6548 270)
			(unlocked yes)
			(layer "F.Fab")
			(hide yes)
			(effects
				(font
					(size 1.016 1.016)
					(thickness 0.1524)
				)
			)
		)
		(duplicate_pad_numbers_are_jumpers no)
		(fp_line
			(start -1.016 2.2352)
			(end -1.016 0.8382)
			(stroke
				(width 0.1524)
				(type default)
			)
			(layer "F.SilkS")
		)
		(fp_line
			(start 1.016 2.2352)
			(end -1.016 2.2352)
			(stroke
				(width 0.1524)
				(type default)
			)
			(layer "F.SilkS")
		)
		(fp_line
			(start 1.016 0.8382)
			(end 1.016 2.2352)
			(stroke
				(width 0.1524)
				(type default)
			)
			(layer "F.SilkS")
		)
		(fp_line
			(start -1.016 -0.8382)
			(end -1.016 -2.2352)
			(stroke
				(width 0.1524)
				(type default)
			)
			(layer "F.SilkS")
		)
		(fp_line
			(start -1.016 -2.2352)
			(end 1.016 -2.2352)
			(stroke
				(width 0.1524)
				(type default)
			)
			(layer "F.SilkS")
		)
		(fp_line
			(start 1.016 -2.2352)
			(end 1.016 -0.8382)
			(stroke
				(width 0.1524)
				(type default)
			)
			(layer "F.SilkS")
		)
		(fp_rect
			(start -1.0922 2.3114)
			(end 1.0922 -2.3114)
			(stroke
				(width 0)
				(type default)
			)
			(fill no)
			(layer "F.CrtYd")
		)
		(fp_poly
			(pts
				(xy 1.0922 -2.3114) (xy 1.0922 2.3114) (xy -1.0922 2.3114) (xy -1.0922 -2.3114)
			)
			(stroke
				(width 0)
				(type default)
			)
			(fill no)
			(layer "F.Fab")
		)
		(pad "1" smd rect
			(at 0 -1.397 270)
			(size 1.651 1.27)
			(layers "F.Cu" "F.Mask" "F.Paste")
			(net "OTP_RETRY_G")
		)
		(pad "2" smd rect
			(at 0 1.397 270)
			(size 1.651 1.27)
			(layers "F.Cu" "F.Mask" "F.Paste")
			(net "GND")
		)
	)
	(footprint ""
		(layer "F.Cu")
		(at 28.2448 -210.8454 180)
		(property "Reference" "R137"
			(at 0 0 180)
			(layer "F.SilkS")
			(hide yes)
			(effects
				(font
					(size 1.27 1.27)
				)
			)
		)
		(property "Value" "0R2J-2-GP"
			(at 0.064008 -3.993896 180)
			(unlocked yes)
			(layer "F.Fab")
			(hide yes)
			(effects
				(font
					(size 1.016 1.016)
					(thickness 0.1524)
				)
			)
		)
		(property "Device Type" "R402H16"
			(at 0.064008 -5.517896 180)
			(unlocked yes)
			(layer "F.Fab")
			(hide yes)
			(effects
				(font
					(size 1.016 1.016)
					(thickness 0.1524)
				)
			)
		)
		(duplicate_pad_numbers_are_jumpers no)
		(fp_line
			(start 0.508 -0.9398)
			(end -0.508 -0.9398)
			(stroke
				(width 0.1524)
				(type default)
			)
			(layer "F.SilkS")
		)
		(fp_line
			(start -0.508 -0.9398)
			(end -0.508 0.9398)
			(stroke
				(width 0.1524)
				(type default)
			)
			(layer "F.SilkS")
		)
		(fp_rect
			(start -0.508 0.9398)
			(end 0.508 -0.9398)
			(stroke
				(width 0)
				(type default)
			)
			(fill no)
			(layer "F.CrtYd")
		)
		(fp_rect
			(start -0.508 0.9398)
			(end 0.508 -0.9398)
			(stroke
				(width 0)
				(type default)
			)
			(fill no)
			(layer "F.Fab")
		)
		(pad "1" smd custom
			(at 0 -0.4445 180)
			(size 0.1397 0.1397)
			(layers "F.Cu" "F.Mask" "F.Paste")
			(net "PWM_OUT_FAN5_NET")
			(options
				(clearance outline)
				(anchor circle)
			)
			(primitives
				(gr_poly
					(pts
						(arc
							(start -0.1778 -0.2794)
							(mid -0.249642 -0.249642)
							(end -0.2794 -0.1778)
						)
						(arc
							(start -0.2794 0.1778)
							(mid -0.249642 0.249642)
							(end -0.1778 0.2794)
						)
						(arc
							(start 0.1778 0.2794)
							(mid 0.249642 0.249642)
							(end 0.2794 0.1778)
						)
						(arc
							(start 0.2794 -0.1778)
							(mid 0.249642 -0.249642)
							(end 0.1778 -0.2794)
						)
					)
					(width 0)
					(fill yes)
				)
			)
		)
		(pad "2" smd custom
			(at 0 0.4445 180)
			(size 0.1397 0.1397)
			(layers "F.Cu" "F.Mask" "F.Paste")
			(net "PWM_OUT_FAN5")
			(options
				(clearance outline)
				(anchor circle)
			)
			(primitives
				(gr_poly
					(pts
						(arc
							(start -0.1778 -0.2794)
							(mid -0.249642 -0.249642)
							(end -0.2794 -0.1778)
						)
						(arc
							(start -0.2794 0.1778)
							(mid -0.249642 0.249642)
							(end -0.1778 0.2794)
						)
						(arc
							(start 0.1778 0.2794)
							(mid 0.249642 0.249642)
							(end 0.2794 0.1778)
						)
						(arc
							(start 0.2794 -0.1778)
							(mid 0.249642 -0.249642)
							(end 0.1778 -0.2794)
						)
					)
					(width 0)
					(fill yes)
				)
			)
		)
	)
	(footprint ""
		(layer "F.Cu")
		(at 12.7 -447.1162 90)
		(property "Reference" "C46"
			(at 0 0 90)
			(layer "F.SilkS")
			(hide yes)
			(effects
				(font
					(size 1.27 1.27)
				)
			)
		)
		(property "Value" "SCD1U16V2KX-3GP"
			(at 1.1811 -2.7051 90)
			(unlocked yes)
			(layer "F.Fab")
			(hide yes)
			(effects
				(font
					(size 1.016 1.016)
					(thickness 0.1524)
				)
			)
		)
		(property "Device Type" "C402H22"
			(at 1.1811 -4.2291 90)
			(unlocked yes)
			(layer "F.Fab")
			(hide yes)
			(effects
				(font
					(size 1.016 1.016)
					(thickness 0.1524)
				)
			)
		)
		(duplicate_pad_numbers_are_jumpers no)
		(fp_rect
			(start -0.4318 0.9525)
			(end 0.4318 -0.9525)
			(stroke
				(width 0)
				(type default)
			)
			(fill no)
			(layer "F.CrtYd")
		)
		(fp_rect
			(start -0.4318 0.9525)
			(end 0.4318 -0.9525)
			(stroke
				(width 0)
				(type default)
			)
			(fill no)
			(layer "F.Fab")
		)
		(pad "1" smd custom
			(at 0 -0.4445 90)
			(size 0.1524 0.1524)
			(layers "F.Cu" "F.Mask" "F.Paste")
			(net "FAN_TACH2")
			(options
				(clearance outline)
				(anchor circle)
			)
			(primitives
				(gr_poly
					(pts
						(arc
							(start 0.3048 -0.2032)
							(mid 0.275042 -0.275042)
							(end 0.2032 -0.3048)
						)
						(arc
							(start -0.2032 -0.3048)
							(mid -0.275042 -0.275042)
							(end -0.3048 -0.2032)
						)
						(arc
							(start -0.3048 0.2032)
							(mid -0.275042 0.275042)
							(end -0.2032 0.3048)
						)
						(arc
							(start 0.2032 0.3048)
							(mid 0.275042 0.275042)
							(end 0.3048 0.2032)
						)
					)
					(width 0)
					(fill yes)
				)
			)
		)
		(pad "2" smd custom
			(at 0 0.4445 90)
			(size 0.1524 0.1524)
			(layers "F.Cu" "F.Mask" "F.Paste")
			(net "GND")
			(options
				(clearance outline)
				(anchor circle)
			)
			(primitives
				(gr_poly
					(pts
						(arc
							(start 0.3048 -0.2032)
							(mid 0.275042 -0.275042)
							(end 0.2032 -0.3048)
						)
						(arc
							(start -0.2032 -0.3048)
							(mid -0.275042 -0.275042)
							(end -0.3048 -0.2032)
						)
						(arc
							(start -0.3048 0.2032)
							(mid -0.275042 0.275042)
							(end -0.2032 0.3048)
						)
						(arc
							(start 0.2032 0.3048)
							(mid 0.275042 0.275042)
							(end 0.3048 0.2032)
						)
					)
					(width 0)
					(fill yes)
				)
			)
		)
	)
	(footprint ""
		(layer "F.Cu")
		(at 22.537166 -135.554466 -90)
		(property "Reference" "PR98"
			(at 0 0 270)
			(layer "F.SilkS")
			(hide yes)
			(effects
				(font
					(size 1.27 1.27)
				)
			)
		)
		(property "Value" "1MR3J-L-GP"
			(at -0.0254 -2.5146 270)
			(unlocked yes)
			(layer "F.Fab")
			(hide yes)
			(effects
				(font
					(size 1.016 1.016)
					(thickness 0.1524)
				)
			)
		)
		(property "Device Type" "R603H22"
			(at -0.0254 -4.0386 270)
			(unlocked yes)
			(layer "F.Fab")
			(hide yes)
			(effects
				(font
					(size 1.016 1.016)
					(thickness 0.1524)
				)
			)
		)
		(duplicate_pad_numbers_are_jumpers no)
		(fp_line
			(start -0.4826 0)
			(end -0.2032 0)
			(stroke
				(width 0.2032)
				(type default)
			)
			(layer "F.SilkS")
		)
		(fp_line
			(start 0.2032 0)
			(end 0.4826 0)
			(stroke
				(width 0.2032)
				(type default)
			)
			(layer "F.SilkS")
		)
		(fp_rect
			(start -0.5842 1.3335)
			(end 0.5842 -1.3335)
			(stroke
				(width 0)
				(type default)
			)
			(fill no)
			(layer "F.CrtYd")
		)
		(fp_rect
			(start -0.5842 1.3335)
			(end 0.5842 -1.3335)
			(stroke
				(width 0)
				(type default)
			)
			(fill no)
			(layer "F.Fab")
		)
		(pad "1" smd custom
			(at 0 -0.762 270)
			(size 0.2159 0.2159)
			(layers "F.Cu" "F.Mask" "F.Paste")
			(net "P12VU_2490_VCC")
			(options
				(clearance outline)
				(anchor circle)
			)
			(primitives
				(gr_poly
					(pts
						(arc
							(start -0.3302 -0.4318)
							(mid -0.402042 -0.402042)
							(end -0.4318 -0.3302)
						)
						(arc
							(start -0.4318 0.3302)
							(mid -0.402042 0.402042)
							(end -0.3302 0.4318)
						)
						(arc
							(start 0.3302 0.4318)
							(mid 0.402042 0.402042)
							(end 0.4318 0.3302)
						)
						(arc
							(start 0.4318 -0.3302)
							(mid 0.402042 -0.402042)
							(end 0.3302 -0.4318)
						)
					)
					(width 0)
					(fill yes)
				)
			)
		)
		(pad "2" smd custom
			(at 0 0.762 270)
			(size 0.2159 0.2159)
			(layers "F.Cu" "F.Mask" "F.Paste")
			(net "P12VU_2490_SENSE")
			(options
				(clearance outline)
				(anchor circle)
			)
			(primitives
				(gr_poly
					(pts
						(arc
							(start -0.3302 -0.4318)
							(mid -0.402042 -0.402042)
							(end -0.4318 -0.3302)
						)
						(arc
							(start -0.4318 0.3302)
							(mid -0.402042 0.402042)
							(end -0.3302 0.4318)
						)
						(arc
							(start 0.3302 0.4318)
							(mid 0.402042 0.402042)
							(end 0.4318 0.3302)
						)
						(arc
							(start 0.4318 -0.3302)
							(mid 0.402042 -0.402042)
							(end 0.3302 -0.4318)
						)
					)
					(width 0)
					(fill yes)
				)
			)
		)
	)
	(footprint ""
		(layer "F.Cu")
		(at 26.416 -374.523 -90)
		(property "Reference" "PC1"
			(at 0 0 270)
			(layer "F.SilkS")
			(hide yes)
			(effects
				(font
					(size 1.27 1.27)
				)
			)
		)
		(property "Value" "SC1U25V3KX-1-GP"
			(at 0 -2.8194 270)
			(unlocked yes)
			(layer "F.Fab")
			(hide yes)
			(effects
				(font
					(size 1.016 1.016)
					(thickness 0.1524)
				)
			)
		)
		(property "Device Type" "C603H36"
			(at 0 -4.3434 270)
			(unlocked yes)
			(layer "F.Fab")
			(hide yes)
			(effects
				(font
					(size 1.016 1.016)
					(thickness 0.1524)
				)
			)
		)
		(duplicate_pad_numbers_are_jumpers no)
		(fp_line
			(start 0.508 0)
			(end -0.508 0)
			(stroke
				(width 0.2032)
				(type default)
			)
			(layer "F.SilkS")
		)
		(fp_rect
			(start -0.5842 1.3335)
			(end 0.5842 -1.3335)
			(stroke
				(width 0)
				(type default)
			)
			(fill no)
			(layer "F.CrtYd")
		)
		(fp_rect
			(start -0.5842 1.3335)
			(end 0.5842 -1.3335)
			(stroke
				(width 0)
				(type default)
			)
			(fill no)
			(layer "F.Fab")
		)
		(pad "1" smd custom
			(at 0 -0.762 270)
			(size 0.2159 0.2159)
			(layers "F.Cu" "F.Mask" "F.Paste")
			(net "ADM1276_VCC")
			(options
				(clearance outline)
				(anchor circle)
			)
			(primitives
				(gr_poly
					(pts
						(arc
							(start -0.3302 -0.4318)
							(mid -0.402042 -0.402042)
							(end -0.4318 -0.3302)
						)
						(arc
							(start -0.4318 0.3302)
							(mid -0.402042 0.402042)
							(end -0.3302 0.4318)
						)
						(arc
							(start 0.3302 0.4318)
							(mid 0.402042 0.402042)
							(end 0.4318 0.3302)
						)
						(arc
							(start 0.4318 -0.3302)
							(mid 0.402042 -0.402042)
							(end 0.3302 -0.4318)
						)
					)
					(width 0)
					(fill yes)
				)
			)
		)
		(pad "2" smd custom
			(at 0 0.762 270)
			(size 0.2159 0.2159)
			(layers "F.Cu" "F.Mask" "F.Paste")
			(net "GND")
			(options
				(clearance outline)
				(anchor circle)
			)
			(primitives
				(gr_poly
					(pts
						(arc
							(start -0.3302 -0.4318)
							(mid -0.402042 -0.402042)
							(end -0.4318 -0.3302)
						)
						(arc
							(start -0.4318 0.3302)
							(mid -0.402042 0.402042)
							(end -0.3302 0.4318)
						)
						(arc
							(start 0.3302 0.4318)
							(mid 0.402042 0.402042)
							(end 0.4318 0.3302)
						)
						(arc
							(start 0.4318 -0.3302)
							(mid 0.402042 -0.402042)
							(end 0.3302 -0.4318)
						)
					)
					(width 0)
					(fill yes)
				)
			)
		)
	)
	(footprint ""
		(layer "F.Cu")
		(at 36.212526 -362.208826)
		(property "Reference" "PQ5"
			(at 0 0 0)
			(layer "F.SilkS")
			(hide yes)
			(effects
				(font
					(size 1.27 1.27)
				)
			)
		)
		(property "Value" "PMBS3904-1-GP"
			(at 0 -9.0932 0)
			(unlocked yes)
			(layer "F.Fab")
			(hide yes)
			(effects
				(font
					(size 1.016 1.016)
					(thickness 0.1524)
				)
			)
		)
		(property "Device Type" "SOT-23-10H44"
			(at 0 -10.6172 0)
			(unlocked yes)
			(layer "F.Fab")
			(hide yes)
			(effects
				(font
					(size 1.016 1.016)
					(thickness 0.1524)
				)
			)
		)
		(duplicate_pad_numbers_are_jumpers no)
		(fp_line
			(start -1.7526 1.8796)
			(end -1.7526 0.9906)
			(stroke
				(width 0.3302)
				(type default)
			)
			(layer "F.SilkS")
		)
		(fp_line
			(start -1.651 -1.778)
			(end -1.651 1.778)
			(stroke
				(width 0.1524)
				(type default)
			)
			(layer "F.SilkS")
		)
		(fp_line
			(start -1.651 1.778)
			(end 1.651 1.778)
			(stroke
				(width 0.1524)
				(type default)
			)
			(layer "F.SilkS")
		)
		(fp_line
			(start -1.279398 2.152142)
			(end -0.9906 1.86309)
			(stroke
				(width 0.0127)
				(type default)
			)
			(layer "F.SilkS")
		)
		(fp_line
			(start -1.279144 2.15265)
			(end -0.701294 2.15265)
			(stroke
				(width 0.0127)
				(type default)
			)
			(layer "F.SilkS")
		)
		(fp_line
			(start -1.260856 2.1336)
			(end -0.720344 2.1336)
			(stroke
				(width 0.0127)
				(type default)
			)
			(layer "F.SilkS")
		)
		(fp_line
			(start -1.251458 2.124202)
			(end -0.729996 2.124202)
			(stroke
				(width 0.0127)
				(type default)
			)
			(layer "F.SilkS")
		)
		(fp_line
			(start -1.241806 2.11455)
			(end -0.739394 2.11455)
			(stroke
				(width 0.0127)
				(type default)
			)
			(layer "F.SilkS")
		)
		(fp_line
			(start -1.232408 2.105152)
			(end -0.749046 2.105152)
			(stroke
				(width 0.0127)
				(type default)
			)
			(layer "F.SilkS")
		)
		(fp_line
			(start -1.222756 2.0955)
			(end -0.758444 2.0955)
			(stroke
				(width 0.0127)
				(type default)
			)
			(layer "F.SilkS")
		)
		(fp_line
			(start -1.213358 2.086102)
			(end -0.768096 2.086102)
			(stroke
				(width 0.0127)
				(type default)
			)
			(layer "F.SilkS")
		)
		(fp_line
			(start -1.203706 2.07645)
			(end -0.777494 2.07645)
			(stroke
				(width 0.0127)
				(type default)
			)
			(layer "F.SilkS")
		)
		(fp_line
			(start -1.194308 2.067052)
			(end -0.787146 2.067052)
			(stroke
				(width 0.0127)
				(type default)
			)
			(layer "F.SilkS")
		)
		(fp_line
			(start -1.184656 2.0574)
			(end -0.796544 2.0574)
			(stroke
				(width 0.0127)
				(type default)
			)
			(layer "F.SilkS")
		)
		(fp_line
			(start -1.175258 2.048002)
			(end -0.806196 2.048002)
			(stroke
				(width 0.0127)
				(type default)
			)
			(layer "F.SilkS")
		)
		(fp_line
			(start -1.165606 2.03835)
			(end -0.815594 2.03835)
			(stroke
				(width 0.0127)
				(type default)
			)
			(layer "F.SilkS")
		)
		(fp_line
			(start -1.156208 2.028952)
			(end -0.825246 2.028952)
			(stroke
				(width 0.0127)
				(type default)
			)
			(layer "F.SilkS")
		)
		(fp_line
			(start -1.146556 2.0193)
			(end -0.834644 2.0193)
			(stroke
				(width 0.0127)
				(type default)
			)
			(layer "F.SilkS")
		)
		(fp_line
			(start -1.137158 2.009902)
			(end -0.844296 2.009902)
			(stroke
				(width 0.0127)
				(type default)
			)
			(layer "F.SilkS")
		)
		(fp_line
			(start -1.127506 2.00025)
			(end -0.853694 2.00025)
			(stroke
				(width 0.0127)
				(type default)
			)
			(layer "F.SilkS")
		)
		(fp_line
			(start -1.118108 1.990852)
			(end -0.863346 1.990852)
			(stroke
				(width 0.0127)
				(type default)
			)
			(layer "F.SilkS")
		)
		(fp_line
			(start -1.108456 1.9812)
			(end -0.872744 1.9812)
			(stroke
				(width 0.0127)
				(type default)
			)
			(layer "F.SilkS")
		)
		(fp_line
			(start -1.099058 1.971802)
			(end -0.882396 1.971802)
			(stroke
				(width 0.0127)
				(type default)
			)
			(layer "F.SilkS")
		)
		(fp_line
			(start -1.089406 1.96215)
			(end -0.891794 1.96215)
			(stroke
				(width 0.0127)
				(type default)
			)
			(layer "F.SilkS")
		)
		(fp_line
			(start -1.080008 1.952752)
			(end -0.901446 1.952752)
			(stroke
				(width 0.0127)
				(type default)
			)
			(layer "F.SilkS")
		)
		(fp_line
			(start -1.070356 1.9431)
			(end -0.910844 1.9431)
			(stroke
				(width 0.0127)
				(type default)
			)
			(layer "F.SilkS")
		)
		(fp_line
			(start -1.060958 1.933702)
			(end -0.920496 1.933702)
			(stroke
				(width 0.0127)
				(type default)
			)
			(layer "F.SilkS")
		)
		(fp_line
			(start -1.051306 1.92405)
			(end -0.929894 1.92405)
			(stroke
				(width 0.0127)
				(type default)
			)
			(layer "F.SilkS")
		)
		(fp_line
			(start -1.041908 1.914652)
			(end -0.939546 1.914652)
			(stroke
				(width 0.0127)
				(type default)
			)
			(layer "F.SilkS")
		)
		(fp_line
			(start -1.032256 1.905)
			(end -0.948944 1.905)
			(stroke
				(width 0.0127)
				(type default)
			)
			(layer "F.SilkS")
		)
		(fp_line
			(start -1.022858 1.895602)
			(end -0.958596 1.895602)
			(stroke
				(width 0.0127)
				(type default)
			)
			(layer "F.SilkS")
		)
		(fp_line
			(start -1.013206 1.88595)
			(end -0.967994 1.88595)
			(stroke
				(width 0.0127)
				(type default)
			)
			(layer "F.SilkS")
		)
		(fp_line
			(start -1.003808 1.876552)
			(end -0.977646 1.876552)
			(stroke
				(width 0.0127)
				(type default)
			)
			(layer "F.SilkS")
		)
		(fp_line
			(start -0.994156 1.8669)
			(end -0.987044 1.8669)
			(stroke
				(width 0.0127)
				(type default)
			)
			(layer "F.SilkS")
		)
		(fp_line
			(start -0.9906 1.86309)
			(end -0.701294 2.15265)
			(stroke
				(width 0.0127)
				(type default)
			)
			(layer "F.SilkS")
		)
		(fp_line
			(start -0.719074 2.145538)
			(end -1.265936 2.14122)
			(stroke
				(width 0.0127)
				(type default)
			)
			(layer "F.SilkS")
		)
		(fp_line
			(start -0.71628 2.15265)
			(end -1.26492 2.15265)
			(stroke
				(width 0.0127)
				(type default)
			)
			(layer "F.SilkS")
		)
		(fp_line
			(start -0.635 1.8796)
			(end -1.7526 1.8796)
			(stroke
				(width 0.3302)
				(type default)
			)
			(layer "F.SilkS")
		)
		(fp_line
			(start 1.651 -1.778)
			(end -1.651 -1.778)
			(stroke
				(width 0.1524)
				(type default)
			)
			(layer "F.SilkS")
		)
		(fp_line
			(start 1.651 1.778)
			(end 1.651 -1.778)
			(stroke
				(width 0.1524)
				(type default)
			)
			(layer "F.SilkS")
		)
		(fp_poly
			(pts
				(xy -1.285748 2.159) (xy -1.285748 1.8796) (xy -1.778 1.8796) (xy -1.778 -1.8796) (xy 1.778 -1.8796)
				(xy 1.778 1.8796) (xy -0.694944 1.8796) (xy -0.694944 2.159)
			)
			(stroke
				(width 0)
				(type default)
			)
			(fill no)
			(layer "F.CrtYd")
		)
		(fp_poly
			(pts
				(xy -1.285748 2.159) (xy -1.285748 1.8796) (xy -1.778 1.8796) (xy -1.778 -1.8796) (xy 1.778 -1.8796)
				(xy 1.778 1.8796) (xy -0.694944 1.8796) (xy -0.694944 2.159)
			)
			(stroke
				(width 0)
				(type default)
			)
			(fill no)
			(layer "F.Fab")
		)
		(pad "1" smd rect
			(at -0.98425 0.9525)
			(size 0.762 1.143)
			(layers "F.Cu" "F.Mask" "F.Paste")
			(net "TEMP_ALM#_REVERSE_R")
		)
		(pad "2" smd rect
			(at 0.98425 0.9525)
			(size 0.762 1.143)
			(layers "F.Cu" "F.Mask" "F.Paste")
			(net "GND")
		)
		(pad "3" smd rect
			(at 0 -0.9525)
			(size 0.762 1.143)
			(layers "F.Cu" "F.Mask" "F.Paste")
			(net "ADM1276_LATCH_B")
		)
	)
	(footprint ""
		(layer "F.Cu")
		(at 4.897882 -78.481428)
		(property "Reference" "R113"
			(at 0 0 0)
			(layer "F.SilkS")
			(hide yes)
			(effects
				(font
					(size 1.27 1.27)
				)
			)
		)
		(property "Value" "2KR2F-3-GP"
			(at 0.064008 -3.993896 0)
			(unlocked yes)
			(layer "F.Fab")
			(hide yes)
			(effects
				(font
					(size 1.016 1.016)
					(thickness 0.1524)
				)
			)
		)
		(property "Device Type" "R402H16"
			(at 0.064008 -5.517896 0)
			(unlocked yes)
			(layer "F.Fab")
			(hide yes)
			(effects
				(font
					(size 1.016 1.016)
					(thickness 0.1524)
				)
			)
		)
		(duplicate_pad_numbers_are_jumpers no)
		(fp_line
			(start -0.508 -0.9398)
			(end -0.508 0.9398)
			(stroke
				(width 0.1524)
				(type default)
			)
			(layer "F.SilkS")
		)
		(fp_line
			(start 0.508 -0.9398)
			(end -0.508 -0.9398)
			(stroke
				(width 0.1524)
				(type default)
			)
			(layer "F.SilkS")
		)
		(fp_rect
			(start -0.508 0.9398)
			(end 0.508 -0.9398)
			(stroke
				(width 0)
				(type default)
			)
			(fill no)
			(layer "F.CrtYd")
		)
		(fp_rect
			(start -0.508 0.9398)
			(end 0.508 -0.9398)
			(stroke
				(width 0)
				(type default)
			)
			(fill no)
			(layer "F.Fab")
		)
		(pad "1" smd custom
			(at 0 -0.4445)
			(size 0.1397 0.1397)
			(layers "F.Cu" "F.Mask" "F.Paste")
			(net "LED_DR_LED4")
			(options
				(clearance outline)
				(anchor circle)
			)
			(primitives
				(gr_poly
					(pts
						(arc
							(start -0.1778 -0.2794)
							(mid -0.249642 -0.249642)
							(end -0.2794 -0.1778)
						)
						(arc
							(start -0.2794 0.1778)
							(mid -0.249642 0.249642)
							(end -0.1778 0.2794)
						)
						(arc
							(start 0.1778 0.2794)
							(mid 0.249642 0.249642)
							(end 0.2794 0.1778)
						)
						(arc
							(start 0.2794 -0.1778)
							(mid 0.249642 -0.249642)
							(end 0.1778 -0.2794)
						)
					)
					(width 0)
					(fill yes)
				)
			)
		)
		(pad "2" smd custom
			(at 0 0.4445)
			(size 0.1397 0.1397)
			(layers "F.Cu" "F.Mask" "F.Paste")
			(net "LED_DR_LED4_B")
			(options
				(clearance outline)
				(anchor circle)
			)
			(primitives
				(gr_poly
					(pts
						(arc
							(start -0.1778 -0.2794)
							(mid -0.249642 -0.249642)
							(end -0.2794 -0.1778)
						)
						(arc
							(start -0.2794 0.1778)
							(mid -0.249642 0.249642)
							(end -0.1778 0.2794)
						)
						(arc
							(start 0.1778 0.2794)
							(mid 0.249642 0.249642)
							(end 0.2794 0.1778)
						)
						(arc
							(start 0.2794 -0.1778)
							(mid 0.249642 -0.249642)
							(end 0.1778 -0.2794)
						)
					)
					(width 0)
					(fill yes)
				)
			)
		)
	)
	(footprint ""
		(layer "F.Cu")
		(at 42.0116 -362.839 180)
		(property "Reference" "PR49"
			(at 0 0 180)
			(layer "F.SilkS")
			(hide yes)
			(effects
				(font
					(size 1.27 1.27)
				)
			)
		)
		(property "Value" "4K7R2J-2-GP"
			(at 0.064008 -3.993896 180)
			(unlocked yes)
			(layer "F.Fab")
			(hide yes)
			(effects
				(font
					(size 1.016 1.016)
					(thickness 0.1524)
				)
			)
		)
		(property "Device Type" "R402H16"
			(at 0.064008 -5.517896 180)
			(unlocked yes)
			(layer "F.Fab")
			(hide yes)
			(effects
				(font
					(size 1.016 1.016)
					(thickness 0.1524)
				)
			)
		)
		(duplicate_pad_numbers_are_jumpers no)
		(fp_line
			(start 0.508 -0.9398)
			(end -0.508 -0.9398)
			(stroke
				(width 0.1524)
				(type default)
			)
			(layer "F.SilkS")
		)
		(fp_line
			(start -0.508 -0.9398)
			(end -0.508 0.9398)
			(stroke
				(width 0.1524)
				(type default)
			)
			(layer "F.SilkS")
		)
		(fp_rect
			(start -0.508 0.9398)
			(end 0.508 -0.9398)
			(stroke
				(width 0)
				(type default)
			)
			(fill no)
			(layer "F.CrtYd")
		)
		(fp_rect
			(start -0.508 0.9398)
			(end 0.508 -0.9398)
			(stroke
				(width 0)
				(type default)
			)
			(fill no)
			(layer "F.Fab")
		)
		(pad "1" smd custom
			(at 0 -0.4445 180)
			(size 0.1397 0.1397)
			(layers "F.Cu" "F.Mask" "F.Paste")
			(net "GND")
			(options
				(clearance outline)
				(anchor circle)
			)
			(primitives
				(gr_poly
					(pts
						(arc
							(start -0.1778 -0.2794)
							(mid -0.249642 -0.249642)
							(end -0.2794 -0.1778)
						)
						(arc
							(start -0.2794 0.1778)
							(mid -0.249642 0.249642)
							(end -0.1778 0.2794)
						)
						(arc
							(start 0.1778 0.2794)
							(mid 0.249642 0.249642)
							(end 0.2794 0.1778)
						)
						(arc
							(start 0.2794 -0.1778)
							(mid 0.249642 -0.249642)
							(end 0.1778 -0.2794)
						)
					)
					(width 0)
					(fill yes)
				)
			)
		)
		(pad "2" smd custom
			(at 0 0.4445 180)
			(size 0.1397 0.1397)
			(layers "F.Cu" "F.Mask" "F.Paste")
			(net "ADM1276_LATCH#")
			(options
				(clearance outline)
				(anchor circle)
			)
			(primitives
				(gr_poly
					(pts
						(arc
							(start -0.1778 -0.2794)
							(mid -0.249642 -0.249642)
							(end -0.2794 -0.1778)
						)
						(arc
							(start -0.2794 0.1778)
							(mid -0.249642 0.249642)
							(end -0.1778 0.2794)
						)
						(arc
							(start 0.1778 0.2794)
							(mid 0.249642 0.249642)
							(end 0.2794 0.1778)
						)
						(arc
							(start 0.2794 -0.1778)
							(mid 0.249642 -0.249642)
							(end 0.1778 -0.2794)
						)
					)
					(width 0)
					(fill yes)
				)
			)
		)
	)
	(footprint ""
		(layer "F.Cu")
		(at 24.2824 -361.188 180)
		(property "Reference" "PR11"
			(at 0 0 180)
			(layer "F.SilkS")
			(hide yes)
			(effects
				(font
					(size 1.27 1.27)
				)
			)
		)
		(property "Value" "150KR2F-L-GP"
			(at 0.064008 -3.993896 180)
			(unlocked yes)
			(layer "F.Fab")
			(hide yes)
			(effects
				(font
					(size 1.016 1.016)
					(thickness 0.1524)
				)
			)
		)
		(property "Device Type" "R402H16"
			(at 0.064008 -5.517896 180)
			(unlocked yes)
			(layer "F.Fab")
			(hide yes)
			(effects
				(font
					(size 1.016 1.016)
					(thickness 0.1524)
				)
			)
		)
		(duplicate_pad_numbers_are_jumpers no)
		(fp_line
			(start 0.508 -0.9398)
			(end -0.508 -0.9398)
			(stroke
				(width 0.1524)
				(type default)
			)
			(layer "F.SilkS")
		)
		(fp_line
			(start -0.508 -0.9398)
			(end -0.508 0.9398)
			(stroke
				(width 0.1524)
				(type default)
			)
			(layer "F.SilkS")
		)
		(fp_rect
			(start -0.508 0.9398)
			(end 0.508 -0.9398)
			(stroke
				(width 0)
				(type default)
			)
			(fill no)
			(layer "F.CrtYd")
		)
		(fp_rect
			(start -0.508 0.9398)
			(end 0.508 -0.9398)
			(stroke
				(width 0)
				(type default)
			)
			(fill no)
			(layer "F.Fab")
		)
		(pad "1" smd custom
			(at 0 -0.4445 180)
			(size 0.1397 0.1397)
			(layers "F.Cu" "F.Mask" "F.Paste")
			(net "ADM1276_ADR")
			(options
				(clearance outline)
				(anchor circle)
			)
			(primitives
				(gr_poly
					(pts
						(arc
							(start -0.1778 -0.2794)
							(mid -0.249642 -0.249642)
							(end -0.2794 -0.1778)
						)
						(arc
							(start -0.2794 0.1778)
							(mid -0.249642 0.249642)
							(end -0.1778 0.2794)
						)
						(arc
							(start 0.1778 0.2794)
							(mid 0.249642 0.249642)
							(end 0.2794 0.1778)
						)
						(arc
							(start 0.2794 -0.1778)
							(mid 0.249642 -0.249642)
							(end 0.1778 -0.2794)
						)
					)
					(width 0)
					(fill yes)
				)
			)
		)
		(pad "2" smd custom
			(at 0 0.4445 180)
			(size 0.1397 0.1397)
			(layers "F.Cu" "F.Mask" "F.Paste")
			(net "GND")
			(options
				(clearance outline)
				(anchor circle)
			)
			(primitives
				(gr_poly
					(pts
						(arc
							(start -0.1778 -0.2794)
							(mid -0.249642 -0.249642)
							(end -0.2794 -0.1778)
						)
						(arc
							(start -0.2794 0.1778)
							(mid -0.249642 0.249642)
							(end -0.1778 0.2794)
						)
						(arc
							(start 0.1778 0.2794)
							(mid 0.249642 0.249642)
							(end 0.2794 0.1778)
						)
						(arc
							(start 0.2794 -0.1778)
							(mid 0.249642 -0.249642)
							(end 0.1778 -0.2794)
						)
					)
					(width 0)
					(fill yes)
				)
			)
		)
	)
	(footprint ""
		(layer "F.Cu")
		(at 44.704 -122.428)
		(property "Reference" "PR62"
			(at 0 0 0)
			(layer "F.SilkS")
			(hide yes)
			(effects
				(font
					(size 1.27 1.27)
				)
			)
		)
		(property "Value" "D002R2512F-GP"
			(at -3.228594 -1.194054 0)
			(unlocked yes)
			(layer "F.Fab")
			(hide yes)
			(effects
				(font
					(size 1.016 1.016)
					(thickness 0.1524)
				)
			)
		)
		(property "Device Type" "R2512-2H32"
			(at -3.228594 -2.718054 0)
			(unlocked yes)
			(layer "F.Fab")
			(hide yes)
			(effects
				(font
					(size 1.016 1.016)
					(thickness 0.1524)
				)
			)
		)
		(duplicate_pad_numbers_are_jumpers no)
		(fp_line
			(start -1.9685 -3.81)
			(end 1.9685 -3.81)
			(stroke
				(width 0.1524)
				(type default)
			)
			(layer "F.SilkS")
		)
		(fp_line
			(start -1.9685 3.81)
			(end -1.9685 -3.81)
			(stroke
				(width 0.1524)
				(type default)
			)
			(layer "F.SilkS")
		)
		(fp_line
			(start 1.9685 -3.81)
			(end 1.9685 3.81)
			(stroke
				(width 0.1524)
				(type default)
			)
			(layer "F.SilkS")
		)
		(fp_line
			(start 1.9685 3.81)
			(end -1.9685 3.81)
			(stroke
				(width 0.1524)
				(type default)
			)
			(layer "F.SilkS")
		)
		(fp_rect
			(start -1.5875 3.175)
			(end 1.5875 -3.175)
			(stroke
				(width 0)
				(type default)
			)
			(fill no)
			(layer "F.CrtYd")
		)
		(fp_poly
			(pts
				(xy -2.2225 3.8862) (xy -2.2225 0.00254) (xy -1.5875 0.00254) (xy -1.5875 3.175) (xy 1.5875 3.175)
				(xy 1.5875 -3.175) (xy -1.5875 -3.175) (xy -1.5875 -0.00254) (xy -2.2225 -0.00254) (xy -2.2225 -3.8862)
				(xy 2.2225 -3.8862) (xy 2.2225 3.8862)
			)
			(stroke
				(width 0)
				(type default)
			)
			(fill no)
			(layer "F.CrtYd")
		)
		(fp_rect
			(start -2.2225 3.8862)
			(end 2.2225 -3.8862)
			(stroke
				(width 0)
				(type default)
			)
			(fill no)
			(layer "F.Fab")
		)
		(pad "1" smd rect
			(at 0 -2.273808)
			(size 3.429 2.5654)
			(layers "F.Cu" "F.Mask" "F.Paste")
			(net "P12V")
		)
		(pad "2" smd rect
			(at 0 2.273808)
			(size 3.429 2.5654)
			(layers "F.Cu" "F.Mask" "F.Paste")
			(net "P12VL_NET")
		)
	)
	(footprint ""
		(layer "F.Cu")
		(at 23.622 -366.4712 -90)
		(property "Reference" "C58"
			(at 0 0 270)
			(layer "F.SilkS")
			(hide yes)
			(effects
				(font
					(size 1.27 1.27)
				)
			)
		)
		(property "Value" "SCD1U25V2KX-GP"
			(at 1.1811 -2.7051 270)
			(unlocked yes)
			(layer "F.Fab")
			(hide yes)
			(effects
				(font
					(size 1.016 1.016)
					(thickness 0.1524)
				)
			)
		)
		(property "Device Type" "C402H22"
			(at 1.1811 -4.2291 270)
			(unlocked yes)
			(layer "F.Fab")
			(hide yes)
			(effects
				(font
					(size 1.016 1.016)
					(thickness 0.1524)
				)
			)
		)
		(duplicate_pad_numbers_are_jumpers no)
		(fp_rect
			(start -0.4318 0.9525)
			(end 0.4318 -0.9525)
			(stroke
				(width 0)
				(type default)
			)
			(fill no)
			(layer "F.CrtYd")
		)
		(fp_rect
			(start -0.4318 0.9525)
			(end 0.4318 -0.9525)
			(stroke
				(width 0)
				(type default)
			)
			(fill no)
			(layer "F.Fab")
		)
		(pad "1" smd custom
			(at 0 -0.4445 270)
			(size 0.1524 0.1524)
			(layers "F.Cu" "F.Mask" "F.Paste")
			(net "ADM1276_ISET")
			(options
				(clearance outline)
				(anchor circle)
			)
			(primitives
				(gr_poly
					(pts
						(arc
							(start 0.3048 -0.2032)
							(mid 0.275042 -0.275042)
							(end 0.2032 -0.3048)
						)
						(arc
							(start -0.2032 -0.3048)
							(mid -0.275042 -0.275042)
							(end -0.3048 -0.2032)
						)
						(arc
							(start -0.3048 0.2032)
							(mid -0.275042 0.275042)
							(end -0.2032 0.3048)
						)
						(arc
							(start 0.2032 0.3048)
							(mid 0.275042 0.275042)
							(end 0.3048 0.2032)
						)
					)
					(width 0)
					(fill yes)
				)
			)
		)
		(pad "2" smd custom
			(at 0 0.4445 270)
			(size 0.1524 0.1524)
			(layers "F.Cu" "F.Mask" "F.Paste")
			(net "GND")
			(options
				(clearance outline)
				(anchor circle)
			)
			(primitives
				(gr_poly
					(pts
						(arc
							(start 0.3048 -0.2032)
							(mid 0.275042 -0.275042)
							(end 0.2032 -0.3048)
						)
						(arc
							(start -0.2032 -0.3048)
							(mid -0.275042 -0.275042)
							(end -0.3048 -0.2032)
						)
						(arc
							(start -0.3048 0.2032)
							(mid -0.275042 0.275042)
							(end -0.2032 0.3048)
						)
						(arc
							(start 0.2032 0.3048)
							(mid 0.275042 0.275042)
							(end 0.3048 0.2032)
						)
					)
					(width 0)
					(fill yes)
				)
			)
		)
	)
	(footprint ""
		(layer "F.Cu")
		(at 23.241 -361.188)
		(property "Reference" "PR5"
			(at 0 0 0)
			(layer "F.SilkS")
			(hide yes)
			(effects
				(font
					(size 1.27 1.27)
				)
			)
		)
		(property "Value" "0R2J-2-GP"
			(at 0.064008 -3.993896 0)
			(unlocked yes)
			(layer "F.Fab")
			(hide yes)
			(effects
				(font
					(size 1.016 1.016)
					(thickness 0.1524)
				)
			)
		)
		(property "Device Type" "R402H16"
			(at 0.064008 -5.517896 0)
			(unlocked yes)
			(layer "F.Fab")
			(hide yes)
			(effects
				(font
					(size 1.016 1.016)
					(thickness 0.1524)
				)
			)
		)
		(duplicate_pad_numbers_are_jumpers no)
		(fp_line
			(start -0.508 -0.9398)
			(end -0.508 0.9398)
			(stroke
				(width 0.1524)
				(type default)
			)
			(layer "F.SilkS")
		)
		(fp_line
			(start 0.508 -0.9398)
			(end -0.508 -0.9398)
			(stroke
				(width 0.1524)
				(type default)
			)
			(layer "F.SilkS")
		)
		(fp_rect
			(start -0.508 0.9398)
			(end 0.508 -0.9398)
			(stroke
				(width 0)
				(type default)
			)
			(fill no)
			(layer "F.CrtYd")
		)
		(fp_rect
			(start -0.508 0.9398)
			(end 0.508 -0.9398)
			(stroke
				(width 0)
				(type default)
			)
			(fill no)
			(layer "F.Fab")
		)
		(pad "1" smd custom
			(at 0 -0.4445)
			(size 0.1397 0.1397)
			(layers "F.Cu" "F.Mask" "F.Paste")
			(net "ADM1276_VCAP")
			(options
				(clearance outline)
				(anchor circle)
			)
			(primitives
				(gr_poly
					(pts
						(arc
							(start -0.1778 -0.2794)
							(mid -0.249642 -0.249642)
							(end -0.2794 -0.1778)
						)
						(arc
							(start -0.2794 0.1778)
							(mid -0.249642 0.249642)
							(end -0.1778 0.2794)
						)
						(arc
							(start 0.1778 0.2794)
							(mid 0.249642 0.249642)
							(end 0.2794 0.1778)
						)
						(arc
							(start 0.2794 -0.1778)
							(mid 0.249642 -0.249642)
							(end 0.1778 -0.2794)
						)
					)
					(width 0)
					(fill yes)
				)
			)
		)
		(pad "2" smd custom
			(at 0 0.4445)
			(size 0.1397 0.1397)
			(layers "F.Cu" "F.Mask" "F.Paste")
			(net "ADM1276_ADR")
			(options
				(clearance outline)
				(anchor circle)
			)
			(primitives
				(gr_poly
					(pts
						(arc
							(start -0.1778 -0.2794)
							(mid -0.249642 -0.249642)
							(end -0.2794 -0.1778)
						)
						(arc
							(start -0.2794 0.1778)
							(mid -0.249642 0.249642)
							(end -0.1778 0.2794)
						)
						(arc
							(start 0.1778 0.2794)
							(mid 0.249642 0.249642)
							(end 0.2794 0.1778)
						)
						(arc
							(start 0.2794 -0.1778)
							(mid 0.249642 -0.249642)
							(end 0.1778 -0.2794)
						)
					)
					(width 0)
					(fill yes)
				)
			)
		)
	)
	(footprint ""
		(layer "F.Cu")
		(at 21.766784 -214.4014 90)
		(property "Reference" "R130"
			(at 0 0 90)
			(layer "F.SilkS")
			(hide yes)
			(effects
				(font
					(size 1.27 1.27)
				)
			)
		)
		(property "Value" "4K7R2F-GP"
			(at 0.064008 -3.993896 90)
			(unlocked yes)
			(layer "F.Fab")
			(hide yes)
			(effects
				(font
					(size 1.016 1.016)
					(thickness 0.1524)
				)
			)
		)
		(property "Device Type" "R402H16"
			(at 0.064008 -5.517896 90)
			(unlocked yes)
			(layer "F.Fab")
			(hide yes)
			(effects
				(font
					(size 1.016 1.016)
					(thickness 0.1524)
				)
			)
		)
		(duplicate_pad_numbers_are_jumpers no)
		(fp_line
			(start 0.508 -0.9398)
			(end -0.508 -0.9398)
			(stroke
				(width 0.1524)
				(type default)
			)
			(layer "F.SilkS")
		)
		(fp_line
			(start -0.508 -0.9398)
			(end -0.508 0.9398)
			(stroke
				(width 0.1524)
				(type default)
			)
			(layer "F.SilkS")
		)
		(fp_rect
			(start -0.508 0.9398)
			(end 0.508 -0.9398)
			(stroke
				(width 0)
				(type default)
			)
			(fill no)
			(layer "F.CrtYd")
		)
		(fp_rect
			(start -0.508 0.9398)
			(end 0.508 -0.9398)
			(stroke
				(width 0)
				(type default)
			)
			(fill no)
			(layer "F.Fab")
		)
		(pad "1" smd custom
			(at 0 -0.4445 90)
			(size 0.1397 0.1397)
			(layers "F.Cu" "F.Mask" "F.Paste")
			(net "P3V3")
			(options
				(clearance outline)
				(anchor circle)
			)
			(primitives
				(gr_poly
					(pts
						(arc
							(start -0.1778 -0.2794)
							(mid -0.249642 -0.249642)
							(end -0.2794 -0.1778)
						)
						(arc
							(start -0.2794 0.1778)
							(mid -0.249642 0.249642)
							(end -0.1778 0.2794)
						)
						(arc
							(start 0.1778 0.2794)
							(mid 0.249642 0.249642)
							(end 0.2794 0.1778)
						)
						(arc
							(start 0.2794 -0.1778)
							(mid 0.249642 -0.249642)
							(end 0.1778 -0.2794)
						)
					)
					(width 0)
					(fill yes)
				)
			)
		)
		(pad "2" smd custom
			(at 0 0.4445 90)
			(size 0.1397 0.1397)
			(layers "F.Cu" "F.Mask" "F.Paste")
			(net "PWM_OUT_FAN6")
			(options
				(clearance outline)
				(anchor circle)
			)
			(primitives
				(gr_poly
					(pts
						(arc
							(start -0.1778 -0.2794)
							(mid -0.249642 -0.249642)
							(end -0.2794 -0.1778)
						)
						(arc
							(start -0.2794 0.1778)
							(mid -0.249642 0.249642)
							(end -0.1778 0.2794)
						)
						(arc
							(start 0.1778 0.2794)
							(mid 0.249642 0.249642)
							(end 0.2794 0.1778)
						)
						(arc
							(start 0.2794 -0.1778)
							(mid 0.249642 -0.249642)
							(end 0.1778 -0.2794)
						)
					)
					(width 0)
					(fill yes)
				)
			)
		)
	)
	(footprint ""
		(layer "F.Cu")
		(at 43.7896 -136.2456 90)
		(property "Reference" "PC90"
			(at 0 0 90)
			(layer "F.SilkS")
			(hide yes)
			(effects
				(font
					(size 1.27 1.27)
				)
			)
		)
		(property "Value" "SCD1U25V2KX-GP"
			(at 1.1811 -2.7051 90)
			(unlocked yes)
			(layer "F.Fab")
			(hide yes)
			(effects
				(font
					(size 1.016 1.016)
					(thickness 0.1524)
				)
			)
		)
		(property "Device Type" "C402H22"
			(at 1.1811 -4.2291 90)
			(unlocked yes)
			(layer "F.Fab")
			(hide yes)
			(effects
				(font
					(size 1.016 1.016)
					(thickness 0.1524)
				)
			)
		)
		(duplicate_pad_numbers_are_jumpers no)
		(fp_rect
			(start -0.4318 0.9525)
			(end 0.4318 -0.9525)
			(stroke
				(width 0)
				(type default)
			)
			(fill no)
			(layer "F.CrtYd")
		)
		(fp_rect
			(start -0.4318 0.9525)
			(end 0.4318 -0.9525)
			(stroke
				(width 0)
				(type default)
			)
			(fill no)
			(layer "F.Fab")
		)
		(pad "1" smd custom
			(at 0 -0.4445 90)
			(size 0.1524 0.1524)
			(layers "F.Cu" "F.Mask" "F.Paste")
			(net "P12VL_2490_VCC")
			(options
				(clearance outline)
				(anchor circle)
			)
			(primitives
				(gr_poly
					(pts
						(arc
							(start 0.3048 -0.2032)
							(mid 0.275042 -0.275042)
							(end 0.2032 -0.3048)
						)
						(arc
							(start -0.2032 -0.3048)
							(mid -0.275042 -0.275042)
							(end -0.3048 -0.2032)
						)
						(arc
							(start -0.3048 0.2032)
							(mid -0.275042 0.275042)
							(end -0.2032 0.3048)
						)
						(arc
							(start 0.2032 0.3048)
							(mid 0.275042 0.275042)
							(end 0.3048 0.2032)
						)
					)
					(width 0)
					(fill yes)
				)
			)
		)
		(pad "2" smd custom
			(at 0 0.4445 90)
			(size 0.1524 0.1524)
			(layers "F.Cu" "F.Mask" "F.Paste")
			(net "GND")
			(options
				(clearance outline)
				(anchor circle)
			)
			(primitives
				(gr_poly
					(pts
						(arc
							(start 0.3048 -0.2032)
							(mid 0.275042 -0.275042)
							(end 0.2032 -0.3048)
						)
						(arc
							(start -0.2032 -0.3048)
							(mid -0.275042 -0.275042)
							(end -0.3048 -0.2032)
						)
						(arc
							(start -0.3048 0.2032)
							(mid -0.275042 0.275042)
							(end -0.2032 0.3048)
						)
						(arc
							(start 0.2032 0.3048)
							(mid 0.275042 0.275042)
							(end 0.3048 0.2032)
						)
					)
					(width 0)
					(fill yes)
				)
			)
		)
	)
	(footprint ""
		(layer "F.Cu")
		(at 25.654 -400.177)
		(property "Reference" "PQ1"
			(at 0 0 0)
			(layer "F.SilkS")
			(hide yes)
			(effects
				(font
					(size 1.27 1.27)
				)
			)
		)
		(property "Value" "PH0925CL-GP"
			(at -4.2799 -0.4572 0)
			(unlocked yes)
			(layer "F.Fab")
			(hide yes)
			(effects
				(font
					(size 1.016 1.016)
					(thickness 0.1524)
				)
			)
		)
		(property "Device Type" "LFPAK-5PH48-U"
			(at -4.2799 -1.9812 0)
			(unlocked yes)
			(layer "F.Fab")
			(hide yes)
			(effects
				(font
					(size 1.016 1.016)
					(thickness 0.1524)
				)
			)
		)
		(duplicate_pad_numbers_are_jumpers no)
		(fp_line
			(start -2.7559 -6.5532)
			(end -2.7559 1.0668)
			(stroke
				(width 0.1524)
				(type default)
			)
			(layer "F.SilkS")
		)
		(fp_line
			(start -2.7559 1.0668)
			(end 2.7559 1.0668)
			(stroke
				(width 0.1524)
				(type default)
			)
			(layer "F.SilkS")
		)
		(fp_line
			(start -1.7272 1.1684)
			(end -2.1082 1.1684)
			(stroke
				(width 0.3302)
				(type default)
			)
			(layer "F.SilkS")
		)
		(fp_line
			(start 2.7559 -6.5532)
			(end -2.7559 -6.5532)
			(stroke
				(width 0.1524)
				(type default)
			)
			(layer "F.SilkS")
		)
		(fp_line
			(start 2.7559 1.0668)
			(end 2.7559 -6.5532)
			(stroke
				(width 0.1524)
				(type default)
			)
			(layer "F.SilkS")
		)
		(fp_poly
			(pts
				(xy -2.3368 1.5748) (xy -1.905 1.143) (xy -1.4732 1.5748)
			)
			(stroke
				(width 0)
				(type default)
			)
			(fill yes)
			(layer "F.SilkS")
		)
		(fp_poly
			(pts
				(xy -2.5019 -4.02971) (xy -0.3302 -4.02971) (xy -0.3302 -6.30301) (xy -2.5019 -6.30301)
			)
			(stroke
				(width 0)
				(type default)
			)
			(fill yes)
			(layer "F.Paste")
		)
		(fp_poly
			(pts
				(xy -2.5019 -1.09601) (xy -0.3302 -1.09601) (xy -0.3302 -3.36931) (xy -2.5019 -3.36931)
			)
			(stroke
				(width 0)
				(type default)
			)
			(fill yes)
			(layer "F.Paste")
		)
		(fp_poly
			(pts
				(xy 0.3302 -4.02971) (xy 2.5019 -4.02971) (xy 2.5019 -6.30301) (xy 0.3302 -6.30301)
			)
			(stroke
				(width 0)
				(type default)
			)
			(fill yes)
			(layer "F.Paste")
		)
		(fp_poly
			(pts
				(xy 0.3302 -1.09601) (xy 2.5019 -1.09601) (xy 2.5019 -3.36931) (xy 0.3302 -3.36931)
			)
			(stroke
				(width 0)
				(type default)
			)
			(fill yes)
			(layer "F.Paste")
		)
		(fp_rect
			(start -2.4511 0.3048)
			(end 2.4511 -5.6896)
			(stroke
				(width 0)
				(type default)
			)
			(fill no)
			(layer "F.CrtYd")
		)
		(fp_poly
			(pts
				(xy -3.0099 1.3208) (xy -3.0099 -6.8072) (xy 3.0099 -6.8072) (xy 3.0099 -1.016) (xy 2.4511 -1.016)
				(xy 2.4511 -5.6896) (xy -2.4511 -5.6896) (xy -2.4511 0.3048) (xy 2.4511 0.3048) (xy 2.4511 -1.0033)
				(xy 3.0099 -1.0033) (xy 3.0099 1.3208)
			)
			(stroke
				(width 0)
				(type default)
			)
			(fill no)
			(layer "F.CrtYd")
		)
		(fp_rect
			(start -3.0099 1.3208)
			(end 3.0099 -6.8072)
			(stroke
				(width 0)
				(type default)
			)
			(fill no)
			(layer "F.Fab")
		)
		(pad "1" smd rect
			(at -1.905 0)
			(size 0.762 1.6256)
			(layers "F.Cu" "F.Mask" "F.Paste")
			(net "P12V")
		)
		(pad "2" smd rect
			(at -0.635 0)
			(size 0.762 1.6256)
			(layers "F.Cu" "F.Mask" "F.Paste")
			(net "P12V")
		)
		(pad "3" smd rect
			(at 0.635 0)
			(size 0.762 1.6256)
			(layers "F.Cu" "F.Mask" "F.Paste")
			(net "P12V")
		)
		(pad "4" smd rect
			(at 1.905 0)
			(size 0.762 1.6256)
			(layers "F.Cu" "F.Mask" "F.Paste")
			(net "ADM1276_GATE_DRV1")
		)
		(pad "5" smd rect
			(at 0 -3.69951)
			(size 5.0038 5.207)
			(layers "F.Cu" "F.Mask" "F.Paste")
			(net "P12V_SENSE_TRACE")
		)
	)
	(footprint ""
		(layer "F.Cu")
		(at 45.500036 -19.99996)
		(property "Reference" "H1"
			(at 0 0 0)
			(layer "F.SilkS")
			(hide yes)
			(effects
				(font
					(size 1.27 1.27)
				)
			)
		)
		(property "Value" "HOLE315R138"
			(at 0 -7.0612 0)
			(unlocked yes)
			(layer "F.Fab")
			(hide yes)
			(effects
				(font
					(size 1.016 1.016)
					(thickness 0.1524)
				)
			)
		)
		(property "Device Type" "HOLE315R138"
			(at 0 -8.5852 0)
			(unlocked yes)
			(layer "F.Fab")
			(hide yes)
			(effects
				(font
					(size 1.016 1.016)
					(thickness 0.1524)
				)
			)
		)
		(duplicate_pad_numbers_are_jumpers no)
		(fp_poly
			(pts
				(xy 0 4.3053) (xy -0.13462 4.30276) (xy -0.27051 4.29641) (xy -0.40513 4.28625) (xy -0.53975 4.27101)
				(xy -0.6731 4.25196) (xy -0.80645 4.2291) (xy -0.9398 4.20116) (xy -1.07061 4.17068) (xy -1.20142 4.13385)
				(xy -1.33096 4.09448) (xy -1.45796 4.0513) (xy -1.58496 4.00304) (xy -1.70942 3.95097) (xy -1.83261 3.89509)
				(xy -1.95453 3.83667) (xy -2.07391 3.77317) (xy -2.19202 3.70586) (xy -2.30632 3.63474) (xy -2.41935 3.56108)
				(xy -2.53111 3.48361) (xy -2.63906 3.40233) (xy -2.74447 3.31724) (xy -2.84734 3.22961) (xy -2.94767 3.13817)
				(xy -3.04419 3.04419) (xy -3.13817 2.94767) (xy -3.22961 2.84734) (xy -3.31724 2.74447) (xy -3.40233 2.63906)
				(xy -3.48361 2.53111) (xy -3.56108 2.41935) (xy -3.63474 2.30632) (xy -3.70586 2.19202) (xy -3.77317 2.07391)
				(xy -3.83667 1.95453) (xy -3.89509 1.83261) (xy -3.95097 1.70942) (xy -4.00304 1.58496) (xy -4.0513 1.45796)
				(xy -4.09448 1.33096) (xy -4.13385 1.20142) (xy -4.17068 1.07061) (xy -4.20116 0.9398) (xy -4.2291 0.80645)
				(xy -4.25196 0.6731) (xy -4.27101 0.53975) (xy -4.28625 0.40513) (xy -4.29641 0.27051) (xy -4.30276 0.13462)
				(xy -4.3053 0) (xy -4.30276 -0.13462) (xy -4.29641 -0.27051) (xy -4.28625 -0.40513) (xy -4.27101 -0.53975)
				(xy -4.25196 -0.6731) (xy -4.2291 -0.80645) (xy -4.20116 -0.9398) (xy -4.17068 -1.07061) (xy -4.13385 -1.20142)
				(xy -4.09448 -1.33096) (xy -4.0513 -1.45796) (xy -4.00304 -1.58496) (xy -3.95097 -1.70942) (xy -3.89509 -1.83261)
				(xy -3.83667 -1.95453) (xy -3.77317 -2.07391) (xy -3.70586 -2.19202) (xy -3.63474 -2.30632) (xy -3.56108 -2.41935)
				(xy -3.48361 -2.53111) (xy -3.40233 -2.63906) (xy -3.31724 -2.74447) (xy -3.22961 -2.84734) (xy -3.13817 -2.94767)
				(xy -3.04419 -3.04419) (xy -2.94767 -3.13817) (xy -2.84734 -3.22961) (xy -2.74447 -3.31724) (xy -2.63906 -3.40233)
				(xy -2.53111 -3.48361) (xy -2.41935 -3.56108) (xy -2.30632 -3.63474) (xy -2.19202 -3.70586) (xy -2.07391 -3.77317)
				(xy -1.95453 -3.83667) (xy -1.83261 -3.89509) (xy -1.70942 -3.95097) (xy -1.58496 -4.00304) (xy -1.45796 -4.0513)
				(xy -1.33096 -4.09448) (xy -1.20142 -4.13385) (xy -1.07061 -4.17068) (xy -0.9398 -4.20116) (xy -0.80645 -4.2291)
				(xy -0.6731 -4.25196) (xy -0.53975 -4.27101) (xy -0.40513 -4.28625) (xy -0.27051 -4.29641) (xy -0.13462 -4.30276)
				(xy 0 -4.3053) (xy 0.13462 -4.30276) (xy 0.27051 -4.29641) (xy 0.40513 -4.28625) (xy 0.53975 -4.27101)
				(xy 0.6731 -4.25196) (xy 0.80645 -4.2291) (xy 0.9398 -4.20116) (xy 1.07061 -4.17068) (xy 1.20142 -4.13385)
				(xy 1.33096 -4.09448) (xy 1.45796 -4.0513) (xy 1.58496 -4.00304) (xy 1.70942 -3.95097) (xy 1.83261 -3.89509)
				(xy 1.95453 -3.83667) (xy 2.07391 -3.77317) (xy 2.19202 -3.70586) (xy 2.30632 -3.63474) (xy 2.41935 -3.56108)
				(xy 2.53111 -3.48361) (xy 2.63906 -3.40233) (xy 2.74447 -3.31724) (xy 2.84734 -3.22961) (xy 2.94767 -3.13817)
				(xy 3.04419 -3.04419) (xy 3.13817 -2.94767) (xy 3.22961 -2.84734) (xy 3.31724 -2.74447) (xy 3.40233 -2.63906)
				(xy 3.48361 -2.53111) (xy 3.56108 -2.41935) (xy 3.63474 -2.30632) (xy 3.70586 -2.19202) (xy 3.77317 -2.07391)
				(xy 3.83667 -1.95453) (xy 3.89509 -1.83261) (xy 3.95097 -1.70942) (xy 4.00304 -1.58496) (xy 4.0513 -1.45796)
				(xy 4.09448 -1.33096) (xy 4.13385 -1.20142) (xy 4.17068 -1.07061) (xy 4.20116 -0.9398) (xy 4.2291 -0.80645)
				(xy 4.25196 -0.6731) (xy 4.27101 -0.53975) (xy 4.28625 -0.40513) (xy 4.29641 -0.27051) (xy 4.30276 -0.13462)
				(xy 4.3053 0) (xy 4.30276 0.13462) (xy 4.29641 0.27051) (xy 4.28625 0.40513) (xy 4.27101 0.53975)
				(xy 4.25196 0.6731) (xy 4.2291 0.80645) (xy 4.20116 0.9398) (xy 4.17068 1.07061) (xy 4.13385 1.20142)
				(xy 4.09448 1.33096) (xy 4.0513 1.45796) (xy 4.00304 1.58496) (xy 3.95097 1.70942) (xy 3.89509 1.83261)
				(xy 3.83667 1.95453) (xy 3.77317 2.07391) (xy 3.70586 2.19202) (xy 3.63474 2.30632) (xy 3.56108 2.41935)
				(xy 3.48361 2.53111) (xy 3.40233 2.63906) (xy 3.31724 2.74447) (xy 3.22961 2.84734) (xy 3.13817 2.94767)
				(xy 3.04419 3.04419) (xy 2.94767 3.13817) (xy 2.84734 3.22961) (xy 2.74447 3.31724) (xy 2.63906 3.40233)
				(xy 2.53111 3.48361) (xy 2.41935 3.56108) (xy 2.30632 3.63474) (xy 2.19202 3.70586) (xy 2.07391 3.77317)
				(xy 1.95453 3.83667) (xy 1.83261 3.89509) (xy 1.70942 3.95097) (xy 1.58496 4.00304) (xy 1.45796 4.0513)
				(xy 1.33096 4.09448) (xy 1.20142 4.13385) (xy 1.07061 4.17068) (xy 0.9398 4.20116) (xy 0.80645 4.2291)
				(xy 0.6731 4.25196) (xy 0.53975 4.27101) (xy 0.40513 4.28625) (xy 0.27051 4.29641) (xy 0.13462 4.30276)
			)
			(stroke
				(width 0)
				(type default)
			)
			(fill no)
			(layer "F.CrtYd")
		)
		(fp_poly
			(pts
				(xy 0 4.3053) (xy -0.13462 4.30276) (xy -0.27051 4.29641) (xy -0.40513 4.28625) (xy -0.53975 4.27101)
				(xy -0.6731 4.25196) (xy -0.80645 4.2291) (xy -0.9398 4.20116) (xy -1.07061 4.17068) (xy -1.20142 4.13385)
				(xy -1.33096 4.09448) (xy -1.45796 4.0513) (xy -1.58496 4.00304) (xy -1.70942 3.95097) (xy -1.83261 3.89509)
				(xy -1.95453 3.83667) (xy -2.07391 3.77317) (xy -2.19202 3.70586) (xy -2.30632 3.63474) (xy -2.41935 3.56108)
				(xy -2.53111 3.48361) (xy -2.63906 3.40233) (xy -2.74447 3.31724) (xy -2.84734 3.22961) (xy -2.94767 3.13817)
				(xy -3.04419 3.04419) (xy -3.13817 2.94767) (xy -3.22961 2.84734) (xy -3.31724 2.74447) (xy -3.40233 2.63906)
				(xy -3.48361 2.53111) (xy -3.56108 2.41935) (xy -3.63474 2.30632) (xy -3.70586 2.19202) (xy -3.77317 2.07391)
				(xy -3.83667 1.95453) (xy -3.89509 1.83261) (xy -3.95097 1.70942) (xy -4.00304 1.58496) (xy -4.0513 1.45796)
				(xy -4.09448 1.33096) (xy -4.13385 1.20142) (xy -4.17068 1.07061) (xy -4.20116 0.9398) (xy -4.2291 0.80645)
				(xy -4.25196 0.6731) (xy -4.27101 0.53975) (xy -4.28625 0.40513) (xy -4.29641 0.27051) (xy -4.30276 0.13462)
				(xy -4.3053 0) (xy -4.30276 -0.13462) (xy -4.29641 -0.27051) (xy -4.28625 -0.40513) (xy -4.27101 -0.53975)
				(xy -4.25196 -0.6731) (xy -4.2291 -0.80645) (xy -4.20116 -0.9398) (xy -4.17068 -1.07061) (xy -4.13385 -1.20142)
				(xy -4.09448 -1.33096) (xy -4.0513 -1.45796) (xy -4.00304 -1.58496) (xy -3.95097 -1.70942) (xy -3.89509 -1.83261)
				(xy -3.83667 -1.95453) (xy -3.77317 -2.07391) (xy -3.70586 -2.19202) (xy -3.63474 -2.30632) (xy -3.56108 -2.41935)
				(xy -3.48361 -2.53111) (xy -3.40233 -2.63906) (xy -3.31724 -2.74447) (xy -3.22961 -2.84734) (xy -3.13817 -2.94767)
				(xy -3.04419 -3.04419) (xy -2.94767 -3.13817) (xy -2.84734 -3.22961) (xy -2.74447 -3.31724) (xy -2.63906 -3.40233)
				(xy -2.53111 -3.48361) (xy -2.41935 -3.56108) (xy -2.30632 -3.63474) (xy -2.19202 -3.70586) (xy -2.07391 -3.77317)
				(xy -1.95453 -3.83667) (xy -1.83261 -3.89509) (xy -1.70942 -3.95097) (xy -1.58496 -4.00304) (xy -1.45796 -4.0513)
				(xy -1.33096 -4.09448) (xy -1.20142 -4.13385) (xy -1.07061 -4.17068) (xy -0.9398 -4.20116) (xy -0.80645 -4.2291)
				(xy -0.6731 -4.25196) (xy -0.53975 -4.27101) (xy -0.40513 -4.28625) (xy -0.27051 -4.29641) (xy -0.13462 -4.30276)
				(xy 0 -4.3053) (xy 0.13462 -4.30276) (xy 0.27051 -4.29641) (xy 0.40513 -4.28625) (xy 0.53975 -4.27101)
				(xy 0.6731 -4.25196) (xy 0.80645 -4.2291) (xy 0.9398 -4.20116) (xy 1.07061 -4.17068) (xy 1.20142 -4.13385)
				(xy 1.33096 -4.09448) (xy 1.45796 -4.0513) (xy 1.58496 -4.00304) (xy 1.70942 -3.95097) (xy 1.83261 -3.89509)
				(xy 1.95453 -3.83667) (xy 2.07391 -3.77317) (xy 2.19202 -3.70586) (xy 2.30632 -3.63474) (xy 2.41935 -3.56108)
				(xy 2.53111 -3.48361) (xy 2.63906 -3.40233) (xy 2.74447 -3.31724) (xy 2.84734 -3.22961) (xy 2.94767 -3.13817)
				(xy 3.04419 -3.04419) (xy 3.13817 -2.94767) (xy 3.22961 -2.84734) (xy 3.31724 -2.74447) (xy 3.40233 -2.63906)
				(xy 3.48361 -2.53111) (xy 3.56108 -2.41935) (xy 3.63474 -2.30632) (xy 3.70586 -2.19202) (xy 3.77317 -2.07391)
				(xy 3.83667 -1.95453) (xy 3.89509 -1.83261) (xy 3.95097 -1.70942) (xy 4.00304 -1.58496) (xy 4.0513 -1.45796)
				(xy 4.09448 -1.33096) (xy 4.13385 -1.20142) (xy 4.17068 -1.07061) (xy 4.20116 -0.9398) (xy 4.2291 -0.80645)
				(xy 4.25196 -0.6731) (xy 4.27101 -0.53975) (xy 4.28625 -0.40513) (xy 4.29641 -0.27051) (xy 4.30276 -0.13462)
				(xy 4.3053 0) (xy 4.30276 0.13462) (xy 4.29641 0.27051) (xy 4.28625 0.40513) (xy 4.27101 0.53975)
				(xy 4.25196 0.6731) (xy 4.2291 0.80645) (xy 4.20116 0.9398) (xy 4.17068 1.07061) (xy 4.13385 1.20142)
				(xy 4.09448 1.33096) (xy 4.0513 1.45796) (xy 4.00304 1.58496) (xy 3.95097 1.70942) (xy 3.89509 1.83261)
				(xy 3.83667 1.95453) (xy 3.77317 2.07391) (xy 3.70586 2.19202) (xy 3.63474 2.30632) (xy 3.56108 2.41935)
				(xy 3.48361 2.53111) (xy 3.40233 2.63906) (xy 3.31724 2.74447) (xy 3.22961 2.84734) (xy 3.13817 2.94767)
				(xy 3.04419 3.04419) (xy 2.94767 3.13817) (xy 2.84734 3.22961) (xy 2.74447 3.31724) (xy 2.63906 3.40233)
				(xy 2.53111 3.48361) (xy 2.41935 3.56108) (xy 2.30632 3.63474) (xy 2.19202 3.70586) (xy 2.07391 3.77317)
				(xy 1.95453 3.83667) (xy 1.83261 3.89509) (xy 1.70942 3.95097) (xy 1.58496 4.00304) (xy 1.45796 4.0513)
				(xy 1.33096 4.09448) (xy 1.20142 4.13385) (xy 1.07061 4.17068) (xy 0.9398 4.20116) (xy 0.80645 4.2291)
				(xy 0.6731 4.25196) (xy 0.53975 4.27101) (xy 0.40513 4.28625) (xy 0.27051 4.29641) (xy 0.13462 4.30276)
			)
			(stroke
				(width 0)
				(type default)
			)
			(fill no)
			(layer "F.Fab")
		)
		(pad "1" thru_hole circle
			(at 0 0)
			(size 8.001 8.001)
			(drill 3.5052)
			(layers "*.Cu" "*.Mask")
			(remove_unused_layers no)
			(net "GND")
			(clearance -1.7399)
			(thermal_gap 0.3048)
			(padstack
				(mode front_inner_back)
				(layer "Inner"
					(shape circle)
					(size 3.9116 3.9116)
					(clearance 0.3048)
				)
				(layer "B.Cu"
					(shape circle)
					(size 8.001 8.001)
					(clearance -1.7399)
				)
			)
		)
	)
	(footprint ""
		(layer "F.Cu")
		(at 23.749 -375.285 180)
		(property "Reference" "PR37"
			(at 0 0 180)
			(layer "F.SilkS")
			(hide yes)
			(effects
				(font
					(size 1.27 1.27)
				)
			)
		)
		(property "Value" "4K99R2F-L-GP"
			(at 0.064008 -3.993896 180)
			(unlocked yes)
			(layer "F.Fab")
			(hide yes)
			(effects
				(font
					(size 1.016 1.016)
					(thickness 0.1524)
				)
			)
		)
		(property "Device Type" "R402H16"
			(at 0.064008 -5.517896 180)
			(unlocked yes)
			(layer "F.Fab")
			(hide yes)
			(effects
				(font
					(size 1.016 1.016)
					(thickness 0.1524)
				)
			)
		)
		(duplicate_pad_numbers_are_jumpers no)
		(fp_line
			(start 0.508 -0.9398)
			(end -0.508 -0.9398)
			(stroke
				(width 0.1524)
				(type default)
			)
			(layer "F.SilkS")
		)
		(fp_line
			(start -0.508 -0.9398)
			(end -0.508 0.9398)
			(stroke
				(width 0.1524)
				(type default)
			)
			(layer "F.SilkS")
		)
		(fp_rect
			(start -0.508 0.9398)
			(end 0.508 -0.9398)
			(stroke
				(width 0)
				(type default)
			)
			(fill no)
			(layer "F.CrtYd")
		)
		(fp_rect
			(start -0.508 0.9398)
			(end 0.508 -0.9398)
			(stroke
				(width 0)
				(type default)
			)
			(fill no)
			(layer "F.Fab")
		)
		(pad "1" smd custom
			(at 0 -0.4445 180)
			(size 0.1397 0.1397)
			(layers "F.Cu" "F.Mask" "F.Paste")
			(net "ADM1276_UV")
			(options
				(clearance outline)
				(anchor circle)
			)
			(primitives
				(gr_poly
					(pts
						(arc
							(start -0.1778 -0.2794)
							(mid -0.249642 -0.249642)
							(end -0.2794 -0.1778)
						)
						(arc
							(start -0.2794 0.1778)
							(mid -0.249642 0.249642)
							(end -0.1778 0.2794)
						)
						(arc
							(start 0.1778 0.2794)
							(mid 0.249642 0.249642)
							(end 0.2794 0.1778)
						)
						(arc
							(start 0.2794 -0.1778)
							(mid 0.249642 -0.249642)
							(end 0.1778 -0.2794)
						)
					)
					(width 0)
					(fill yes)
				)
			)
		)
		(pad "2" smd custom
			(at 0 0.4445 180)
			(size 0.1397 0.1397)
			(layers "F.Cu" "F.Mask" "F.Paste")
			(net "GND")
			(options
				(clearance outline)
				(anchor circle)
			)
			(primitives
				(gr_poly
					(pts
						(arc
							(start -0.1778 -0.2794)
							(mid -0.249642 -0.249642)
							(end -0.2794 -0.1778)
						)
						(arc
							(start -0.2794 0.1778)
							(mid -0.249642 0.249642)
							(end -0.1778 0.2794)
						)
						(arc
							(start 0.1778 0.2794)
							(mid 0.249642 0.249642)
							(end 0.2794 0.1778)
						)
						(arc
							(start 0.2794 -0.1778)
							(mid 0.249642 -0.249642)
							(end 0.1778 -0.2794)
						)
					)
					(width 0)
					(fill yes)
				)
			)
		)
	)
	(footprint ""
		(layer "F.Cu")
		(at 28.702 -194.0814 90)
		(property "Reference" "C41"
			(at 0 0 90)
			(layer "F.SilkS")
			(hide yes)
			(effects
				(font
					(size 1.27 1.27)
				)
			)
		)
		(property "Value" "SCD1U50V3KX-GP"
			(at 0 -2.8194 90)
			(unlocked yes)
			(layer "F.Fab")
			(hide yes)
			(effects
				(font
					(size 1.016 1.016)
					(thickness 0.1524)
				)
			)
		)
		(property "Device Type" "C603H36"
			(at 0 -4.3434 90)
			(unlocked yes)
			(layer "F.Fab")
			(hide yes)
			(effects
				(font
					(size 1.016 1.016)
					(thickness 0.1524)
				)
			)
		)
		(duplicate_pad_numbers_are_jumpers no)
		(fp_line
			(start 0.508 0)
			(end -0.508 0)
			(stroke
				(width 0.2032)
				(type default)
			)
			(layer "F.SilkS")
		)
		(fp_rect
			(start -0.5842 1.3335)
			(end 0.5842 -1.3335)
			(stroke
				(width 0)
				(type default)
			)
			(fill no)
			(layer "F.CrtYd")
		)
		(fp_rect
			(start -0.5842 1.3335)
			(end 0.5842 -1.3335)
			(stroke
				(width 0)
				(type default)
			)
			(fill no)
			(layer "F.Fab")
		)
		(pad "1" smd custom
			(at 0 -0.762 90)
			(size 0.2159 0.2159)
			(layers "F.Cu" "F.Mask" "F.Paste")
			(net "P12V")
			(options
				(clearance outline)
				(anchor circle)
			)
			(primitives
				(gr_poly
					(pts
						(arc
							(start -0.3302 -0.4318)
							(mid -0.402042 -0.402042)
							(end -0.4318 -0.3302)
						)
						(arc
							(start -0.4318 0.3302)
							(mid -0.402042 0.402042)
							(end -0.3302 0.4318)
						)
						(arc
							(start 0.3302 0.4318)
							(mid 0.402042 0.402042)
							(end 0.4318 0.3302)
						)
						(arc
							(start 0.4318 -0.3302)
							(mid 0.402042 -0.402042)
							(end 0.3302 -0.4318)
						)
					)
					(width 0)
					(fill yes)
				)
			)
		)
		(pad "2" smd custom
			(at 0 0.762 90)
			(size 0.2159 0.2159)
			(layers "F.Cu" "F.Mask" "F.Paste")
			(net "GND")
			(options
				(clearance outline)
				(anchor circle)
			)
			(primitives
				(gr_poly
					(pts
						(arc
							(start -0.3302 -0.4318)
							(mid -0.402042 -0.402042)
							(end -0.4318 -0.3302)
						)
						(arc
							(start -0.4318 0.3302)
							(mid -0.402042 0.402042)
							(end -0.3302 0.4318)
						)
						(arc
							(start 0.3302 0.4318)
							(mid 0.402042 0.402042)
							(end 0.4318 0.3302)
						)
						(arc
							(start 0.4318 -0.3302)
							(mid 0.402042 -0.402042)
							(end 0.3302 -0.4318)
						)
					)
					(width 0)
					(fill yes)
				)
			)
		)
	)
	(footprint ""
		(layer "F.Cu")
		(at 40.132 -146.5326)
		(property "Reference" "PR109"
			(at 0 0 0)
			(layer "F.SilkS")
			(hide yes)
			(effects
				(font
					(size 1.27 1.27)
				)
			)
		)
		(property "Value" "6K81R2F-1-GP"
			(at 0.064008 -3.993896 0)
			(unlocked yes)
			(layer "F.Fab")
			(hide yes)
			(effects
				(font
					(size 1.016 1.016)
					(thickness 0.1524)
				)
			)
		)
		(property "Device Type" "R402H16"
			(at 0.064008 -5.517896 0)
			(unlocked yes)
			(layer "F.Fab")
			(hide yes)
			(effects
				(font
					(size 1.016 1.016)
					(thickness 0.1524)
				)
			)
		)
		(duplicate_pad_numbers_are_jumpers no)
		(fp_line
			(start -0.508 -0.9398)
			(end -0.508 0.9398)
			(stroke
				(width 0.1524)
				(type default)
			)
			(layer "F.SilkS")
		)
		(fp_line
			(start 0.508 -0.9398)
			(end -0.508 -0.9398)
			(stroke
				(width 0.1524)
				(type default)
			)
			(layer "F.SilkS")
		)
		(fp_rect
			(start -0.508 0.9398)
			(end 0.508 -0.9398)
			(stroke
				(width 0)
				(type default)
			)
			(fill no)
			(layer "F.CrtYd")
		)
		(fp_rect
			(start -0.508 0.9398)
			(end 0.508 -0.9398)
			(stroke
				(width 0)
				(type default)
			)
			(fill no)
			(layer "F.Fab")
		)
		(pad "1" smd custom
			(at 0 -0.4445)
			(size 0.1397 0.1397)
			(layers "F.Cu" "F.Mask" "F.Paste")
			(net "P12V")
			(options
				(clearance outline)
				(anchor circle)
			)
			(primitives
				(gr_poly
					(pts
						(arc
							(start -0.1778 -0.2794)
							(mid -0.249642 -0.249642)
							(end -0.2794 -0.1778)
						)
						(arc
							(start -0.2794 0.1778)
							(mid -0.249642 0.249642)
							(end -0.1778 0.2794)
						)
						(arc
							(start 0.1778 0.2794)
							(mid 0.249642 0.249642)
							(end 0.2794 0.1778)
						)
						(arc
							(start 0.2794 -0.1778)
							(mid 0.249642 -0.249642)
							(end 0.1778 -0.2794)
						)
					)
					(width 0)
					(fill yes)
				)
			)
		)
		(pad "2" smd custom
			(at 0 0.4445)
			(size 0.1397 0.1397)
			(layers "F.Cu" "F.Mask" "F.Paste")
			(net "P12VL_2490_EN_1")
			(options
				(clearance outline)
				(anchor circle)
			)
			(primitives
				(gr_poly
					(pts
						(arc
							(start -0.1778 -0.2794)
							(mid -0.249642 -0.249642)
							(end -0.2794 -0.1778)
						)
						(arc
							(start -0.2794 0.1778)
							(mid -0.249642 0.249642)
							(end -0.1778 0.2794)
						)
						(arc
							(start 0.1778 0.2794)
							(mid 0.249642 0.249642)
							(end 0.2794 0.1778)
						)
						(arc
							(start 0.2794 -0.1778)
							(mid 0.249642 -0.249642)
							(end 0.1778 -0.2794)
						)
					)
					(width 0)
					(fill yes)
				)
			)
		)
	)
	(footprint ""
		(layer "F.Cu")
		(at 39.5224 -134.7978)
		(property "Reference" "PR97"
			(at 0 0 0)
			(layer "F.SilkS")
			(hide yes)
			(effects
				(font
					(size 1.27 1.27)
				)
			)
		)
		(property "Value" "0R2J-2-GP"
			(at 0.064008 -3.993896 0)
			(unlocked yes)
			(layer "F.Fab")
			(hide yes)
			(effects
				(font
					(size 1.016 1.016)
					(thickness 0.1524)
				)
			)
		)
		(property "Device Type" "R402H16"
			(at 0.064008 -5.517896 0)
			(unlocked yes)
			(layer "F.Fab")
			(hide yes)
			(effects
				(font
					(size 1.016 1.016)
					(thickness 0.1524)
				)
			)
		)
		(duplicate_pad_numbers_are_jumpers no)
		(fp_line
			(start -0.508 -0.9398)
			(end -0.508 0.9398)
			(stroke
				(width 0.1524)
				(type default)
			)
			(layer "F.SilkS")
		)
		(fp_line
			(start 0.508 -0.9398)
			(end -0.508 -0.9398)
			(stroke
				(width 0.1524)
				(type default)
			)
			(layer "F.SilkS")
		)
		(fp_rect
			(start -0.508 0.9398)
			(end 0.508 -0.9398)
			(stroke
				(width 0)
				(type default)
			)
			(fill no)
			(layer "F.CrtYd")
		)
		(fp_rect
			(start -0.508 0.9398)
			(end 0.508 -0.9398)
			(stroke
				(width 0)
				(type default)
			)
			(fill no)
			(layer "F.Fab")
		)
		(pad "1" smd custom
			(at 0 -0.4445)
			(size 0.1397 0.1397)
			(layers "F.Cu" "F.Mask" "F.Paste")
			(net "P12VL_2490_SENSE")
			(options
				(clearance outline)
				(anchor circle)
			)
			(primitives
				(gr_poly
					(pts
						(arc
							(start -0.1778 -0.2794)
							(mid -0.249642 -0.249642)
							(end -0.2794 -0.1778)
						)
						(arc
							(start -0.2794 0.1778)
							(mid -0.249642 0.249642)
							(end -0.1778 0.2794)
						)
						(arc
							(start 0.1778 0.2794)
							(mid 0.249642 0.249642)
							(end 0.2794 0.1778)
						)
						(arc
							(start 0.2794 -0.1778)
							(mid 0.249642 -0.249642)
							(end 0.1778 -0.2794)
						)
					)
					(width 0)
					(fill yes)
				)
			)
		)
		(pad "2" smd custom
			(at 0 0.4445)
			(size 0.1397 0.1397)
			(layers "F.Cu" "F.Mask" "F.Paste")
			(net "P12VL_NET")
			(options
				(clearance outline)
				(anchor circle)
			)
			(primitives
				(gr_poly
					(pts
						(arc
							(start -0.1778 -0.2794)
							(mid -0.249642 -0.249642)
							(end -0.2794 -0.1778)
						)
						(arc
							(start -0.2794 0.1778)
							(mid -0.249642 0.249642)
							(end -0.1778 0.2794)
						)
						(arc
							(start 0.1778 0.2794)
							(mid 0.249642 0.249642)
							(end 0.2794 0.1778)
						)
						(arc
							(start 0.2794 -0.1778)
							(mid 0.249642 -0.249642)
							(end 0.1778 -0.2794)
						)
					)
					(width 0)
					(fill yes)
				)
			)
		)
	)
	(footprint ""
		(layer "F.Cu")
		(at 21.766784 -215.519 90)
		(property "Reference" "R131"
			(at 0 0 90)
			(layer "F.SilkS")
			(hide yes)
			(effects
				(font
					(size 1.27 1.27)
				)
			)
		)
		(property "Value" "4K7R2F-GP"
			(at 0.064008 -3.993896 90)
			(unlocked yes)
			(layer "F.Fab")
			(hide yes)
			(effects
				(font
					(size 1.016 1.016)
					(thickness 0.1524)
				)
			)
		)
		(property "Device Type" "R402H16"
			(at 0.064008 -5.517896 90)
			(unlocked yes)
			(layer "F.Fab")
			(hide yes)
			(effects
				(font
					(size 1.016 1.016)
					(thickness 0.1524)
				)
			)
		)
		(duplicate_pad_numbers_are_jumpers no)
		(fp_line
			(start 0.508 -0.9398)
			(end -0.508 -0.9398)
			(stroke
				(width 0.1524)
				(type default)
			)
			(layer "F.SilkS")
		)
		(fp_line
			(start -0.508 -0.9398)
			(end -0.508 0.9398)
			(stroke
				(width 0.1524)
				(type default)
			)
			(layer "F.SilkS")
		)
		(fp_rect
			(start -0.508 0.9398)
			(end 0.508 -0.9398)
			(stroke
				(width 0)
				(type default)
			)
			(fill no)
			(layer "F.CrtYd")
		)
		(fp_rect
			(start -0.508 0.9398)
			(end 0.508 -0.9398)
			(stroke
				(width 0)
				(type default)
			)
			(fill no)
			(layer "F.Fab")
		)
		(pad "1" smd custom
			(at 0 -0.4445 90)
			(size 0.1397 0.1397)
			(layers "F.Cu" "F.Mask" "F.Paste")
			(net "P3V3")
			(options
				(clearance outline)
				(anchor circle)
			)
			(primitives
				(gr_poly
					(pts
						(arc
							(start -0.1778 -0.2794)
							(mid -0.249642 -0.249642)
							(end -0.2794 -0.1778)
						)
						(arc
							(start -0.2794 0.1778)
							(mid -0.249642 0.249642)
							(end -0.1778 0.2794)
						)
						(arc
							(start 0.1778 0.2794)
							(mid 0.249642 0.249642)
							(end 0.2794 0.1778)
						)
						(arc
							(start 0.2794 -0.1778)
							(mid 0.249642 -0.249642)
							(end 0.1778 -0.2794)
						)
					)
					(width 0)
					(fill yes)
				)
			)
		)
		(pad "2" smd custom
			(at 0 0.4445 90)
			(size 0.1397 0.1397)
			(layers "F.Cu" "F.Mask" "F.Paste")
			(net "PWM_OUT_FAN5")
			(options
				(clearance outline)
				(anchor circle)
			)
			(primitives
				(gr_poly
					(pts
						(arc
							(start -0.1778 -0.2794)
							(mid -0.249642 -0.249642)
							(end -0.2794 -0.1778)
						)
						(arc
							(start -0.2794 0.1778)
							(mid -0.249642 0.249642)
							(end -0.1778 0.2794)
						)
						(arc
							(start 0.1778 0.2794)
							(mid 0.249642 0.249642)
							(end 0.2794 0.1778)
						)
						(arc
							(start 0.2794 -0.1778)
							(mid 0.249642 -0.249642)
							(end 0.1778 -0.2794)
						)
					)
					(width 0)
					(fill yes)
				)
			)
		)
	)
	(footprint ""
		(layer "F.Cu")
		(at 26.6446 -167.767 180)
		(property "Reference" "R163"
			(at 0 0 180)
			(layer "F.SilkS")
			(hide yes)
			(effects
				(font
					(size 1.27 1.27)
				)
			)
		)
		(property "Value" "0R2J-2-GP"
			(at 0.064008 -3.993896 180)
			(unlocked yes)
			(layer "F.Fab")
			(hide yes)
			(effects
				(font
					(size 1.016 1.016)
					(thickness 0.1524)
				)
			)
		)
		(property "Device Type" "R402H16"
			(at 0.064008 -5.517896 180)
			(unlocked yes)
			(layer "F.Fab")
			(hide yes)
			(effects
				(font
					(size 1.016 1.016)
					(thickness 0.1524)
				)
			)
		)
		(duplicate_pad_numbers_are_jumpers no)
		(fp_line
			(start 0.508 -0.9398)
			(end -0.508 -0.9398)
			(stroke
				(width 0.1524)
				(type default)
			)
			(layer "F.SilkS")
		)
		(fp_line
			(start -0.508 -0.9398)
			(end -0.508 0.9398)
			(stroke
				(width 0.1524)
				(type default)
			)
			(layer "F.SilkS")
		)
		(fp_rect
			(start -0.508 0.9398)
			(end 0.508 -0.9398)
			(stroke
				(width 0)
				(type default)
			)
			(fill no)
			(layer "F.CrtYd")
		)
		(fp_rect
			(start -0.508 0.9398)
			(end 0.508 -0.9398)
			(stroke
				(width 0)
				(type default)
			)
			(fill no)
			(layer "F.Fab")
		)
		(pad "1" smd custom
			(at 0 -0.4445 180)
			(size 0.1397 0.1397)
			(layers "F.Cu" "F.Mask" "F.Paste")
			(net "NCT7904D_PWM3")
			(options
				(clearance outline)
				(anchor circle)
			)
			(primitives
				(gr_poly
					(pts
						(arc
							(start -0.1778 -0.2794)
							(mid -0.249642 -0.249642)
							(end -0.2794 -0.1778)
						)
						(arc
							(start -0.2794 0.1778)
							(mid -0.249642 0.249642)
							(end -0.1778 0.2794)
						)
						(arc
							(start 0.1778 0.2794)
							(mid 0.249642 0.249642)
							(end 0.2794 0.1778)
						)
						(arc
							(start 0.2794 -0.1778)
							(mid 0.249642 -0.249642)
							(end 0.1778 -0.2794)
						)
					)
					(width 0)
					(fill yes)
				)
			)
		)
		(pad "2" smd custom
			(at 0 0.4445 180)
			(size 0.1397 0.1397)
			(layers "F.Cu" "F.Mask" "F.Paste")
			(net "PWM_BUFFER_IN_FAN5_FAN6")
			(options
				(clearance outline)
				(anchor circle)
			)
			(primitives
				(gr_poly
					(pts
						(arc
							(start -0.1778 -0.2794)
							(mid -0.249642 -0.249642)
							(end -0.2794 -0.1778)
						)
						(arc
							(start -0.2794 0.1778)
							(mid -0.249642 0.249642)
							(end -0.1778 0.2794)
						)
						(arc
							(start 0.1778 0.2794)
							(mid 0.249642 0.249642)
							(end 0.2794 0.1778)
						)
						(arc
							(start 0.2794 -0.1778)
							(mid 0.249642 -0.249642)
							(end 0.1778 -0.2794)
						)
					)
					(width 0)
					(fill yes)
				)
			)
		)
	)
	(footprint ""
		(layer "F.Cu")
		(at 44.704 -158.5722 -90)
		(property "Reference" "R14"
			(at 0 0 270)
			(layer "F.SilkS")
			(hide yes)
			(effects
				(font
					(size 1.27 1.27)
				)
			)
		)
		(property "Value" "110KR2F-L-GP"
			(at 0.064008 -3.993896 270)
			(unlocked yes)
			(layer "F.Fab")
			(hide yes)
			(effects
				(font
					(size 1.016 1.016)
					(thickness 0.1524)
				)
			)
		)
		(property "Device Type" "R402H16"
			(at 0.064008 -5.517896 270)
			(unlocked yes)
			(layer "F.Fab")
			(hide yes)
			(effects
				(font
					(size 1.016 1.016)
					(thickness 0.1524)
				)
			)
		)
		(duplicate_pad_numbers_are_jumpers no)
		(fp_line
			(start -0.508 -0.9398)
			(end -0.508 0.9398)
			(stroke
				(width 0.1524)
				(type default)
			)
			(layer "F.SilkS")
		)
		(fp_line
			(start 0.508 -0.9398)
			(end -0.508 -0.9398)
			(stroke
				(width 0.1524)
				(type default)
			)
			(layer "F.SilkS")
		)
		(fp_rect
			(start -0.508 0.9398)
			(end 0.508 -0.9398)
			(stroke
				(width 0)
				(type default)
			)
			(fill no)
			(layer "F.CrtYd")
		)
		(fp_rect
			(start -0.508 0.9398)
			(end 0.508 -0.9398)
			(stroke
				(width 0)
				(type default)
			)
			(fill no)
			(layer "F.Fab")
		)
		(pad "1" smd custom
			(at 0 -0.4445 270)
			(size 0.1397 0.1397)
			(layers "F.Cu" "F.Mask" "F.Paste")
			(net "P12V_AUX")
			(options
				(clearance outline)
				(anchor circle)
			)
			(primitives
				(gr_poly
					(pts
						(arc
							(start -0.1778 -0.2794)
							(mid -0.249642 -0.249642)
							(end -0.2794 -0.1778)
						)
						(arc
							(start -0.2794 0.1778)
							(mid -0.249642 0.249642)
							(end -0.1778 0.2794)
						)
						(arc
							(start 0.1778 0.2794)
							(mid 0.249642 0.249642)
							(end 0.2794 0.1778)
						)
						(arc
							(start 0.2794 -0.1778)
							(mid 0.249642 -0.249642)
							(end 0.1778 -0.2794)
						)
					)
					(width 0)
					(fill yes)
				)
			)
		)
		(pad "2" smd custom
			(at 0 0.4445 270)
			(size 0.1397 0.1397)
			(layers "F.Cu" "F.Mask" "F.Paste")
			(net "NCT7904_VSEN_P12V_AUX")
			(options
				(clearance outline)
				(anchor circle)
			)
			(primitives
				(gr_poly
					(pts
						(arc
							(start -0.1778 -0.2794)
							(mid -0.249642 -0.249642)
							(end -0.2794 -0.1778)
						)
						(arc
							(start -0.2794 0.1778)
							(mid -0.249642 0.249642)
							(end -0.1778 0.2794)
						)
						(arc
							(start 0.1778 0.2794)
							(mid 0.249642 0.249642)
							(end 0.2794 0.1778)
						)
						(arc
							(start 0.2794 -0.1778)
							(mid 0.249642 -0.249642)
							(end 0.1778 -0.2794)
						)
					)
					(width 0)
					(fill yes)
				)
			)
		)
	)
	(footprint ""
		(layer "F.Cu")
		(at 38.862 -240.665 180)
		(property "Reference" "R156"
			(at 0 0 180)
			(layer "F.SilkS")
			(hide yes)
			(effects
				(font
					(size 1.27 1.27)
				)
			)
		)
		(property "Value" "330R2J-3-GP"
			(at 0.064008 -3.993896 180)
			(unlocked yes)
			(layer "F.Fab")
			(hide yes)
			(effects
				(font
					(size 1.016 1.016)
					(thickness 0.1524)
				)
			)
		)
		(property "Device Type" "R402H16"
			(at 0.064008 -5.517896 180)
			(unlocked yes)
			(layer "F.Fab")
			(hide yes)
			(effects
				(font
					(size 1.016 1.016)
					(thickness 0.1524)
				)
			)
		)
		(duplicate_pad_numbers_are_jumpers no)
		(fp_line
			(start 0.508 -0.9398)
			(end -0.508 -0.9398)
			(stroke
				(width 0.1524)
				(type default)
			)
			(layer "F.SilkS")
		)
		(fp_line
			(start -0.508 -0.9398)
			(end -0.508 0.9398)
			(stroke
				(width 0.1524)
				(type default)
			)
			(layer "F.SilkS")
		)
		(fp_rect
			(start -0.508 0.9398)
			(end 0.508 -0.9398)
			(stroke
				(width 0)
				(type default)
			)
			(fill no)
			(layer "F.CrtYd")
		)
		(fp_rect
			(start -0.508 0.9398)
			(end 0.508 -0.9398)
			(stroke
				(width 0)
				(type default)
			)
			(fill no)
			(layer "F.Fab")
		)
		(pad "1" smd custom
			(at 0 -0.4445 180)
			(size 0.1397 0.1397)
			(layers "F.Cu" "F.Mask" "F.Paste")
			(net "P3V3")
			(options
				(clearance outline)
				(anchor circle)
			)
			(primitives
				(gr_poly
					(pts
						(arc
							(start -0.1778 -0.2794)
							(mid -0.249642 -0.249642)
							(end -0.2794 -0.1778)
						)
						(arc
							(start -0.2794 0.1778)
							(mid -0.249642 0.249642)
							(end -0.1778 0.2794)
						)
						(arc
							(start 0.1778 0.2794)
							(mid 0.249642 0.249642)
							(end 0.2794 0.1778)
						)
						(arc
							(start 0.2794 -0.1778)
							(mid 0.249642 -0.249642)
							(end 0.1778 -0.2794)
						)
					)
					(width 0)
					(fill yes)
				)
			)
		)
		(pad "2" smd custom
			(at 0 0.4445 180)
			(size 0.1397 0.1397)
			(layers "F.Cu" "F.Mask" "F.Paste")
			(net "LED_DR_LED2")
			(options
				(clearance outline)
				(anchor circle)
			)
			(primitives
				(gr_poly
					(pts
						(arc
							(start -0.1778 -0.2794)
							(mid -0.249642 -0.249642)
							(end -0.2794 -0.1778)
						)
						(arc
							(start -0.2794 0.1778)
							(mid -0.249642 0.249642)
							(end -0.1778 0.2794)
						)
						(arc
							(start 0.1778 0.2794)
							(mid 0.249642 0.249642)
							(end 0.2794 0.1778)
						)
						(arc
							(start 0.2794 -0.1778)
							(mid 0.249642 -0.249642)
							(end 0.1778 -0.2794)
						)
					)
					(width 0)
					(fill yes)
				)
			)
		)
	)
	(footprint ""
		(layer "F.Cu")
		(at 32.9946 -251.3838 180)
		(property "Reference" "C19"
			(at 0 0 180)
			(layer "F.SilkS")
			(hide yes)
			(effects
				(font
					(size 1.27 1.27)
				)
			)
		)
		(property "Value" "SC1U16V3KX-5GP"
			(at 0 -2.8194 180)
			(unlocked yes)
			(layer "F.Fab")
			(hide yes)
			(effects
				(font
					(size 1.016 1.016)
					(thickness 0.1524)
				)
			)
		)
		(property "Device Type" "C603H36"
			(at 0 -4.3434 180)
			(unlocked yes)
			(layer "F.Fab")
			(hide yes)
			(effects
				(font
					(size 1.016 1.016)
					(thickness 0.1524)
				)
			)
		)
		(duplicate_pad_numbers_are_jumpers no)
		(fp_line
			(start 0.508 0)
			(end -0.508 0)
			(stroke
				(width 0.2032)
				(type default)
			)
			(layer "F.SilkS")
		)
		(fp_rect
			(start -0.5842 1.3335)
			(end 0.5842 -1.3335)
			(stroke
				(width 0)
				(type default)
			)
			(fill no)
			(layer "F.CrtYd")
		)
		(fp_rect
			(start -0.5842 1.3335)
			(end 0.5842 -1.3335)
			(stroke
				(width 0)
				(type default)
			)
			(fill no)
			(layer "F.Fab")
		)
		(pad "1" smd custom
			(at 0 -0.762 180)
			(size 0.2159 0.2159)
			(layers "F.Cu" "F.Mask" "F.Paste")
			(net "P3V3")
			(options
				(clearance outline)
				(anchor circle)
			)
			(primitives
				(gr_poly
					(pts
						(arc
							(start -0.3302 -0.4318)
							(mid -0.402042 -0.402042)
							(end -0.4318 -0.3302)
						)
						(arc
							(start -0.4318 0.3302)
							(mid -0.402042 0.402042)
							(end -0.3302 0.4318)
						)
						(arc
							(start 0.3302 0.4318)
							(mid 0.402042 0.402042)
							(end 0.4318 0.3302)
						)
						(arc
							(start 0.4318 -0.3302)
							(mid 0.402042 -0.402042)
							(end 0.3302 -0.4318)
						)
					)
					(width 0)
					(fill yes)
				)
			)
		)
		(pad "2" smd custom
			(at 0 0.762 180)
			(size 0.2159 0.2159)
			(layers "F.Cu" "F.Mask" "F.Paste")
			(net "GND")
			(options
				(clearance outline)
				(anchor circle)
			)
			(primitives
				(gr_poly
					(pts
						(arc
							(start -0.3302 -0.4318)
							(mid -0.402042 -0.402042)
							(end -0.4318 -0.3302)
						)
						(arc
							(start -0.4318 0.3302)
							(mid -0.402042 0.402042)
							(end -0.3302 0.4318)
						)
						(arc
							(start 0.3302 0.4318)
							(mid 0.402042 0.402042)
							(end 0.4318 0.3302)
						)
						(arc
							(start 0.4318 -0.3302)
							(mid 0.402042 -0.402042)
							(end 0.3302 -0.4318)
						)
					)
					(width 0)
					(fill yes)
				)
			)
		)
	)
	(footprint ""
		(layer "F.Cu")
		(at 17.119092 -17.602962 180)
		(property "Reference" "R67"
			(at 0 0 180)
			(layer "F.SilkS")
			(hide yes)
			(effects
				(font
					(size 1.27 1.27)
				)
			)
		)
		(property "Value" "4K7R2F-GP"
			(at 0.064008 -3.993896 180)
			(unlocked yes)
			(layer "F.Fab")
			(hide yes)
			(effects
				(font
					(size 1.016 1.016)
					(thickness 0.1524)
				)
			)
		)
		(property "Device Type" "R402H16"
			(at 0.064008 -5.517896 180)
			(unlocked yes)
			(layer "F.Fab")
			(hide yes)
			(effects
				(font
					(size 1.016 1.016)
					(thickness 0.1524)
				)
			)
		)
		(duplicate_pad_numbers_are_jumpers no)
		(fp_line
			(start 0.508 -0.9398)
			(end -0.508 -0.9398)
			(stroke
				(width 0.1524)
				(type default)
			)
			(layer "F.SilkS")
		)
		(fp_line
			(start -0.508 -0.9398)
			(end -0.508 0.9398)
			(stroke
				(width 0.1524)
				(type default)
			)
			(layer "F.SilkS")
		)
		(fp_rect
			(start -0.508 0.9398)
			(end 0.508 -0.9398)
			(stroke
				(width 0)
				(type default)
			)
			(fill no)
			(layer "F.CrtYd")
		)
		(fp_rect
			(start -0.508 1.0668)
			(end 0.508 -0.8128)
			(stroke
				(width 0)
				(type default)
			)
			(fill no)
			(layer "F.Fab")
		)
		(pad "1" smd custom
			(at 0 -0.4445 180)
			(size 0.1397 0.1397)
			(layers "F.Cu" "F.Mask" "F.Paste")
			(net "P12V")
			(options
				(clearance outline)
				(anchor circle)
			)
			(primitives
				(gr_poly
					(pts
						(arc
							(start -0.1778 -0.2794)
							(mid -0.249642 -0.249642)
							(end -0.2794 -0.1778)
						)
						(arc
							(start -0.2794 0.1778)
							(mid -0.249642 0.249642)
							(end -0.1778 0.2794)
						)
						(arc
							(start 0.1778 0.2794)
							(mid 0.249642 0.249642)
							(end 0.2794 0.1778)
						)
						(arc
							(start 0.2794 -0.1778)
							(mid 0.249642 -0.249642)
							(end 0.1778 -0.2794)
						)
					)
					(width 0)
					(fill yes)
				)
			)
		)
		(pad "2" smd custom
			(at 0 0.4445 180)
			(size 0.1397 0.1397)
			(layers "F.Cu" "F.Mask" "F.Paste")
			(net "FAN_TACH12")
			(options
				(clearance outline)
				(anchor circle)
			)
			(primitives
				(gr_poly
					(pts
						(arc
							(start -0.1778 -0.2794)
							(mid -0.249642 -0.249642)
							(end -0.2794 -0.1778)
						)
						(arc
							(start -0.2794 0.1778)
							(mid -0.249642 0.249642)
							(end -0.1778 0.2794)
						)
						(arc
							(start 0.1778 0.2794)
							(mid 0.249642 0.249642)
							(end 0.2794 0.1778)
						)
						(arc
							(start 0.2794 -0.1778)
							(mid 0.249642 -0.249642)
							(end 0.1778 -0.2794)
						)
					)
					(width 0)
					(fill yes)
				)
			)
		)
	)
	(footprint ""
		(layer "F.Cu")
		(at 41.3766 -140.5382 -90)
		(property "Reference" "PC98"
			(at 0 0 270)
			(layer "F.SilkS")
			(hide yes)
			(effects
				(font
					(size 1.27 1.27)
				)
			)
		)
		(property "Value" "SCD1U50V3KX-GP"
			(at 0 -2.8194 270)
			(unlocked yes)
			(layer "F.Fab")
			(hide yes)
			(effects
				(font
					(size 1.016 1.016)
					(thickness 0.1524)
				)
			)
		)
		(property "Device Type" "C603H36"
			(at 0 -4.3434 270)
			(unlocked yes)
			(layer "F.Fab")
			(hide yes)
			(effects
				(font
					(size 1.016 1.016)
					(thickness 0.1524)
				)
			)
		)
		(duplicate_pad_numbers_are_jumpers no)
		(fp_line
			(start 0.508 0)
			(end -0.508 0)
			(stroke
				(width 0.2032)
				(type default)
			)
			(layer "F.SilkS")
		)
		(fp_rect
			(start -0.5842 1.3335)
			(end 0.5842 -1.3335)
			(stroke
				(width 0)
				(type default)
			)
			(fill no)
			(layer "F.CrtYd")
		)
		(fp_rect
			(start -0.5842 1.3335)
			(end 0.5842 -1.3335)
			(stroke
				(width 0)
				(type default)
			)
			(fill no)
			(layer "F.Fab")
		)
		(pad "1" smd custom
			(at 0 -0.762 270)
			(size 0.2159 0.2159)
			(layers "F.Cu" "F.Mask" "F.Paste")
			(net "P12VL_2490_EN_2")
			(options
				(clearance outline)
				(anchor circle)
			)
			(primitives
				(gr_poly
					(pts
						(arc
							(start -0.3302 -0.4318)
							(mid -0.402042 -0.402042)
							(end -0.4318 -0.3302)
						)
						(arc
							(start -0.4318 0.3302)
							(mid -0.402042 0.402042)
							(end -0.3302 0.4318)
						)
						(arc
							(start 0.3302 0.4318)
							(mid 0.402042 0.402042)
							(end 0.4318 0.3302)
						)
						(arc
							(start 0.4318 -0.3302)
							(mid 0.402042 -0.402042)
							(end 0.3302 -0.4318)
						)
					)
					(width 0)
					(fill yes)
				)
			)
		)
		(pad "2" smd custom
			(at 0 0.762 270)
			(size 0.2159 0.2159)
			(layers "F.Cu" "F.Mask" "F.Paste")
			(net "GND")
			(options
				(clearance outline)
				(anchor circle)
			)
			(primitives
				(gr_poly
					(pts
						(arc
							(start -0.3302 -0.4318)
							(mid -0.402042 -0.402042)
							(end -0.4318 -0.3302)
						)
						(arc
							(start -0.4318 0.3302)
							(mid -0.402042 0.402042)
							(end -0.3302 0.4318)
						)
						(arc
							(start 0.3302 0.4318)
							(mid 0.402042 0.402042)
							(end 0.4318 0.3302)
						)
						(arc
							(start 0.4318 -0.3302)
							(mid 0.402042 -0.402042)
							(end 0.3302 -0.4318)
						)
					)
					(width 0)
					(fill yes)
				)
			)
		)
	)
	(footprint ""
		(layer "F.Cu")
		(at 34.29 -358.166416)
		(property "Reference" "R364"
			(at 0 0 0)
			(layer "F.SilkS")
			(hide yes)
			(effects
				(font
					(size 1.27 1.27)
				)
			)
		)
		(property "Value" "0R2J-2-GP"
			(at 0.064008 -3.993896 0)
			(unlocked yes)
			(layer "F.Fab")
			(hide yes)
			(effects
				(font
					(size 1.016 1.016)
					(thickness 0.1524)
				)
			)
		)
		(property "Device Type" "R402H16"
			(at 0.064008 -5.517896 0)
			(unlocked yes)
			(layer "F.Fab")
			(hide yes)
			(effects
				(font
					(size 1.016 1.016)
					(thickness 0.1524)
				)
			)
		)
		(duplicate_pad_numbers_are_jumpers no)
		(fp_line
			(start -0.508 -0.9398)
			(end -0.508 0.9398)
			(stroke
				(width 0.1524)
				(type default)
			)
			(layer "F.SilkS")
		)
		(fp_line
			(start 0.508 -0.9398)
			(end -0.508 -0.9398)
			(stroke
				(width 0.1524)
				(type default)
			)
			(layer "F.SilkS")
		)
		(fp_rect
			(start -0.508 0.9398)
			(end 0.508 -0.9398)
			(stroke
				(width 0)
				(type default)
			)
			(fill no)
			(layer "F.CrtYd")
		)
		(fp_rect
			(start -0.508 0.9398)
			(end 0.508 -0.9398)
			(stroke
				(width 0)
				(type default)
			)
			(fill no)
			(layer "F.Fab")
		)
		(pad "1" smd custom
			(at 0 -0.4445)
			(size 0.1397 0.1397)
			(layers "F.Cu" "F.Mask" "F.Paste")
			(net "OTP_RETRY_DIODE")
			(options
				(clearance outline)
				(anchor circle)
			)
			(primitives
				(gr_poly
					(pts
						(arc
							(start -0.1778 -0.2794)
							(mid -0.249642 -0.249642)
							(end -0.2794 -0.1778)
						)
						(arc
							(start -0.2794 0.1778)
							(mid -0.249642 0.249642)
							(end -0.1778 0.2794)
						)
						(arc
							(start 0.1778 0.2794)
							(mid 0.249642 0.249642)
							(end 0.2794 0.1778)
						)
						(arc
							(start 0.2794 -0.1778)
							(mid 0.249642 -0.249642)
							(end 0.1778 -0.2794)
						)
					)
					(width 0)
					(fill yes)
				)
			)
		)
		(pad "2" smd custom
			(at 0 0.4445)
			(size 0.1397 0.1397)
			(layers "F.Cu" "F.Mask" "F.Paste")
			(net "OTP_RETRY_G")
			(options
				(clearance outline)
				(anchor circle)
			)
			(primitives
				(gr_poly
					(pts
						(arc
							(start -0.1778 -0.2794)
							(mid -0.249642 -0.249642)
							(end -0.2794 -0.1778)
						)
						(arc
							(start -0.2794 0.1778)
							(mid -0.249642 0.249642)
							(end -0.1778 0.2794)
						)
						(arc
							(start 0.1778 0.2794)
							(mid 0.249642 0.249642)
							(end 0.2794 0.1778)
						)
						(arc
							(start 0.2794 -0.1778)
							(mid 0.249642 -0.249642)
							(end 0.1778 -0.2794)
						)
					)
					(width 0)
					(fill yes)
				)
			)
		)
	)
	(footprint ""
		(layer "F.Cu")
		(at 39.243 -149.098 -90)
		(property "Reference" "PR108"
			(at 0 0 270)
			(layer "F.SilkS")
			(hide yes)
			(effects
				(font
					(size 1.27 1.27)
				)
			)
		)
		(property "Value" "6K81R2F-1-GP"
			(at 0.064008 -3.993896 270)
			(unlocked yes)
			(layer "F.Fab")
			(hide yes)
			(effects
				(font
					(size 1.016 1.016)
					(thickness 0.1524)
				)
			)
		)
		(property "Device Type" "R402H16"
			(at 0.064008 -5.517896 270)
			(unlocked yes)
			(layer "F.Fab")
			(hide yes)
			(effects
				(font
					(size 1.016 1.016)
					(thickness 0.1524)
				)
			)
		)
		(duplicate_pad_numbers_are_jumpers no)
		(fp_line
			(start -0.508 -0.9398)
			(end -0.508 0.9398)
			(stroke
				(width 0.1524)
				(type default)
			)
			(layer "F.SilkS")
		)
		(fp_line
			(start 0.508 -0.9398)
			(end -0.508 -0.9398)
			(stroke
				(width 0.1524)
				(type default)
			)
			(layer "F.SilkS")
		)
		(fp_rect
			(start -0.508 0.9398)
			(end 0.508 -0.9398)
			(stroke
				(width 0)
				(type default)
			)
			(fill no)
			(layer "F.CrtYd")
		)
		(fp_rect
			(start -0.508 0.9398)
			(end 0.508 -0.9398)
			(stroke
				(width 0)
				(type default)
			)
			(fill no)
			(layer "F.Fab")
		)
		(pad "1" smd custom
			(at 0 -0.4445 270)
			(size 0.1397 0.1397)
			(layers "F.Cu" "F.Mask" "F.Paste")
			(net "P12V")
			(options
				(clearance outline)
				(anchor circle)
			)
			(primitives
				(gr_poly
					(pts
						(arc
							(start -0.1778 -0.2794)
							(mid -0.249642 -0.249642)
							(end -0.2794 -0.1778)
						)
						(arc
							(start -0.2794 0.1778)
							(mid -0.249642 0.249642)
							(end -0.1778 0.2794)
						)
						(arc
							(start 0.1778 0.2794)
							(mid 0.249642 0.249642)
							(end 0.2794 0.1778)
						)
						(arc
							(start 0.2794 -0.1778)
							(mid 0.249642 -0.249642)
							(end 0.1778 -0.2794)
						)
					)
					(width 0)
					(fill yes)
				)
			)
		)
		(pad "2" smd custom
			(at 0 0.4445 270)
			(size 0.1397 0.1397)
			(layers "F.Cu" "F.Mask" "F.Paste")
			(net "P12VU_2490_EN_1")
			(options
				(clearance outline)
				(anchor circle)
			)
			(primitives
				(gr_poly
					(pts
						(arc
							(start -0.1778 -0.2794)
							(mid -0.249642 -0.249642)
							(end -0.2794 -0.1778)
						)
						(arc
							(start -0.2794 0.1778)
							(mid -0.249642 0.249642)
							(end -0.1778 0.2794)
						)
						(arc
							(start 0.1778 0.2794)
							(mid 0.249642 0.249642)
							(end 0.2794 0.1778)
						)
						(arc
							(start 0.2794 -0.1778)
							(mid 0.249642 -0.249642)
							(end 0.1778 -0.2794)
						)
					)
					(width 0)
					(fill yes)
				)
			)
		)
	)
	(footprint ""
		(layer "F.Cu")
		(at 20.6756 -135.1788)
		(property "Reference" "PR95"
			(at 0 0 0)
			(layer "F.SilkS")
			(hide yes)
			(effects
				(font
					(size 1.27 1.27)
				)
			)
		)
		(property "Value" "0R2J-2-GP"
			(at 0.064008 -3.993896 0)
			(unlocked yes)
			(layer "F.Fab")
			(hide yes)
			(effects
				(font
					(size 1.016 1.016)
					(thickness 0.1524)
				)
			)
		)
		(property "Device Type" "R402H16"
			(at 0.064008 -5.517896 0)
			(unlocked yes)
			(layer "F.Fab")
			(hide yes)
			(effects
				(font
					(size 1.016 1.016)
					(thickness 0.1524)
				)
			)
		)
		(duplicate_pad_numbers_are_jumpers no)
		(fp_line
			(start -0.508 -0.9398)
			(end -0.508 0.9398)
			(stroke
				(width 0.1524)
				(type default)
			)
			(layer "F.SilkS")
		)
		(fp_line
			(start 0.508 -0.9398)
			(end -0.508 -0.9398)
			(stroke
				(width 0.1524)
				(type default)
			)
			(layer "F.SilkS")
		)
		(fp_rect
			(start -0.508 0.9398)
			(end 0.508 -0.9398)
			(stroke
				(width 0)
				(type default)
			)
			(fill no)
			(layer "F.CrtYd")
		)
		(fp_rect
			(start -0.508 0.9398)
			(end 0.508 -0.9398)
			(stroke
				(width 0)
				(type default)
			)
			(fill no)
			(layer "F.Fab")
		)
		(pad "1" smd custom
			(at 0 -0.4445)
			(size 0.1397 0.1397)
			(layers "F.Cu" "F.Mask" "F.Paste")
			(net "P12VU_2490_SENSE")
			(options
				(clearance outline)
				(anchor circle)
			)
			(primitives
				(gr_poly
					(pts
						(arc
							(start -0.1778 -0.2794)
							(mid -0.249642 -0.249642)
							(end -0.2794 -0.1778)
						)
						(arc
							(start -0.2794 0.1778)
							(mid -0.249642 0.249642)
							(end -0.1778 0.2794)
						)
						(arc
							(start 0.1778 0.2794)
							(mid 0.249642 0.249642)
							(end 0.2794 0.1778)
						)
						(arc
							(start 0.2794 -0.1778)
							(mid 0.249642 -0.249642)
							(end 0.1778 -0.2794)
						)
					)
					(width 0)
					(fill yes)
				)
			)
		)
		(pad "2" smd custom
			(at 0 0.4445)
			(size 0.1397 0.1397)
			(layers "F.Cu" "F.Mask" "F.Paste")
			(net "P12VU_NET")
			(options
				(clearance outline)
				(anchor circle)
			)
			(primitives
				(gr_poly
					(pts
						(arc
							(start -0.1778 -0.2794)
							(mid -0.249642 -0.249642)
							(end -0.2794 -0.1778)
						)
						(arc
							(start -0.2794 0.1778)
							(mid -0.249642 0.249642)
							(end -0.1778 0.2794)
						)
						(arc
							(start 0.1778 0.2794)
							(mid 0.249642 0.249642)
							(end 0.2794 0.1778)
						)
						(arc
							(start 0.2794 -0.1778)
							(mid 0.249642 -0.249642)
							(end 0.1778 -0.2794)
						)
					)
					(width 0)
					(fill yes)
				)
			)
		)
	)
	(footprint ""
		(layer "F.Cu")
		(at 35.0266 -378.3076 180)
		(property "Reference" "PR51"
			(at 0 0 180)
			(layer "F.SilkS")
			(hide yes)
			(effects
				(font
					(size 1.27 1.27)
				)
			)
		)
		(property "Value" "10R2F-L-GP"
			(at 0.064008 -3.993896 180)
			(unlocked yes)
			(layer "F.Fab")
			(hide yes)
			(effects
				(font
					(size 1.016 1.016)
					(thickness 0.1524)
				)
			)
		)
		(property "Device Type" "R402H14"
			(at 0.064008 -5.517896 180)
			(unlocked yes)
			(layer "F.Fab")
			(hide yes)
			(effects
				(font
					(size 1.016 1.016)
					(thickness 0.1524)
				)
			)
		)
		(duplicate_pad_numbers_are_jumpers no)
		(fp_line
			(start 0.508 -0.9398)
			(end -0.508 -0.9398)
			(stroke
				(width 0.1524)
				(type default)
			)
			(layer "F.SilkS")
		)
		(fp_line
			(start -0.508 -0.9398)
			(end -0.508 0.9398)
			(stroke
				(width 0.1524)
				(type default)
			)
			(layer "F.SilkS")
		)
		(fp_rect
			(start -0.508 0.9398)
			(end 0.508 -0.9398)
			(stroke
				(width 0)
				(type default)
			)
			(fill no)
			(layer "F.CrtYd")
		)
		(fp_rect
			(start -0.508 0.9398)
			(end 0.508 -0.9398)
			(stroke
				(width 0)
				(type default)
			)
			(fill no)
			(layer "F.Fab")
		)
		(pad "1" smd custom
			(at 0 -0.4445 180)
			(size 0.1397 0.1397)
			(layers "F.Cu" "F.Mask" "F.Paste")
			(net "ADM1276_GATE")
			(options
				(clearance outline)
				(anchor circle)
			)
			(primitives
				(gr_poly
					(pts
						(arc
							(start -0.1778 -0.2794)
							(mid -0.249642 -0.249642)
							(end -0.2794 -0.1778)
						)
						(arc
							(start -0.2794 0.1778)
							(mid -0.249642 0.249642)
							(end -0.1778 0.2794)
						)
						(arc
							(start 0.1778 0.2794)
							(mid 0.249642 0.249642)
							(end 0.2794 0.1778)
						)
						(arc
							(start 0.2794 -0.1778)
							(mid 0.249642 -0.249642)
							(end 0.1778 -0.2794)
						)
					)
					(width 0)
					(fill yes)
				)
			)
		)
		(pad "2" smd custom
			(at 0 0.4445 180)
			(size 0.1397 0.1397)
			(layers "F.Cu" "F.Mask" "F.Paste")
			(net "ADM1276_GATE_DRV0")
			(options
				(clearance outline)
				(anchor circle)
			)
			(primitives
				(gr_poly
					(pts
						(arc
							(start -0.1778 -0.2794)
							(mid -0.249642 -0.249642)
							(end -0.2794 -0.1778)
						)
						(arc
							(start -0.2794 0.1778)
							(mid -0.249642 0.249642)
							(end -0.1778 0.2794)
						)
						(arc
							(start 0.1778 0.2794)
							(mid 0.249642 0.249642)
							(end 0.2794 0.1778)
						)
						(arc
							(start 0.2794 -0.1778)
							(mid 0.249642 -0.249642)
							(end 0.1778 -0.2794)
						)
					)
					(width 0)
					(fill yes)
				)
			)
		)
	)
	(footprint ""
		(layer "F.Cu")
		(at 39.243 -178.054 180)
		(property "Reference" "PR45"
			(at 0 0 180)
			(layer "F.SilkS")
			(hide yes)
			(effects
				(font
					(size 1.27 1.27)
				)
			)
		)
		(property "Value" "10KR2F-2-GP"
			(at 0.064008 -3.993896 180)
			(unlocked yes)
			(layer "F.Fab")
			(hide yes)
			(effects
				(font
					(size 1.016 1.016)
					(thickness 0.1524)
				)
			)
		)
		(property "Device Type" "R402H16"
			(at 0.064008 -5.517896 180)
			(unlocked yes)
			(layer "F.Fab")
			(hide yes)
			(effects
				(font
					(size 1.016 1.016)
					(thickness 0.1524)
				)
			)
		)
		(duplicate_pad_numbers_are_jumpers no)
		(fp_line
			(start 0.508 -0.9398)
			(end -0.508 -0.9398)
			(stroke
				(width 0.1524)
				(type default)
			)
			(layer "F.SilkS")
		)
		(fp_line
			(start -0.508 -0.9398)
			(end -0.508 0.9398)
			(stroke
				(width 0.1524)
				(type default)
			)
			(layer "F.SilkS")
		)
		(fp_rect
			(start -0.508 0.9398)
			(end 0.508 -0.9398)
			(stroke
				(width 0)
				(type default)
			)
			(fill no)
			(layer "F.CrtYd")
		)
		(fp_rect
			(start -0.508 0.9398)
			(end 0.508 -0.9398)
			(stroke
				(width 0)
				(type default)
			)
			(fill no)
			(layer "F.Fab")
		)
		(pad "1" smd custom
			(at 0 -0.4445 180)
			(size 0.1397 0.1397)
			(layers "F.Cu" "F.Mask" "F.Paste")
			(net "P3V3_AUX")
			(options
				(clearance outline)
				(anchor circle)
			)
			(primitives
				(gr_poly
					(pts
						(arc
							(start -0.1778 -0.2794)
							(mid -0.249642 -0.249642)
							(end -0.2794 -0.1778)
						)
						(arc
							(start -0.2794 0.1778)
							(mid -0.249642 0.249642)
							(end -0.1778 0.2794)
						)
						(arc
							(start 0.1778 0.2794)
							(mid 0.249642 0.249642)
							(end 0.2794 0.1778)
						)
						(arc
							(start 0.2794 -0.1778)
							(mid 0.249642 -0.249642)
							(end 0.1778 -0.2794)
						)
					)
					(width 0)
					(fill yes)
				)
			)
		)
		(pad "2" smd custom
			(at 0 0.4445 180)
			(size 0.1397 0.1397)
			(layers "F.Cu" "F.Mask" "F.Paste")
			(net "TEMP_ALM#_IN_D")
			(options
				(clearance outline)
				(anchor circle)
			)
			(primitives
				(gr_poly
					(pts
						(arc
							(start -0.1778 -0.2794)
							(mid -0.249642 -0.249642)
							(end -0.2794 -0.1778)
						)
						(arc
							(start -0.2794 0.1778)
							(mid -0.249642 0.249642)
							(end -0.1778 0.2794)
						)
						(arc
							(start 0.1778 0.2794)
							(mid 0.249642 0.249642)
							(end 0.2794 0.1778)
						)
						(arc
							(start 0.2794 -0.1778)
							(mid 0.249642 -0.249642)
							(end 0.1778 -0.2794)
						)
					)
					(width 0)
					(fill yes)
				)
			)
		)
	)
	(footprint ""
		(layer "F.Cu")
		(at 43.2054 -155.2956 180)
		(property "Reference" "C3"
			(at 0 0 180)
			(layer "F.SilkS")
			(hide yes)
			(effects
				(font
					(size 1.27 1.27)
				)
			)
		)
		(property "Value" "SC10U25V5KX-GP"
			(at -0.0762 -6.1214 180)
			(unlocked yes)
			(layer "F.Fab")
			(hide yes)
			(effects
				(font
					(size 1.016 1.016)
					(thickness 0.1524)
				)
			)
		)
		(property "Device Type" "C805H56"
			(at -0.0762 -8.1534 180)
			(unlocked yes)
			(layer "F.Fab")
			(hide yes)
			(effects
				(font
					(size 1.016 1.016)
					(thickness 0.1524)
				)
			)
		)
		(duplicate_pad_numbers_are_jumpers no)
		(fp_line
			(start 0.635 0)
			(end -0.635 0)
			(stroke
				(width 0.508)
				(type default)
			)
			(layer "F.SilkS")
		)
		(fp_rect
			(start -0.9652 1.778)
			(end 0.9652 -1.778)
			(stroke
				(width 0)
				(type default)
			)
			(fill no)
			(layer "F.CrtYd")
		)
		(fp_poly
			(pts
				(xy -0.9652 -1.778) (xy 0.9652 -1.778) (xy 0.9652 1.778) (xy -0.9652 1.778)
			)
			(stroke
				(width 0)
				(type default)
			)
			(fill no)
			(layer "F.Fab")
		)
		(pad "1" smd rect
			(at 0 -0.9652 180)
			(size 1.397 1.143)
			(layers "F.Cu" "F.Mask" "F.Paste")
			(net "NCT7904_3VSB")
		)
		(pad "2" smd rect
			(at 0 0.9652 180)
			(size 1.397 1.143)
			(layers "F.Cu" "F.Mask" "F.Paste")
			(net "GND")
		)
	)
	(footprint ""
		(layer "F.Cu")
		(at 23.4442 -222.416116 180)
		(property "Reference" "C15"
			(at 0 0 180)
			(layer "F.SilkS")
			(hide yes)
			(effects
				(font
					(size 1.27 1.27)
				)
			)
		)
		(property "Value" "SC1U16V3KX-5GP"
			(at 0 -2.8194 180)
			(unlocked yes)
			(layer "F.Fab")
			(hide yes)
			(effects
				(font
					(size 1.016 1.016)
					(thickness 0.1524)
				)
			)
		)
		(property "Device Type" "C603H36"
			(at 0 -4.3434 180)
			(unlocked yes)
			(layer "F.Fab")
			(hide yes)
			(effects
				(font
					(size 1.016 1.016)
					(thickness 0.1524)
				)
			)
		)
		(duplicate_pad_numbers_are_jumpers no)
		(fp_line
			(start 0.508 0)
			(end -0.508 0)
			(stroke
				(width 0.2032)
				(type default)
			)
			(layer "F.SilkS")
		)
		(fp_rect
			(start -0.5842 1.3335)
			(end 0.5842 -1.3335)
			(stroke
				(width 0)
				(type default)
			)
			(fill no)
			(layer "F.CrtYd")
		)
		(fp_rect
			(start -0.5842 1.3335)
			(end 0.5842 -1.3335)
			(stroke
				(width 0)
				(type default)
			)
			(fill no)
			(layer "F.Fab")
		)
		(pad "1" smd custom
			(at 0 -0.762 180)
			(size 0.2159 0.2159)
			(layers "F.Cu" "F.Mask" "F.Paste")
			(net "P3V3")
			(options
				(clearance outline)
				(anchor circle)
			)
			(primitives
				(gr_poly
					(pts
						(arc
							(start -0.3302 -0.4318)
							(mid -0.402042 -0.402042)
							(end -0.4318 -0.3302)
						)
						(arc
							(start -0.4318 0.3302)
							(mid -0.402042 0.402042)
							(end -0.3302 0.4318)
						)
						(arc
							(start 0.3302 0.4318)
							(mid 0.402042 0.402042)
							(end 0.4318 0.3302)
						)
						(arc
							(start 0.4318 -0.3302)
							(mid 0.402042 -0.402042)
							(end 0.3302 -0.4318)
						)
					)
					(width 0)
					(fill yes)
				)
			)
		)
		(pad "2" smd custom
			(at 0 0.762 180)
			(size 0.2159 0.2159)
			(layers "F.Cu" "F.Mask" "F.Paste")
			(net "GND")
			(options
				(clearance outline)
				(anchor circle)
			)
			(primitives
				(gr_poly
					(pts
						(arc
							(start -0.3302 -0.4318)
							(mid -0.402042 -0.402042)
							(end -0.4318 -0.3302)
						)
						(arc
							(start -0.4318 0.3302)
							(mid -0.402042 0.402042)
							(end -0.3302 0.4318)
						)
						(arc
							(start 0.3302 0.4318)
							(mid 0.402042 0.402042)
							(end 0.4318 0.3302)
						)
						(arc
							(start 0.4318 -0.3302)
							(mid 0.402042 -0.402042)
							(end 0.3302 -0.4318)
						)
					)
					(width 0)
					(fill yes)
				)
			)
		)
	)
	(footprint ""
		(layer "F.Cu")
		(at 43.9166 -101.0666 90)
		(property "Reference" "TC8"
			(at 0 0 90)
			(layer "F.SilkS")
			(hide yes)
			(effects
				(font
					(size 1.27 1.27)
				)
			)
		)
		(property "Value" "ST15U25VDM-1-GP"
			(at 0 -9.6012 90)
			(unlocked yes)
			(layer "F.Fab")
			(hide yes)
			(effects
				(font
					(size 1.016 1.016)
					(thickness 0.1524)
				)
			)
		)
		(property "Device Type" "CT7343H79"
			(at 0 -11.1252 90)
			(unlocked yes)
			(layer "F.Fab")
			(hide yes)
			(effects
				(font
					(size 1.016 1.016)
					(thickness 0.1524)
				)
			)
		)
		(duplicate_pad_numbers_are_jumpers no)
		(fp_line
			(start 2.286 -4.8768)
			(end -2.286 -4.8768)
			(stroke
				(width 0.1524)
				(type default)
			)
			(layer "F.SilkS")
		)
		(fp_line
			(start -2.286 -4.8768)
			(end -2.286 -2.032)
			(stroke
				(width 0.1524)
				(type default)
			)
			(layer "F.SilkS")
		)
		(fp_line
			(start 2.1082 -4.699)
			(end -2.1082 -4.699)
			(stroke
				(width 0.508)
				(type default)
			)
			(layer "F.SilkS")
		)
		(fp_line
			(start 2.286 -2.032)
			(end 2.286 -4.8768)
			(stroke
				(width 0.1524)
				(type default)
			)
			(layer "F.SilkS")
		)
		(fp_line
			(start 2.286 2.032)
			(end 2.286 4.8768)
			(stroke
				(width 0.1524)
				(type default)
			)
			(layer "F.SilkS")
		)
		(fp_line
			(start 2.286 4.8768)
			(end -2.286 4.8768)
			(stroke
				(width 0.1524)
				(type default)
			)
			(layer "F.SilkS")
		)
		(fp_line
			(start -2.286 4.8768)
			(end -2.286 2.032)
			(stroke
				(width 0.1524)
				(type default)
			)
			(layer "F.SilkS")
		)
		(fp_rect
			(start -2.1463 3.6449)
			(end 2.1463 -3.6449)
			(stroke
				(width 0)
				(type default)
			)
			(fill no)
			(layer "F.CrtYd")
		)
		(fp_poly
			(pts
				(xy -2.54 4.953) (xy -2.54 4.2926) (xy -3.81 4.2926) (xy -3.81 -4.2926) (xy -2.54 -4.2926) (xy -2.54 -4.953)
				(xy 2.54 -4.953) (xy 2.54 -4.2926) (xy 3.81 -4.2926) (xy 3.81 -1.6256) (xy 2.1463 -1.6256) (xy 2.1463 -3.6449)
				(xy -2.1463 -3.6449) (xy -2.1463 3.6449) (xy 2.1463 3.6449) (xy 2.1463 -1.6129) (xy 3.81 -1.6129)
				(xy 3.81 4.2926) (xy 2.54 4.2926) (xy 2.54 4.953)
			)
			(stroke
				(width 0)
				(type default)
			)
			(fill no)
			(layer "F.CrtYd")
		)
		(fp_rect
			(start 2.54 4.2926)
			(end 3.81 -4.2926)
			(stroke
				(width 0)
				(type default)
			)
			(fill no)
			(layer "F.Fab")
		)
		(fp_rect
			(start -3.81 4.2926)
			(end -2.54 -4.2926)
			(stroke
				(width 0)
				(type default)
			)
			(fill no)
			(layer "F.Fab")
		)
		(fp_rect
			(start -2.54 4.953)
			(end 2.54 -4.953)
			(stroke
				(width 0)
				(type default)
			)
			(fill no)
			(layer "F.Fab")
		)
		(pad "1" smd rect
			(at 0 -3.1496 90)
			(size 2.413 2.286)
			(layers "F.Cu" "F.Mask" "F.Paste")
			(net "P12VL")
		)
		(pad "2" smd rect
			(at 0 3.1496 90)
			(size 2.413 2.286)
			(layers "F.Cu" "F.Mask" "F.Paste")
			(net "GND")
		)
		(zone
			(layer "F.Cu")
			(hatch none 0.5)
			(connect_pads
				(clearance 0)
			)
			(min_thickness 0.25)
			(keepout
				(tracks allowed)
				(vias not_allowed)
				(pads allowed)
				(copperpour not_allowed)
				(footprints allowed)
			)
			(placement
				(enabled no)
				(sheetname "")
			)
			(fill
				(thermal_gap 0.5)
				(thermal_bridge_width 0.5)
				(island_removal_mode 0)
			)
			(polygon
				(pts
					(xy 42.2275 -102.5779) (xy 39.3192 -102.5779) (xy 39.3192 -99.5553) (xy 42.2148 -99.5553) (xy 42.545 -99.5553)
					(xy 42.545 -102.5779)
				)
			)
		)
		(zone
			(layer "F.Cu")
			(hatch none 0.5)
			(connect_pads
				(clearance 0)
			)
			(min_thickness 0.25)
			(keepout
				(tracks allowed)
				(vias not_allowed)
				(pads allowed)
				(copperpour not_allowed)
				(footprints allowed)
			)
			(placement
				(enabled no)
				(sheetname "")
			)
			(fill
				(thermal_gap 0.5)
				(thermal_bridge_width 0.5)
				(island_removal_mode 0)
			)
			(polygon
				(pts
					(xy 48.514 -99.5553) (xy 48.514 -102.5779) (xy 45.6184 -102.5779) (xy 45.2882 -102.5779) (xy 45.2882 -99.5553)
					(xy 45.6184 -99.5553)
				)
			)
		)
	)
	(footprint ""
		(layer "F.Cu")
		(at 30.3022 -224.3074)
		(property "Reference" "R138"
			(at 0 0 0)
			(layer "F.SilkS")
			(hide yes)
			(effects
				(font
					(size 1.27 1.27)
				)
			)
		)
		(property "Value" "0R2J-2-GP"
			(at 0.064008 -3.993896 0)
			(unlocked yes)
			(layer "F.Fab")
			(hide yes)
			(effects
				(font
					(size 1.016 1.016)
					(thickness 0.1524)
				)
			)
		)
		(property "Device Type" "R402H16"
			(at 0.064008 -5.517896 0)
			(unlocked yes)
			(layer "F.Fab")
			(hide yes)
			(effects
				(font
					(size 1.016 1.016)
					(thickness 0.1524)
				)
			)
		)
		(duplicate_pad_numbers_are_jumpers no)
		(fp_line
			(start -0.508 -0.9398)
			(end -0.508 0.9398)
			(stroke
				(width 0.1524)
				(type default)
			)
			(layer "F.SilkS")
		)
		(fp_line
			(start 0.508 -0.9398)
			(end -0.508 -0.9398)
			(stroke
				(width 0.1524)
				(type default)
			)
			(layer "F.SilkS")
		)
		(fp_rect
			(start -0.508 0.9398)
			(end 0.508 -0.9398)
			(stroke
				(width 0)
				(type default)
			)
			(fill no)
			(layer "F.CrtYd")
		)
		(fp_rect
			(start -0.508 0.9398)
			(end 0.508 -0.9398)
			(stroke
				(width 0)
				(type default)
			)
			(fill no)
			(layer "F.Fab")
		)
		(pad "1" smd custom
			(at 0 -0.4445)
			(size 0.1397 0.1397)
			(layers "F.Cu" "F.Mask" "F.Paste")
			(net "PWM_OUT_FAN3_NET")
			(options
				(clearance outline)
				(anchor circle)
			)
			(primitives
				(gr_poly
					(pts
						(arc
							(start -0.1778 -0.2794)
							(mid -0.249642 -0.249642)
							(end -0.2794 -0.1778)
						)
						(arc
							(start -0.2794 0.1778)
							(mid -0.249642 0.249642)
							(end -0.1778 0.2794)
						)
						(arc
							(start 0.1778 0.2794)
							(mid 0.249642 0.249642)
							(end 0.2794 0.1778)
						)
						(arc
							(start 0.2794 -0.1778)
							(mid 0.249642 -0.249642)
							(end 0.1778 -0.2794)
						)
					)
					(width 0)
					(fill yes)
				)
			)
		)
		(pad "2" smd custom
			(at 0 0.4445)
			(size 0.1397 0.1397)
			(layers "F.Cu" "F.Mask" "F.Paste")
			(net "PWM_OUT_FAN3")
			(options
				(clearance outline)
				(anchor circle)
			)
			(primitives
				(gr_poly
					(pts
						(arc
							(start -0.1778 -0.2794)
							(mid -0.249642 -0.249642)
							(end -0.2794 -0.1778)
						)
						(arc
							(start -0.2794 0.1778)
							(mid -0.249642 0.249642)
							(end -0.1778 0.2794)
						)
						(arc
							(start 0.1778 0.2794)
							(mid 0.249642 0.249642)
							(end 0.2794 0.1778)
						)
						(arc
							(start 0.2794 -0.1778)
							(mid 0.249642 -0.249642)
							(end 0.1778 -0.2794)
						)
					)
					(width 0)
					(fill yes)
				)
			)
		)
	)
	(footprint ""
		(layer "F.Cu")
		(at 9.4488 -74.7522 -90)
		(property "Reference" "C23"
			(at 0 0 270)
			(layer "F.SilkS")
			(hide yes)
			(effects
				(font
					(size 1.27 1.27)
				)
			)
		)
		(property "Value" "SCD1U50V3KX-GP"
			(at 0 -2.8194 270)
			(unlocked yes)
			(layer "F.Fab")
			(hide yes)
			(effects
				(font
					(size 1.016 1.016)
					(thickness 0.1524)
				)
			)
		)
		(property "Device Type" "C603H36"
			(at 0 -4.3434 270)
			(unlocked yes)
			(layer "F.Fab")
			(hide yes)
			(effects
				(font
					(size 1.016 1.016)
					(thickness 0.1524)
				)
			)
		)
		(duplicate_pad_numbers_are_jumpers no)
		(fp_line
			(start 0.508 0)
			(end -0.508 0)
			(stroke
				(width 0.2032)
				(type default)
			)
			(layer "F.SilkS")
		)
		(fp_rect
			(start -0.5842 1.3335)
			(end 0.5842 -1.3335)
			(stroke
				(width 0)
				(type default)
			)
			(fill no)
			(layer "F.CrtYd")
		)
		(fp_rect
			(start -0.5842 1.3335)
			(end 0.5842 -1.3335)
			(stroke
				(width 0)
				(type default)
			)
			(fill no)
			(layer "F.Fab")
		)
		(pad "1" smd custom
			(at 0 -0.762 270)
			(size 0.2159 0.2159)
			(layers "F.Cu" "F.Mask" "F.Paste")
			(net "P12VU")
			(options
				(clearance outline)
				(anchor circle)
			)
			(primitives
				(gr_poly
					(pts
						(arc
							(start -0.3302 -0.4318)
							(mid -0.402042 -0.402042)
							(end -0.4318 -0.3302)
						)
						(arc
							(start -0.4318 0.3302)
							(mid -0.402042 0.402042)
							(end -0.3302 0.4318)
						)
						(arc
							(start 0.3302 0.4318)
							(mid 0.402042 0.402042)
							(end 0.4318 0.3302)
						)
						(arc
							(start 0.4318 -0.3302)
							(mid 0.402042 -0.402042)
							(end 0.3302 -0.4318)
						)
					)
					(width 0)
					(fill yes)
				)
			)
		)
		(pad "2" smd custom
			(at 0 0.762 270)
			(size 0.2159 0.2159)
			(layers "F.Cu" "F.Mask" "F.Paste")
			(net "GND")
			(options
				(clearance outline)
				(anchor circle)
			)
			(primitives
				(gr_poly
					(pts
						(arc
							(start -0.3302 -0.4318)
							(mid -0.402042 -0.402042)
							(end -0.4318 -0.3302)
						)
						(arc
							(start -0.4318 0.3302)
							(mid -0.402042 0.402042)
							(end -0.3302 0.4318)
						)
						(arc
							(start 0.3302 0.4318)
							(mid 0.402042 0.402042)
							(end 0.4318 0.3302)
						)
						(arc
							(start 0.4318 -0.3302)
							(mid 0.402042 -0.402042)
							(end 0.3302 -0.4318)
						)
					)
					(width 0)
					(fill yes)
				)
			)
		)
	)
	(footprint ""
		(layer "F.Cu")
		(at 37.17671 -154.818334)
		(property "Reference" "C2"
			(at 0 0 0)
			(layer "F.SilkS")
			(hide yes)
			(effects
				(font
					(size 1.27 1.27)
				)
			)
		)
		(property "Value" "SCD1U16V2KX-3GP"
			(at 1.1811 -2.7051 0)
			(unlocked yes)
			(layer "F.Fab")
			(hide yes)
			(effects
				(font
					(size 1.016 1.016)
					(thickness 0.1524)
				)
			)
		)
		(property "Device Type" "C402H22"
			(at 1.1811 -4.2291 0)
			(unlocked yes)
			(layer "F.Fab")
			(hide yes)
			(effects
				(font
					(size 1.016 1.016)
					(thickness 0.1524)
				)
			)
		)
		(duplicate_pad_numbers_are_jumpers no)
		(fp_rect
			(start -0.4318 0.9525)
			(end 0.4318 -0.9525)
			(stroke
				(width 0)
				(type default)
			)
			(fill no)
			(layer "F.CrtYd")
		)
		(fp_rect
			(start -0.4318 0.9525)
			(end 0.4318 -0.9525)
			(stroke
				(width 0)
				(type default)
			)
			(fill no)
			(layer "F.Fab")
		)
		(pad "1" smd custom
			(at 0 -0.4445)
			(size 0.1524 0.1524)
			(layers "F.Cu" "F.Mask" "F.Paste")
			(net "NCT7904_3VDD")
			(options
				(clearance outline)
				(anchor circle)
			)
			(primitives
				(gr_poly
					(pts
						(arc
							(start 0.3048 -0.2032)
							(mid 0.275042 -0.275042)
							(end 0.2032 -0.3048)
						)
						(arc
							(start -0.2032 -0.3048)
							(mid -0.275042 -0.275042)
							(end -0.3048 -0.2032)
						)
						(arc
							(start -0.3048 0.2032)
							(mid -0.275042 0.275042)
							(end -0.2032 0.3048)
						)
						(arc
							(start 0.2032 0.3048)
							(mid 0.275042 0.275042)
							(end 0.3048 0.2032)
						)
					)
					(width 0)
					(fill yes)
				)
			)
		)
		(pad "2" smd custom
			(at 0 0.4445)
			(size 0.1524 0.1524)
			(layers "F.Cu" "F.Mask" "F.Paste")
			(net "GND")
			(options
				(clearance outline)
				(anchor circle)
			)
			(primitives
				(gr_poly
					(pts
						(arc
							(start 0.3048 -0.2032)
							(mid 0.275042 -0.275042)
							(end 0.2032 -0.3048)
						)
						(arc
							(start -0.2032 -0.3048)
							(mid -0.275042 -0.275042)
							(end -0.3048 -0.2032)
						)
						(arc
							(start -0.3048 0.2032)
							(mid -0.275042 0.275042)
							(end -0.2032 0.3048)
						)
						(arc
							(start 0.2032 0.3048)
							(mid 0.275042 0.275042)
							(end 0.3048 0.2032)
						)
					)
					(width 0)
					(fill yes)
				)
			)
		)
	)
	(footprint ""
		(layer "F.Cu")
		(at 17.91589 -175.540924 180)
		(property "Reference" "C10"
			(at 0 0 180)
			(layer "F.SilkS")
			(hide yes)
			(effects
				(font
					(size 1.27 1.27)
				)
			)
		)
		(property "Value" "SCD1U50V3KX-GP"
			(at 0 -2.8194 180)
			(unlocked yes)
			(layer "F.Fab")
			(hide yes)
			(effects
				(font
					(size 1.016 1.016)
					(thickness 0.1524)
				)
			)
		)
		(property "Device Type" "C603H36"
			(at 0 -4.3434 180)
			(unlocked yes)
			(layer "F.Fab")
			(hide yes)
			(effects
				(font
					(size 1.016 1.016)
					(thickness 0.1524)
				)
			)
		)
		(duplicate_pad_numbers_are_jumpers no)
		(fp_line
			(start 0.508 0)
			(end -0.508 0)
			(stroke
				(width 0.2032)
				(type default)
			)
			(layer "F.SilkS")
		)
		(fp_rect
			(start -0.5842 1.3335)
			(end 0.5842 -1.3335)
			(stroke
				(width 0)
				(type default)
			)
			(fill no)
			(layer "F.CrtYd")
		)
		(fp_rect
			(start -0.5842 1.3335)
			(end 0.5842 -1.3335)
			(stroke
				(width 0)
				(type default)
			)
			(fill no)
			(layer "F.Fab")
		)
		(pad "1" smd custom
			(at 0 -0.762 180)
			(size 0.2159 0.2159)
			(layers "F.Cu" "F.Mask" "F.Paste")
			(net "P3V3")
			(options
				(clearance outline)
				(anchor circle)
			)
			(primitives
				(gr_poly
					(pts
						(arc
							(start -0.3302 -0.4318)
							(mid -0.402042 -0.402042)
							(end -0.4318 -0.3302)
						)
						(arc
							(start -0.4318 0.3302)
							(mid -0.402042 0.402042)
							(end -0.3302 0.4318)
						)
						(arc
							(start 0.3302 0.4318)
							(mid 0.402042 0.402042)
							(end 0.4318 0.3302)
						)
						(arc
							(start 0.4318 -0.3302)
							(mid 0.402042 -0.402042)
							(end 0.3302 -0.4318)
						)
					)
					(width 0)
					(fill yes)
				)
			)
		)
		(pad "2" smd custom
			(at 0 0.762 180)
			(size 0.2159 0.2159)
			(layers "F.Cu" "F.Mask" "F.Paste")
			(net "GND")
			(options
				(clearance outline)
				(anchor circle)
			)
			(primitives
				(gr_poly
					(pts
						(arc
							(start -0.3302 -0.4318)
							(mid -0.402042 -0.402042)
							(end -0.4318 -0.3302)
						)
						(arc
							(start -0.4318 0.3302)
							(mid -0.402042 0.402042)
							(end -0.3302 0.4318)
						)
						(arc
							(start 0.3302 0.4318)
							(mid 0.402042 0.402042)
							(end 0.4318 0.3302)
						)
						(arc
							(start 0.4318 -0.3302)
							(mid 0.402042 -0.402042)
							(end 0.3302 -0.4318)
						)
					)
					(width 0)
					(fill yes)
				)
			)
		)
	)
	(footprint ""
		(layer "F.Cu")
		(at 21.6916 -140.4366 180)
		(property "Reference" "PU6"
			(at 0 0 180)
			(layer "F.SilkS")
			(hide yes)
			(effects
				(font
					(size 1.27 1.27)
				)
			)
		)
		(property "Value" "TPS2490DGSR-GP"
			(at 0 -11.1252 180)
			(unlocked yes)
			(layer "F.Fab")
			(hide yes)
			(effects
				(font
					(size 1.016 1.016)
					(thickness 0.1524)
				)
			)
		)
		(property "Device Type" "MSOP10H44"
			(at 0 -12.6492 180)
			(unlocked yes)
			(layer "F.Fab")
			(hide yes)
			(effects
				(font
					(size 1.016 1.016)
					(thickness 0.1524)
				)
			)
		)
		(duplicate_pad_numbers_are_jumpers no)
		(fp_line
			(start 1.143 1.016)
			(end -2.0066 1.016)
			(stroke
				(width 0.1524)
				(type default)
			)
			(layer "F.SilkS")
		)
		(fp_line
			(start 1.143 -1.016)
			(end 1.143 1.016)
			(stroke
				(width 0.1524)
				(type default)
			)
			(layer "F.SilkS")
		)
		(fp_line
			(start -1.5748 0)
			(end -1.9558 0.381)
			(stroke
				(width 0.1524)
				(type default)
			)
			(layer "F.SilkS")
		)
		(fp_line
			(start -1.5748 0)
			(end -1.9558 -0.381)
			(stroke
				(width 0.1524)
				(type default)
			)
			(layer "F.SilkS")
		)
		(fp_line
			(start -1.8288 1.016)
			(end -1.8288 3.048)
			(stroke
				(width 0.508)
				(type default)
			)
			(layer "F.SilkS")
		)
		(fp_line
			(start -2.0066 1.016)
			(end -2.0066 -1.016)
			(stroke
				(width 0.1524)
				(type default)
			)
			(layer "F.SilkS")
		)
		(fp_line
			(start -2.0066 -1.016)
			(end 1.143 -1.016)
			(stroke
				(width 0.1524)
				(type default)
			)
			(layer "F.SilkS")
		)
		(fp_poly
			(pts
				(xy -2.0828 3.3401) (xy 2.0828 3.3401) (xy 2.0828 -3.3401) (xy -2.0828 -3.3401)
			)
			(stroke
				(width 0)
				(type default)
			)
			(fill no)
			(layer "F.CrtYd")
		)
		(fp_poly
			(pts
				(xy -2.0828 3.3401) (xy 2.0828 3.3401) (xy 2.0828 -3.3401) (xy -2.0828 -3.3401)
			)
			(stroke
				(width 0)
				(type default)
			)
			(fill no)
			(layer "F.Fab")
		)
		(pad "1" smd rect
			(at -0.99949 2.0701 180)
			(size 0.3048 1.524)
			(layers "F.Cu" "F.Mask" "F.Paste")
			(net "P12VU_2490_EN_2")
		)
		(pad "2" smd rect
			(at -0.50038 2.0701 180)
			(size 0.3048 1.524)
			(layers "F.Cu" "F.Mask" "F.Paste")
			(net "P12VU_2490_VREF")
		)
		(pad "3" smd rect
			(at 0 2.0701 180)
			(size 0.3048 1.524)
			(layers "F.Cu" "F.Mask" "F.Paste")
			(net "P12VU_2490_PROG")
		)
		(pad "4" smd rect
			(at 0.50038 2.0701 180)
			(size 0.3048 1.524)
			(layers "F.Cu" "F.Mask" "F.Paste")
			(net "P12VU_2490_TIMER")
		)
		(pad "5" smd rect
			(at 0.99949 2.0701 180)
			(size 0.3048 1.524)
			(layers "F.Cu" "F.Mask" "F.Paste")
			(net "GND")
		)
		(pad "6" smd rect
			(at 0.99949 -2.0701 180)
			(size 0.3048 1.524)
			(layers "F.Cu" "F.Mask" "F.Paste")
			(net "P12VU_2490_PG")
		)
		(pad "7" smd rect
			(at 0.50038 -2.0701 180)
			(size 0.3048 1.524)
			(layers "F.Cu" "F.Mask" "F.Paste")
			(net "P12VU")
		)
		(pad "8" smd rect
			(at 0 -2.0701 180)
			(size 0.3048 1.524)
			(layers "F.Cu" "F.Mask" "F.Paste")
			(net "P12VU_2490_GATE")
		)
		(pad "9" smd rect
			(at -0.50038 -2.0701 180)
			(size 0.3048 1.524)
			(layers "F.Cu" "F.Mask" "F.Paste")
			(net "P12VU_2490_SENSE")
		)
		(pad "10" smd rect
			(at -0.99949 -2.0701 180)
			(size 0.3048 1.524)
			(layers "F.Cu" "F.Mask" "F.Paste")
			(net "P12VU_2490_VCC")
		)
	)
	(footprint ""
		(layer "F.Cu")
		(at 18.0594 -262.1534 90)
		(property "Reference" "D5"
			(at 0 0 90)
			(layer "F.SilkS")
			(hide yes)
			(effects
				(font
					(size 1.27 1.27)
				)
			)
		)
		(property "Value" "BAS16H-GP"
			(at 0 -5.5372 90)
			(unlocked yes)
			(layer "F.Fab")
			(hide yes)
			(effects
				(font
					(size 1.016 1.016)
					(thickness 0.1524)
				)
			)
		)
		(property "Device Type" "SOD123AKH48"
			(at 0 -7.0612 90)
			(unlocked yes)
			(layer "F.Fab")
			(hide yes)
			(effects
				(font
					(size 1.016 1.016)
					(thickness 0.1524)
				)
			)
		)
		(duplicate_pad_numbers_are_jumpers no)
		(fp_line
			(start 1.016 -2.667)
			(end -1.016 -2.667)
			(stroke
				(width 0.1524)
				(type default)
			)
			(layer "F.SilkS")
		)
		(fp_line
			(start -1.016 -2.667)
			(end -1.016 2.667)
			(stroke
				(width 0.1524)
				(type default)
			)
			(layer "F.SilkS")
		)
		(fp_line
			(start 1.016 2.667)
			(end 1.016 -2.667)
			(stroke
				(width 0.1524)
				(type default)
			)
			(layer "F.SilkS")
		)
		(fp_line
			(start -1.016 2.667)
			(end 1.016 2.667)
			(stroke
				(width 0.1524)
				(type default)
			)
			(layer "F.SilkS")
		)
		(fp_line
			(start 0.889 2.921)
			(end -0.889 2.921)
			(stroke
				(width 0.508)
				(type default)
			)
			(layer "F.SilkS")
		)
		(fp_rect
			(start -1.143 3.175)
			(end 1.143 -2.794)
			(stroke
				(width 0)
				(type default)
			)
			(fill no)
			(layer "F.CrtYd")
		)
		(fp_poly
			(pts
				(xy -1.143 -2.794) (xy 1.143 -2.794) (xy 1.143 3.175) (xy -1.143 3.175)
			)
			(stroke
				(width 0)
				(type default)
			)
			(fill no)
			(layer "F.Fab")
		)
		(pad "A" smd rect
			(at 0 -1.6891 90)
			(size 0.889 1.397)
			(layers "F.Cu" "F.Mask" "F.Paste")
			(net "FAN_TACH6")
		)
		(pad "K" smd rect
			(at 0 1.6891 90)
			(size 0.889 1.397)
			(layers "F.Cu" "F.Mask" "F.Paste")
			(net "P12V")
		)
	)
	(footprint ""
		(layer "F.Cu")
		(at 14.8844 -46.5582 -90)
		(property "Reference" "R174"
			(at 0 0 270)
			(layer "F.SilkS")
			(hide yes)
			(effects
				(font
					(size 1.27 1.27)
				)
			)
		)
		(property "Value" "0R2J-2-GP"
			(at 0.064008 -3.993896 270)
			(unlocked yes)
			(layer "F.Fab")
			(hide yes)
			(effects
				(font
					(size 1.016 1.016)
					(thickness 0.1524)
				)
			)
		)
		(property "Device Type" "R402H16"
			(at 0.064008 -5.517896 270)
			(unlocked yes)
			(layer "F.Fab")
			(hide yes)
			(effects
				(font
					(size 1.016 1.016)
					(thickness 0.1524)
				)
			)
		)
		(duplicate_pad_numbers_are_jumpers no)
		(fp_line
			(start -0.508 -0.9398)
			(end -0.508 0.9398)
			(stroke
				(width 0.1524)
				(type default)
			)
			(layer "F.SilkS")
		)
		(fp_line
			(start 0.508 -0.9398)
			(end -0.508 -0.9398)
			(stroke
				(width 0.1524)
				(type default)
			)
			(layer "F.SilkS")
		)
		(fp_rect
			(start -0.508 0.9398)
			(end 0.508 -0.9398)
			(stroke
				(width 0)
				(type default)
			)
			(fill no)
			(layer "F.CrtYd")
		)
		(fp_rect
			(start -0.508 0.9398)
			(end 0.508 -0.9398)
			(stroke
				(width 0)
				(type default)
			)
			(fill no)
			(layer "F.Fab")
		)
		(pad "1" smd custom
			(at 0 -0.4445 270)
			(size 0.1397 0.1397)
			(layers "F.Cu" "F.Mask" "F.Paste")
			(net "SELF_2A_HB")
			(options
				(clearance outline)
				(anchor circle)
			)
			(primitives
				(gr_poly
					(pts
						(arc
							(start -0.1778 -0.2794)
							(mid -0.249642 -0.249642)
							(end -0.2794 -0.1778)
						)
						(arc
							(start -0.2794 0.1778)
							(mid -0.249642 0.249642)
							(end -0.1778 0.2794)
						)
						(arc
							(start 0.1778 0.2794)
							(mid 0.249642 0.249642)
							(end 0.2794 0.1778)
						)
						(arc
							(start 0.2794 -0.1778)
							(mid 0.249642 -0.249642)
							(end 0.1778 -0.2794)
						)
					)
					(width 0)
					(fill yes)
				)
			)
		)
		(pad "2" smd custom
			(at 0 0.4445 270)
			(size 0.1397 0.1397)
			(layers "F.Cu" "F.Mask" "F.Paste")
			(net "SEB_PEER_1A_HB")
			(options
				(clearance outline)
				(anchor circle)
			)
			(primitives
				(gr_poly
					(pts
						(arc
							(start -0.1778 -0.2794)
							(mid -0.249642 -0.249642)
							(end -0.2794 -0.1778)
						)
						(arc
							(start -0.2794 0.1778)
							(mid -0.249642 0.249642)
							(end -0.1778 0.2794)
						)
						(arc
							(start 0.1778 0.2794)
							(mid 0.249642 0.249642)
							(end 0.2794 0.1778)
						)
						(arc
							(start 0.2794 -0.1778)
							(mid 0.249642 -0.249642)
							(end 0.1778 -0.2794)
						)
					)
					(width 0)
					(fill yes)
				)
			)
		)
	)
	(footprint ""
		(layer "F.Cu")
		(at 14.7574 -262.2804 180)
		(property "Reference" "C35"
			(at 0 0 180)
			(layer "F.SilkS")
			(hide yes)
			(effects
				(font
					(size 1.27 1.27)
				)
			)
		)
		(property "Value" "SCD1U16V2KX-3GP"
			(at 1.1811 -2.7051 180)
			(unlocked yes)
			(layer "F.Fab")
			(hide yes)
			(effects
				(font
					(size 1.016 1.016)
					(thickness 0.1524)
				)
			)
		)
		(property "Device Type" "C402H22"
			(at 1.1811 -4.2291 180)
			(unlocked yes)
			(layer "F.Fab")
			(hide yes)
			(effects
				(font
					(size 1.016 1.016)
					(thickness 0.1524)
				)
			)
		)
		(duplicate_pad_numbers_are_jumpers no)
		(fp_rect
			(start -0.4318 0.9525)
			(end 0.4318 -0.9525)
			(stroke
				(width 0)
				(type default)
			)
			(fill no)
			(layer "F.CrtYd")
		)
		(fp_rect
			(start -0.4318 0.9525)
			(end 0.4318 -0.9525)
			(stroke
				(width 0)
				(type default)
			)
			(fill no)
			(layer "F.Fab")
		)
		(pad "1" smd custom
			(at 0 -0.4445 180)
			(size 0.1524 0.1524)
			(layers "F.Cu" "F.Mask" "F.Paste")
			(net "FAN_TACH6")
			(options
				(clearance outline)
				(anchor circle)
			)
			(primitives
				(gr_poly
					(pts
						(arc
							(start 0.3048 -0.2032)
							(mid 0.275042 -0.275042)
							(end 0.2032 -0.3048)
						)
						(arc
							(start -0.2032 -0.3048)
							(mid -0.275042 -0.275042)
							(end -0.3048 -0.2032)
						)
						(arc
							(start -0.3048 0.2032)
							(mid -0.275042 0.275042)
							(end -0.2032 0.3048)
						)
						(arc
							(start 0.2032 0.3048)
							(mid 0.275042 0.275042)
							(end 0.3048 0.2032)
						)
					)
					(width 0)
					(fill yes)
				)
			)
		)
		(pad "2" smd custom
			(at 0 0.4445 180)
			(size 0.1524 0.1524)
			(layers "F.Cu" "F.Mask" "F.Paste")
			(net "GND")
			(options
				(clearance outline)
				(anchor circle)
			)
			(primitives
				(gr_poly
					(pts
						(arc
							(start 0.3048 -0.2032)
							(mid 0.275042 -0.275042)
							(end 0.2032 -0.3048)
						)
						(arc
							(start -0.2032 -0.3048)
							(mid -0.275042 -0.275042)
							(end -0.3048 -0.2032)
						)
						(arc
							(start -0.3048 0.2032)
							(mid -0.275042 0.275042)
							(end -0.2032 0.3048)
						)
						(arc
							(start 0.2032 0.3048)
							(mid 0.275042 0.275042)
							(end 0.3048 0.2032)
						)
					)
					(width 0)
					(fill yes)
				)
			)
		)
	)
	(footprint ""
		(layer "F.Cu")
		(at 8.9662 -106.2482 -90)
		(property "Reference" "TC2"
			(at 0 0 270)
			(layer "F.SilkS")
			(hide yes)
			(effects
				(font
					(size 1.27 1.27)
				)
			)
		)
		(property "Value" "ST68U16VDM-1-GP"
			(at 0 -9.6012 270)
			(unlocked yes)
			(layer "F.Fab")
			(hide yes)
			(effects
				(font
					(size 1.016 1.016)
					(thickness 0.1524)
				)
			)
		)
		(property "Device Type" "CT7343H79"
			(at 0 -11.1252 270)
			(unlocked yes)
			(layer "F.Fab")
			(hide yes)
			(effects
				(font
					(size 1.016 1.016)
					(thickness 0.1524)
				)
			)
		)
		(duplicate_pad_numbers_are_jumpers no)
		(fp_line
			(start -2.286 4.8768)
			(end -2.286 2.032)
			(stroke
				(width 0.1524)
				(type default)
			)
			(layer "F.SilkS")
		)
		(fp_line
			(start 2.286 4.8768)
			(end -2.286 4.8768)
			(stroke
				(width 0.1524)
				(type default)
			)
			(layer "F.SilkS")
		)
		(fp_line
			(start 2.286 2.032)
			(end 2.286 4.8768)
			(stroke
				(width 0.1524)
				(type default)
			)
			(layer "F.SilkS")
		)
		(fp_line
			(start 2.286 -2.032)
			(end 2.286 -4.8768)
			(stroke
				(width 0.1524)
				(type default)
			)
			(layer "F.SilkS")
		)
		(fp_line
			(start 2.1082 -4.699)
			(end -2.1082 -4.699)
			(stroke
				(width 0.508)
				(type default)
			)
			(layer "F.SilkS")
		)
		(fp_line
			(start -2.286 -4.8768)
			(end -2.286 -2.032)
			(stroke
				(width 0.1524)
				(type default)
			)
			(layer "F.SilkS")
		)
		(fp_line
			(start 2.286 -4.8768)
			(end -2.286 -4.8768)
			(stroke
				(width 0.1524)
				(type default)
			)
			(layer "F.SilkS")
		)
		(fp_rect
			(start -2.1463 3.6449)
			(end 2.1463 -3.6449)
			(stroke
				(width 0)
				(type default)
			)
			(fill no)
			(layer "F.CrtYd")
		)
		(fp_poly
			(pts
				(xy -2.54 4.953) (xy -2.54 4.2926) (xy -3.81 4.2926) (xy -3.81 -4.2926) (xy -2.54 -4.2926) (xy -2.54 -4.953)
				(xy 2.54 -4.953) (xy 2.54 -4.2926) (xy 3.81 -4.2926) (xy 3.81 -1.6256) (xy 2.1463 -1.6256) (xy 2.1463 -3.6449)
				(xy -2.1463 -3.6449) (xy -2.1463 3.6449) (xy 2.1463 3.6449) (xy 2.1463 -1.6129) (xy 3.81 -1.6129)
				(xy 3.81 4.2926) (xy 2.54 4.2926) (xy 2.54 4.953)
			)
			(stroke
				(width 0)
				(type default)
			)
			(fill no)
			(layer "F.CrtYd")
		)
		(fp_rect
			(start -2.54 4.953)
			(end 2.54 -4.953)
			(stroke
				(width 0)
				(type default)
			)
			(fill no)
			(layer "F.Fab")
		)
		(fp_rect
			(start -3.81 4.2926)
			(end -2.54 -4.2926)
			(stroke
				(width 0)
				(type default)
			)
			(fill no)
			(layer "F.Fab")
		)
		(fp_rect
			(start 2.54 4.2926)
			(end 3.81 -4.2926)
			(stroke
				(width 0)
				(type default)
			)
			(fill no)
			(layer "F.Fab")
		)
		(pad "1" smd rect
			(at 0 -3.1496 270)
			(size 2.413 2.286)
			(layers "F.Cu" "F.Mask" "F.Paste")
			(net "P12VU")
		)
		(pad "2" smd rect
			(at 0 3.1496 270)
			(size 2.413 2.286)
			(layers "F.Cu" "F.Mask" "F.Paste")
			(net "GND")
		)
		(zone
			(layer "F.Cu")
			(hatch none 0.5)
			(connect_pads
				(clearance 0)
			)
			(min_thickness 0.25)
			(keepout
				(tracks allowed)
				(vias not_allowed)
				(pads allowed)
				(copperpour not_allowed)
				(footprints allowed)
			)
			(placement
				(enabled no)
				(sheetname "")
			)
			(fill
				(thermal_gap 0.5)
				(thermal_bridge_width 0.5)
				(island_removal_mode 0)
			)
			(polygon
				(pts
					(xy 4.3688 -107.7595) (xy 4.3688 -104.7369) (xy 7.2644 -104.7369) (xy 7.5946 -104.7369) (xy 7.5946 -107.7595)
					(xy 7.2644 -107.7595)
				)
			)
		)
		(zone
			(layer "F.Cu")
			(hatch none 0.5)
			(connect_pads
				(clearance 0)
			)
			(min_thickness 0.25)
			(keepout
				(tracks allowed)
				(vias not_allowed)
				(pads allowed)
				(copperpour not_allowed)
				(footprints allowed)
			)
			(placement
				(enabled no)
				(sheetname "")
			)
			(fill
				(thermal_gap 0.5)
				(thermal_bridge_width 0.5)
				(island_removal_mode 0)
			)
			(polygon
				(pts
					(xy 10.6553 -104.7369) (xy 13.5636 -104.7369) (xy 13.5636 -107.7595) (xy 10.668 -107.7595) (xy 10.3378 -107.7595)
					(xy 10.3378 -104.7369)
				)
			)
		)
	)
	(footprint ""
		(layer "F.Cu")
		(at 27.559 -217.780616)
		(property "Reference" "U7"
			(at 0 0 0)
			(layer "F.SilkS")
			(hide yes)
			(effects
				(font
					(size 1.27 1.27)
				)
			)
		)
		(property "Value" "TSLV07APWR-GP"
			(at -7.112 -6.0579 0)
			(unlocked yes)
			(layer "F.Fab")
			(hide yes)
			(effects
				(font
					(size 1.016 1.016)
					(thickness 0.1524)
				)
			)
		)
		(property "Device Type" "TSOIC14H48"
			(at -7.112 -7.5819 0)
			(unlocked yes)
			(layer "F.Fab")
			(hide yes)
			(effects
				(font
					(size 1.016 1.016)
					(thickness 0.1524)
				)
			)
		)
		(duplicate_pad_numbers_are_jumpers no)
		(fp_line
			(start -2.9718 -1.778)
			(end 2.1336 -1.778)
			(stroke
				(width 0.1524)
				(type default)
			)
			(layer "F.SilkS")
		)
		(fp_line
			(start -2.9718 1.778)
			(end -2.9718 -1.778)
			(stroke
				(width 0.1524)
				(type default)
			)
			(layer "F.SilkS")
		)
		(fp_line
			(start -2.9337 -0.4699)
			(end -2.9083 -0.4699)
			(stroke
				(width 0.1524)
				(type default)
			)
			(layer "F.SilkS")
		)
		(fp_line
			(start -2.9083 -0.4699)
			(end -2.4384 0)
			(stroke
				(width 0.1524)
				(type default)
			)
			(layer "F.SilkS")
		)
		(fp_line
			(start -2.8956 0.4572)
			(end -2.921 0.4572)
			(stroke
				(width 0.1524)
				(type default)
			)
			(layer "F.SilkS")
		)
		(fp_line
			(start -2.794 3.8227)
			(end -2.794 1.7018)
			(stroke
				(width 0.508)
				(type default)
			)
			(layer "F.SilkS")
		)
		(fp_line
			(start -2.4384 0)
			(end -2.8956 0.4572)
			(stroke
				(width 0.1524)
				(type default)
			)
			(layer "F.SilkS")
		)
		(fp_line
			(start 2.1336 -1.778)
			(end 2.1336 1.778)
			(stroke
				(width 0.1524)
				(type default)
			)
			(layer "F.SilkS")
		)
		(fp_line
			(start 2.1336 1.778)
			(end -2.9718 1.778)
			(stroke
				(width 0.1524)
				(type default)
			)
			(layer "F.SilkS")
		)
		(fp_poly
			(pts
				(xy -2.1336 -1.7653) (xy 2.1336 -1.7653) (xy 2.1336 1.778) (xy -2.1336 1.778)
			)
			(stroke
				(width 0)
				(type default)
			)
			(fill yes)
			(layer "F.SilkS")
		)
		(fp_rect
			(start -2.5019 3.2004)
			(end 2.5019 -3.2004)
			(stroke
				(width 0)
				(type default)
			)
			(fill no)
			(layer "F.CrtYd")
		)
		(fp_poly
			(pts
				(xy -3.048 4.0894) (xy -3.048 -2.5781) (xy -2.5019 -2.5781) (xy -2.5019 3.2004) (xy 2.5019 3.2004)
				(xy 2.5019 -3.2004) (xy -2.5019 -3.2004) (xy -2.5019 -2.5908) (xy -3.048 -2.5908) (xy -3.048 -4.0894)
				(xy 3.048 -4.0894) (xy 3.048 4.0894)
			)
			(stroke
				(width 0)
				(type default)
			)
			(fill no)
			(layer "F.CrtYd")
		)
		(fp_rect
			(start -3.048 4.0894)
			(end 3.048 -4.0894)
			(stroke
				(width 0)
				(type default)
			)
			(fill no)
			(layer "F.Fab")
		)
		(pad "1" smd rect
			(at -1.94945 2.8194)
			(size 0.3556 1.524)
			(layers "F.Cu" "F.Mask" "F.Paste")
			(net "PWM_BUFFER_IN_FAN5_FAN6")
		)
		(pad "2" smd rect
			(at -1.30048 2.8194)
			(size 0.3556 1.524)
			(layers "F.Cu" "F.Mask" "F.Paste")
			(net "PWM_OUT_FAN6")
		)
		(pad "3" smd rect
			(at -0.65024 2.8194)
			(size 0.3556 1.524)
			(layers "F.Cu" "F.Mask" "F.Paste")
			(net "PWM_BUFFER_IN_FAN5_FAN6")
		)
		(pad "4" smd rect
			(at 0 2.8194)
			(size 0.3556 1.524)
			(layers "F.Cu" "F.Mask" "F.Paste")
			(net "PWM_OUT_FAN5")
		)
		(pad "5" smd rect
			(at 0.65024 2.8194)
			(size 0.3556 1.524)
			(layers "F.Cu" "F.Mask" "F.Paste")
			(net "PWM_BUFFER_IN_FAN3_FAN4")
		)
		(pad "6" smd rect
			(at 1.30048 2.8194)
			(size 0.3556 1.524)
			(layers "F.Cu" "F.Mask" "F.Paste")
			(net "PWM_OUT_FAN4")
		)
		(pad "7" smd rect
			(at 1.94945 2.8194)
			(size 0.3556 1.524)
			(layers "F.Cu" "F.Mask" "F.Paste")
			(net "GND")
		)
		(pad "8" smd rect
			(at 1.94945 -2.8194)
			(size 0.3556 1.524)
			(layers "F.Cu" "F.Mask" "F.Paste")
			(net "PWM_OUT_FAN3")
		)
		(pad "9" smd rect
			(at 1.30048 -2.8194)
			(size 0.3556 1.524)
			(layers "F.Cu" "F.Mask" "F.Paste")
			(net "PWM_BUFFER_IN_FAN3_FAN4")
		)
		(pad "10" smd rect
			(at 0.65024 -2.8194)
			(size 0.3556 1.524)
			(layers "F.Cu" "F.Mask" "F.Paste")
			(net "PWM_OUT_FAN2")
		)
		(pad "11" smd rect
			(at 0 -2.8194)
			(size 0.3556 1.524)
			(layers "F.Cu" "F.Mask" "F.Paste")
			(net "PWM_BUFFER_IN_FAN1_FAN2")
		)
		(pad "12" smd rect
			(at -0.65024 -2.8194)
			(size 0.3556 1.524)
			(layers "F.Cu" "F.Mask" "F.Paste")
			(net "PWM_OUT_FAN1")
		)
		(pad "13" smd rect
			(at -1.30048 -2.8194)
			(size 0.3556 1.524)
			(layers "F.Cu" "F.Mask" "F.Paste")
			(net "PWM_BUFFER_IN_FAN1_FAN2")
		)
		(pad "14" smd rect
			(at -1.94945 -2.8194)
			(size 0.3556 1.524)
			(layers "F.Cu" "F.Mask" "F.Paste")
			(net "P3V3")
		)
	)
	(footprint ""
		(layer "F.Cu")
		(at 10.5664 -447.2686)
		(property "Reference" "D12"
			(at 0 0 0)
			(layer "F.SilkS")
			(hide yes)
			(effects
				(font
					(size 1.27 1.27)
				)
			)
		)
		(property "Value" "BAS16H-GP"
			(at 0 -5.5372 0)
			(unlocked yes)
			(layer "F.Fab")
			(hide yes)
			(effects
				(font
					(size 1.016 1.016)
					(thickness 0.1524)
				)
			)
		)
		(property "Device Type" "SOD123AKH48"
			(at 0 -7.0612 0)
			(unlocked yes)
			(layer "F.Fab")
			(hide yes)
			(effects
				(font
					(size 1.016 1.016)
					(thickness 0.1524)
				)
			)
		)
		(duplicate_pad_numbers_are_jumpers no)
		(fp_line
			(start -1.016 -2.667)
			(end -1.016 2.667)
			(stroke
				(width 0.1524)
				(type default)
			)
			(layer "F.SilkS")
		)
		(fp_line
			(start -1.016 2.667)
			(end 1.016 2.667)
			(stroke
				(width 0.1524)
				(type default)
			)
			(layer "F.SilkS")
		)
		(fp_line
			(start 0.889 2.921)
			(end -0.889 2.921)
			(stroke
				(width 0.508)
				(type default)
			)
			(layer "F.SilkS")
		)
		(fp_line
			(start 1.016 -2.667)
			(end -1.016 -2.667)
			(stroke
				(width 0.1524)
				(type default)
			)
			(layer "F.SilkS")
		)
		(fp_line
			(start 1.016 2.667)
			(end 1.016 -2.667)
			(stroke
				(width 0.1524)
				(type default)
			)
			(layer "F.SilkS")
		)
		(fp_rect
			(start -1.143 3.175)
			(end 1.143 -2.794)
			(stroke
				(width 0)
				(type default)
			)
			(fill no)
			(layer "F.CrtYd")
		)
		(fp_poly
			(pts
				(xy -1.143 -2.794) (xy 1.143 -2.794) (xy 1.143 3.175) (xy -1.143 3.175)
			)
			(stroke
				(width 0)
				(type default)
			)
			(fill no)
			(layer "F.Fab")
		)
		(pad "A" smd rect
			(at 0 -1.6891)
			(size 0.889 1.397)
			(layers "F.Cu" "F.Mask" "F.Paste")
			(net "FAN_TACH2")
		)
		(pad "K" smd rect
			(at 0 1.6891)
			(size 0.889 1.397)
			(layers "F.Cu" "F.Mask" "F.Paste")
			(net "P12V")
		)
	)
	(footprint ""
		(layer "F.Cu")
		(at 13.5636 -64.2112 -90)
		(property "Reference" "C56"
			(at 0 0 270)
			(layer "F.SilkS")
			(hide yes)
			(effects
				(font
					(size 1.27 1.27)
				)
			)
		)
		(property "Value" "SC220P50V3JN-GP"
			(at 0 -2.8194 270)
			(unlocked yes)
			(layer "F.Fab")
			(hide yes)
			(effects
				(font
					(size 1.016 1.016)
					(thickness 0.1524)
				)
			)
		)
		(property "Device Type" "C603H36"
			(at 0 -4.3434 270)
			(unlocked yes)
			(layer "F.Fab")
			(hide yes)
			(effects
				(font
					(size 1.016 1.016)
					(thickness 0.1524)
				)
			)
		)
		(duplicate_pad_numbers_are_jumpers no)
		(fp_line
			(start 0.508 0)
			(end -0.508 0)
			(stroke
				(width 0.2032)
				(type default)
			)
			(layer "F.SilkS")
		)
		(fp_rect
			(start -0.5842 1.3335)
			(end 0.5842 -1.3335)
			(stroke
				(width 0)
				(type default)
			)
			(fill no)
			(layer "F.CrtYd")
		)
		(fp_rect
			(start -0.5842 1.3335)
			(end 0.5842 -1.3335)
			(stroke
				(width 0)
				(type default)
			)
			(fill no)
			(layer "F.Fab")
		)
		(pad "1" smd custom
			(at 0 -0.762 270)
			(size 0.2159 0.2159)
			(layers "F.Cu" "F.Mask" "F.Paste")
			(net "I2C_C_SCL_CONN_R")
			(options
				(clearance outline)
				(anchor circle)
			)
			(primitives
				(gr_poly
					(pts
						(arc
							(start -0.3302 -0.4318)
							(mid -0.402042 -0.402042)
							(end -0.4318 -0.3302)
						)
						(arc
							(start -0.4318 0.3302)
							(mid -0.402042 0.402042)
							(end -0.3302 0.4318)
						)
						(arc
							(start 0.3302 0.4318)
							(mid 0.402042 0.402042)
							(end 0.4318 0.3302)
						)
						(arc
							(start 0.4318 -0.3302)
							(mid 0.402042 -0.402042)
							(end 0.3302 -0.4318)
						)
					)
					(width 0)
					(fill yes)
				)
			)
		)
		(pad "2" smd custom
			(at 0 0.762 270)
			(size 0.2159 0.2159)
			(layers "F.Cu" "F.Mask" "F.Paste")
			(net "GND")
			(options
				(clearance outline)
				(anchor circle)
			)
			(primitives
				(gr_poly
					(pts
						(arc
							(start -0.3302 -0.4318)
							(mid -0.402042 -0.402042)
							(end -0.4318 -0.3302)
						)
						(arc
							(start -0.4318 0.3302)
							(mid -0.402042 0.402042)
							(end -0.3302 0.4318)
						)
						(arc
							(start 0.3302 0.4318)
							(mid 0.402042 0.402042)
							(end 0.4318 0.3302)
						)
						(arc
							(start 0.4318 -0.3302)
							(mid 0.402042 -0.402042)
							(end 0.3302 -0.4318)
						)
					)
					(width 0)
					(fill yes)
				)
			)
		)
	)
	(footprint ""
		(layer "F.Cu")
		(at 34.739834 -139.324334 90)
		(property "Reference" "TP24"
			(at 0 0 90)
			(layer "F.SilkS")
			(hide yes)
			(effects
				(font
					(size 1.27 1.27)
				)
			)
		)
		(property "Value" "TPAD32-GP"
			(at 0 -3.166364 90)
			(unlocked yes)
			(layer "F.Fab")
			(hide yes)
			(effects
				(font
					(size 1.016 1.016)
					(thickness 0.1524)
				)
			)
		)
		(property "Device Type" "TPAD32"
			(at 0 -4.690618 90)
			(unlocked yes)
			(layer "F.Fab")
			(hide yes)
			(effects
				(font
					(size 1.016 1.016)
					(thickness 0.1524)
				)
			)
		)
		(duplicate_pad_numbers_are_jumpers no)
		(fp_poly
			(pts
				(arc
					(start 0 0.7112)
					(mid 0 -0.7112)
					(end 0 0.7112)
				)
			)
			(stroke
				(width 0)
				(type default)
			)
			(fill no)
			(layer "F.CrtYd")
		)
		(fp_poly
			(pts
				(arc
					(start 0 0.7112)
					(mid 0 -0.7112)
					(end 0 0.7112)
				)
			)
			(stroke
				(width 0)
				(type default)
			)
			(fill no)
			(layer "F.Fab")
		)
		(pad "1" smd circle
			(at 0 0 90)
			(size 0.8128 0.8128)
			(layers "F.Cu" "F.Mask" "F.Paste")
			(net "P12VL_2490_PG")
		)
	)
	(footprint ""
		(layer "F.Cu")
		(at 38.5826 -356.921816)
		(property "Reference" "PQ14"
			(at 0 0 0)
			(layer "F.SilkS")
			(hide yes)
			(effects
				(font
					(size 1.27 1.27)
				)
			)
		)
		(property "Value" "PMBS3904-1-GP"
			(at 0 -9.0932 0)
			(unlocked yes)
			(layer "F.Fab")
			(hide yes)
			(effects
				(font
					(size 1.016 1.016)
					(thickness 0.1524)
				)
			)
		)
		(property "Device Type" "SOT-23-10H44"
			(at 0 -10.6172 0)
			(unlocked yes)
			(layer "F.Fab")
			(hide yes)
			(effects
				(font
					(size 1.016 1.016)
					(thickness 0.1524)
				)
			)
		)
		(duplicate_pad_numbers_are_jumpers no)
		(fp_line
			(start -1.7526 1.8796)
			(end -1.7526 0.9906)
			(stroke
				(width 0.3302)
				(type default)
			)
			(layer "F.SilkS")
		)
		(fp_line
			(start -1.651 -1.778)
			(end -1.651 1.778)
			(stroke
				(width 0.1524)
				(type default)
			)
			(layer "F.SilkS")
		)
		(fp_line
			(start -1.651 1.778)
			(end 1.651 1.778)
			(stroke
				(width 0.1524)
				(type default)
			)
			(layer "F.SilkS")
		)
		(fp_line
			(start -1.279398 2.152142)
			(end -0.9906 1.86309)
			(stroke
				(width 0.0127)
				(type default)
			)
			(layer "F.SilkS")
		)
		(fp_line
			(start -1.279144 2.15265)
			(end -0.701294 2.15265)
			(stroke
				(width 0.0127)
				(type default)
			)
			(layer "F.SilkS")
		)
		(fp_line
			(start -1.260856 2.1336)
			(end -0.720344 2.1336)
			(stroke
				(width 0.0127)
				(type default)
			)
			(layer "F.SilkS")
		)
		(fp_line
			(start -1.251458 2.124202)
			(end -0.729996 2.124202)
			(stroke
				(width 0.0127)
				(type default)
			)
			(layer "F.SilkS")
		)
		(fp_line
			(start -1.241806 2.11455)
			(end -0.739394 2.11455)
			(stroke
				(width 0.0127)
				(type default)
			)
			(layer "F.SilkS")
		)
		(fp_line
			(start -1.232408 2.105152)
			(end -0.749046 2.105152)
			(stroke
				(width 0.0127)
				(type default)
			)
			(layer "F.SilkS")
		)
		(fp_line
			(start -1.222756 2.0955)
			(end -0.758444 2.0955)
			(stroke
				(width 0.0127)
				(type default)
			)
			(layer "F.SilkS")
		)
		(fp_line
			(start -1.213358 2.086102)
			(end -0.768096 2.086102)
			(stroke
				(width 0.0127)
				(type default)
			)
			(layer "F.SilkS")
		)
		(fp_line
			(start -1.203706 2.07645)
			(end -0.777494 2.07645)
			(stroke
				(width 0.0127)
				(type default)
			)
			(layer "F.SilkS")
		)
		(fp_line
			(start -1.194308 2.067052)
			(end -0.787146 2.067052)
			(stroke
				(width 0.0127)
				(type default)
			)
			(layer "F.SilkS")
		)
		(fp_line
			(start -1.184656 2.0574)
			(end -0.796544 2.0574)
			(stroke
				(width 0.0127)
				(type default)
			)
			(layer "F.SilkS")
		)
		(fp_line
			(start -1.175258 2.048002)
			(end -0.806196 2.048002)
			(stroke
				(width 0.0127)
				(type default)
			)
			(layer "F.SilkS")
		)
		(fp_line
			(start -1.165606 2.03835)
			(end -0.815594 2.03835)
			(stroke
				(width 0.0127)
				(type default)
			)
			(layer "F.SilkS")
		)
		(fp_line
			(start -1.156208 2.028952)
			(end -0.825246 2.028952)
			(stroke
				(width 0.0127)
				(type default)
			)
			(layer "F.SilkS")
		)
		(fp_line
			(start -1.146556 2.0193)
			(end -0.834644 2.0193)
			(stroke
				(width 0.0127)
				(type default)
			)
			(layer "F.SilkS")
		)
		(fp_line
			(start -1.137158 2.009902)
			(end -0.844296 2.009902)
			(stroke
				(width 0.0127)
				(type default)
			)
			(layer "F.SilkS")
		)
		(fp_line
			(start -1.127506 2.00025)
			(end -0.853694 2.00025)
			(stroke
				(width 0.0127)
				(type default)
			)
			(layer "F.SilkS")
		)
		(fp_line
			(start -1.118108 1.990852)
			(end -0.863346 1.990852)
			(stroke
				(width 0.0127)
				(type default)
			)
			(layer "F.SilkS")
		)
		(fp_line
			(start -1.108456 1.9812)
			(end -0.872744 1.9812)
			(stroke
				(width 0.0127)
				(type default)
			)
			(layer "F.SilkS")
		)
		(fp_line
			(start -1.099058 1.971802)
			(end -0.882396 1.971802)
			(stroke
				(width 0.0127)
				(type default)
			)
			(layer "F.SilkS")
		)
		(fp_line
			(start -1.089406 1.96215)
			(end -0.891794 1.96215)
			(stroke
				(width 0.0127)
				(type default)
			)
			(layer "F.SilkS")
		)
		(fp_line
			(start -1.080008 1.952752)
			(end -0.901446 1.952752)
			(stroke
				(width 0.0127)
				(type default)
			)
			(layer "F.SilkS")
		)
		(fp_line
			(start -1.070356 1.9431)
			(end -0.910844 1.9431)
			(stroke
				(width 0.0127)
				(type default)
			)
			(layer "F.SilkS")
		)
		(fp_line
			(start -1.060958 1.933702)
			(end -0.920496 1.933702)
			(stroke
				(width 0.0127)
				(type default)
			)
			(layer "F.SilkS")
		)
		(fp_line
			(start -1.051306 1.92405)
			(end -0.929894 1.92405)
			(stroke
				(width 0.0127)
				(type default)
			)
			(layer "F.SilkS")
		)
		(fp_line
			(start -1.041908 1.914652)
			(end -0.939546 1.914652)
			(stroke
				(width 0.0127)
				(type default)
			)
			(layer "F.SilkS")
		)
		(fp_line
			(start -1.032256 1.905)
			(end -0.948944 1.905)
			(stroke
				(width 0.0127)
				(type default)
			)
			(layer "F.SilkS")
		)
		(fp_line
			(start -1.022858 1.895602)
			(end -0.958596 1.895602)
			(stroke
				(width 0.0127)
				(type default)
			)
			(layer "F.SilkS")
		)
		(fp_line
			(start -1.013206 1.88595)
			(end -0.967994 1.88595)
			(stroke
				(width 0.0127)
				(type default)
			)
			(layer "F.SilkS")
		)
		(fp_line
			(start -1.003808 1.876552)
			(end -0.977646 1.876552)
			(stroke
				(width 0.0127)
				(type default)
			)
			(layer "F.SilkS")
		)
		(fp_line
			(start -0.994156 1.8669)
			(end -0.987044 1.8669)
			(stroke
				(width 0.0127)
				(type default)
			)
			(layer "F.SilkS")
		)
		(fp_line
			(start -0.9906 1.86309)
			(end -0.701294 2.15265)
			(stroke
				(width 0.0127)
				(type default)
			)
			(layer "F.SilkS")
		)
		(fp_line
			(start -0.719074 2.145538)
			(end -1.265936 2.14122)
			(stroke
				(width 0.0127)
				(type default)
			)
			(layer "F.SilkS")
		)
		(fp_line
			(start -0.71628 2.15265)
			(end -1.26492 2.15265)
			(stroke
				(width 0.0127)
				(type default)
			)
			(layer "F.SilkS")
		)
		(fp_line
			(start -0.635 1.8796)
			(end -1.7526 1.8796)
			(stroke
				(width 0.3302)
				(type default)
			)
			(layer "F.SilkS")
		)
		(fp_line
			(start 1.651 -1.778)
			(end -1.651 -1.778)
			(stroke
				(width 0.1524)
				(type default)
			)
			(layer "F.SilkS")
		)
		(fp_line
			(start 1.651 1.778)
			(end 1.651 -1.778)
			(stroke
				(width 0.1524)
				(type default)
			)
			(layer "F.SilkS")
		)
		(fp_poly
			(pts
				(xy -1.285748 2.159) (xy -1.285748 1.8796) (xy -1.778 1.8796) (xy -1.778 -1.8796) (xy 1.778 -1.8796)
				(xy 1.778 1.8796) (xy -0.694944 1.8796) (xy -0.694944 2.159)
			)
			(stroke
				(width 0)
				(type default)
			)
			(fill no)
			(layer "F.CrtYd")
		)
		(fp_poly
			(pts
				(xy -1.285748 2.159) (xy -1.285748 1.8796) (xy -1.778 1.8796) (xy -1.778 -1.8796) (xy 1.778 -1.8796)
				(xy 1.778 1.8796) (xy -0.694944 1.8796) (xy -0.694944 2.159)
			)
			(stroke
				(width 0)
				(type default)
			)
			(fill no)
			(layer "F.Fab")
		)
		(pad "1" smd rect
			(at -0.98425 0.9525)
			(size 0.762 1.143)
			(layers "F.Cu" "F.Mask" "F.Paste")
			(net "OTP_RETRY_B")
		)
		(pad "2" smd rect
			(at 0.98425 0.9525)
			(size 0.762 1.143)
			(layers "F.Cu" "F.Mask" "F.Paste")
			(net "GND")
		)
		(pad "3" smd rect
			(at 0 -0.9525)
			(size 0.762 1.143)
			(layers "F.Cu" "F.Mask" "F.Paste")
			(net "OTP_RETRY_C")
		)
	)
	(footprint ""
		(layer "F.Cu")
		(at 25.527 -361.188)
		(property "Reference" "PR9"
			(at 0 0 0)
			(layer "F.SilkS")
			(hide yes)
			(effects
				(font
					(size 1.27 1.27)
				)
			)
		)
		(property "Value" "0R2J-2-GP"
			(at 0.064008 -3.993896 0)
			(unlocked yes)
			(layer "F.Fab")
			(hide yes)
			(effects
				(font
					(size 1.016 1.016)
					(thickness 0.1524)
				)
			)
		)
		(property "Device Type" "R402H16"
			(at 0.064008 -5.517896 0)
			(unlocked yes)
			(layer "F.Fab")
			(hide yes)
			(effects
				(font
					(size 1.016 1.016)
					(thickness 0.1524)
				)
			)
		)
		(duplicate_pad_numbers_are_jumpers no)
		(fp_line
			(start -0.508 -0.9398)
			(end -0.508 0.9398)
			(stroke
				(width 0.1524)
				(type default)
			)
			(layer "F.SilkS")
		)
		(fp_line
			(start 0.508 -0.9398)
			(end -0.508 -0.9398)
			(stroke
				(width 0.1524)
				(type default)
			)
			(layer "F.SilkS")
		)
		(fp_rect
			(start -0.508 0.9398)
			(end 0.508 -0.9398)
			(stroke
				(width 0)
				(type default)
			)
			(fill no)
			(layer "F.CrtYd")
		)
		(fp_rect
			(start -0.508 0.9398)
			(end 0.508 -0.9398)
			(stroke
				(width 0)
				(type default)
			)
			(fill no)
			(layer "F.Fab")
		)
		(pad "1" smd custom
			(at 0 -0.4445)
			(size 0.1397 0.1397)
			(layers "F.Cu" "F.Mask" "F.Paste")
			(net "ADM1276_LATCH#")
			(options
				(clearance outline)
				(anchor circle)
			)
			(primitives
				(gr_poly
					(pts
						(arc
							(start -0.1778 -0.2794)
							(mid -0.249642 -0.249642)
							(end -0.2794 -0.1778)
						)
						(arc
							(start -0.2794 0.1778)
							(mid -0.249642 0.249642)
							(end -0.1778 0.2794)
						)
						(arc
							(start 0.1778 0.2794)
							(mid 0.249642 0.249642)
							(end 0.2794 0.1778)
						)
						(arc
							(start 0.2794 -0.1778)
							(mid 0.249642 -0.249642)
							(end 0.1778 -0.2794)
						)
					)
					(width 0)
					(fill yes)
				)
			)
		)
		(pad "2" smd custom
			(at 0 0.4445)
			(size 0.1397 0.1397)
			(layers "F.Cu" "F.Mask" "F.Paste")
			(net "ADM1276_UV")
			(options
				(clearance outline)
				(anchor circle)
			)
			(primitives
				(gr_poly
					(pts
						(arc
							(start -0.1778 -0.2794)
							(mid -0.249642 -0.249642)
							(end -0.2794 -0.1778)
						)
						(arc
							(start -0.2794 0.1778)
							(mid -0.249642 0.249642)
							(end -0.1778 0.2794)
						)
						(arc
							(start 0.1778 0.2794)
							(mid 0.249642 0.249642)
							(end 0.2794 0.1778)
						)
						(arc
							(start 0.2794 -0.1778)
							(mid 0.249642 -0.249642)
							(end 0.1778 -0.2794)
						)
					)
					(width 0)
					(fill yes)
				)
			)
		)
	)
	(footprint ""
		(layer "F.Cu")
		(at 18.237708 -13.905738)
		(property "Reference" "C29"
			(at 0 0 0)
			(layer "F.SilkS")
			(hide yes)
			(effects
				(font
					(size 1.27 1.27)
				)
			)
		)
		(property "Value" "SCD1U16V2KX-3GP"
			(at 1.1811 -2.7051 0)
			(unlocked yes)
			(layer "F.Fab")
			(hide yes)
			(effects
				(font
					(size 1.016 1.016)
					(thickness 0.1524)
				)
			)
		)
		(property "Device Type" "C402H22"
			(at 1.1811 -4.2291 0)
			(unlocked yes)
			(layer "F.Fab")
			(hide yes)
			(effects
				(font
					(size 1.016 1.016)
					(thickness 0.1524)
				)
			)
		)
		(duplicate_pad_numbers_are_jumpers no)
		(fp_rect
			(start -0.4318 0.9525)
			(end 0.4318 -0.9525)
			(stroke
				(width 0)
				(type default)
			)
			(fill no)
			(layer "F.CrtYd")
		)
		(fp_rect
			(start -0.4318 0.9525)
			(end 0.4318 -0.9525)
			(stroke
				(width 0)
				(type default)
			)
			(fill no)
			(layer "F.Fab")
		)
		(pad "1" smd custom
			(at 0 -0.4445)
			(size 0.1524 0.1524)
			(layers "F.Cu" "F.Mask" "F.Paste")
			(net "FAN_TACH11")
			(options
				(clearance outline)
				(anchor circle)
			)
			(primitives
				(gr_poly
					(pts
						(arc
							(start 0.3048 -0.2032)
							(mid 0.275042 -0.275042)
							(end 0.2032 -0.3048)
						)
						(arc
							(start -0.2032 -0.3048)
							(mid -0.275042 -0.275042)
							(end -0.3048 -0.2032)
						)
						(arc
							(start -0.3048 0.2032)
							(mid -0.275042 0.275042)
							(end -0.2032 0.3048)
						)
						(arc
							(start 0.2032 0.3048)
							(mid 0.275042 0.275042)
							(end 0.3048 0.2032)
						)
					)
					(width 0)
					(fill yes)
				)
			)
		)
		(pad "2" smd custom
			(at 0 0.4445)
			(size 0.1524 0.1524)
			(layers "F.Cu" "F.Mask" "F.Paste")
			(net "GND")
			(options
				(clearance outline)
				(anchor circle)
			)
			(primitives
				(gr_poly
					(pts
						(arc
							(start 0.3048 -0.2032)
							(mid 0.275042 -0.275042)
							(end 0.2032 -0.3048)
						)
						(arc
							(start -0.2032 -0.3048)
							(mid -0.275042 -0.275042)
							(end -0.3048 -0.2032)
						)
						(arc
							(start -0.3048 0.2032)
							(mid -0.275042 0.275042)
							(end -0.2032 0.3048)
						)
						(arc
							(start 0.2032 0.3048)
							(mid 0.275042 0.275042)
							(end 0.3048 0.2032)
						)
					)
					(width 0)
					(fill yes)
				)
			)
		)
	)
	(footprint ""
		(layer "F.Cu")
		(at 17.63649 -172.175424 180)
		(property "Reference" "U3"
			(at 0 0 180)
			(layer "F.SilkS")
			(hide yes)
			(effects
				(font
					(size 1.27 1.27)
				)
			)
		)
		(property "Value" "74LVC1G32GW-1GP"
			(at -2.3368 -8.6868 180)
			(unlocked yes)
			(layer "F.Fab")
			(hide yes)
			(effects
				(font
					(size 1.016 1.016)
					(thickness 0.1524)
				)
			)
		)
		(property "Device Type" "SC70-5H44"
			(at -2.3114 -10.414 180)
			(unlocked yes)
			(layer "F.Fab")
			(hide yes)
			(effects
				(font
					(size 1.016 1.016)
					(thickness 0.1524)
				)
			)
		)
		(duplicate_pad_numbers_are_jumpers no)
		(fp_line
			(start 1.3843 -1.8034)
			(end 1.3843 -1.1176)
			(stroke
				(width 0.3302)
				(type default)
			)
			(layer "F.SilkS")
		)
		(fp_line
			(start 1.27 1.7018)
			(end -1.27 1.7018)
			(stroke
				(width 0.1524)
				(type default)
			)
			(layer "F.SilkS")
		)
		(fp_line
			(start 1.27 -1.7018)
			(end 1.27 1.7018)
			(stroke
				(width 0.1524)
				(type default)
			)
			(layer "F.SilkS")
		)
		(fp_line
			(start 0.6604 -1.8034)
			(end 1.3843 -1.8034)
			(stroke
				(width 0.3302)
				(type default)
			)
			(layer "F.SilkS")
		)
		(fp_line
			(start -1.27 1.7018)
			(end -1.27 -1.7018)
			(stroke
				(width 0.1524)
				(type default)
			)
			(layer "F.SilkS")
		)
		(fp_line
			(start -1.27 -1.7018)
			(end 1.27 -1.7018)
			(stroke
				(width 0.1524)
				(type default)
			)
			(layer "F.SilkS")
		)
		(fp_rect
			(start -1.524 1.9558)
			(end 1.524 -1.9558)
			(stroke
				(width 0)
				(type default)
			)
			(fill no)
			(layer "F.CrtYd")
		)
		(fp_poly
			(pts
				(xy -1.524 -1.9558) (xy 1.524 -1.9558) (xy 1.524 1.9558) (xy -1.524 1.9558)
			)
			(stroke
				(width 0)
				(type default)
			)
			(fill no)
			(layer "F.Fab")
		)
		(pad "1" smd rect
			(at 0.65024 -0.8255 180)
			(size 0.4064 1.2192)
			(layers "F.Cu" "F.Mask" "F.Paste")
			(net "SEB_PEER_1A_1B_HB_OUT")
		)
		(pad "2" smd rect
			(at 0 -0.8255 180)
			(size 0.4064 1.2192)
			(layers "F.Cu" "F.Mask" "F.Paste")
			(net "SEB_PEER_2A_2B_HB_OUT")
		)
		(pad "3" smd rect
			(at -0.65024 -0.8255 180)
			(size 0.4064 1.2192)
			(layers "F.Cu" "F.Mask" "F.Paste")
			(net "GND")
		)
		(pad "4" smd rect
			(at -0.65024 0.8255 180)
			(size 0.4064 1.2192)
			(layers "F.Cu" "F.Mask" "F.Paste")
			(net "THERMHOT#_R")
		)
		(pad "5" smd rect
			(at 0.65024 0.8255 180)
			(size 0.4064 1.2192)
			(layers "F.Cu" "F.Mask" "F.Paste")
			(net "P3V3")
		)
	)
	(footprint ""
		(layer "F.Cu")
		(at 31.242 -361.315 180)
		(property "Reference" "R109"
			(at 0 0 180)
			(layer "F.SilkS")
			(hide yes)
			(effects
				(font
					(size 1.27 1.27)
				)
			)
		)
		(property "Value" "0R2J-2-GP"
			(at 0.064008 -3.993896 180)
			(unlocked yes)
			(layer "F.Fab")
			(hide yes)
			(effects
				(font
					(size 1.016 1.016)
					(thickness 0.1524)
				)
			)
		)
		(property "Device Type" "R402H16"
			(at 0.064008 -5.517896 180)
			(unlocked yes)
			(layer "F.Fab")
			(hide yes)
			(effects
				(font
					(size 1.016 1.016)
					(thickness 0.1524)
				)
			)
		)
		(duplicate_pad_numbers_are_jumpers no)
		(fp_line
			(start 0.508 -0.9398)
			(end -0.508 -0.9398)
			(stroke
				(width 0.1524)
				(type default)
			)
			(layer "F.SilkS")
		)
		(fp_line
			(start -0.508 -0.9398)
			(end -0.508 0.9398)
			(stroke
				(width 0.1524)
				(type default)
			)
			(layer "F.SilkS")
		)
		(fp_rect
			(start -0.508 0.9398)
			(end 0.508 -0.9398)
			(stroke
				(width 0)
				(type default)
			)
			(fill no)
			(layer "F.CrtYd")
		)
		(fp_rect
			(start -0.508 0.9398)
			(end 0.508 -0.9398)
			(stroke
				(width 0)
				(type default)
			)
			(fill no)
			(layer "F.Fab")
		)
		(pad "1" smd custom
			(at 0 -0.4445 180)
			(size 0.1397 0.1397)
			(layers "F.Cu" "F.Mask" "F.Paste")
			(net "I2C_C_SDA")
			(options
				(clearance outline)
				(anchor circle)
			)
			(primitives
				(gr_poly
					(pts
						(arc
							(start -0.1778 -0.2794)
							(mid -0.249642 -0.249642)
							(end -0.2794 -0.1778)
						)
						(arc
							(start -0.2794 0.1778)
							(mid -0.249642 0.249642)
							(end -0.1778 0.2794)
						)
						(arc
							(start 0.1778 0.2794)
							(mid 0.249642 0.249642)
							(end 0.2794 0.1778)
						)
						(arc
							(start 0.2794 -0.1778)
							(mid 0.249642 -0.249642)
							(end 0.1778 -0.2794)
						)
					)
					(width 0)
					(fill yes)
				)
			)
		)
		(pad "2" smd custom
			(at 0 0.4445 180)
			(size 0.1397 0.1397)
			(layers "F.Cu" "F.Mask" "F.Paste")
			(net "I2C_C_SDA_ADM1276")
			(options
				(clearance outline)
				(anchor circle)
			)
			(primitives
				(gr_poly
					(pts
						(arc
							(start -0.1778 -0.2794)
							(mid -0.249642 -0.249642)
							(end -0.2794 -0.1778)
						)
						(arc
							(start -0.2794 0.1778)
							(mid -0.249642 0.249642)
							(end -0.1778 0.2794)
						)
						(arc
							(start 0.1778 0.2794)
							(mid 0.249642 0.249642)
							(end 0.2794 0.1778)
						)
						(arc
							(start 0.2794 -0.1778)
							(mid 0.249642 -0.249642)
							(end 0.1778 -0.2794)
						)
					)
					(width 0)
					(fill yes)
				)
			)
		)
	)
	(footprint ""
		(layer "F.Cu")
		(at 36.740338 -477.189292 90)
		(property "Reference" "C50"
			(at 0 0 90)
			(layer "F.SilkS")
			(hide yes)
			(effects
				(font
					(size 1.27 1.27)
				)
			)
		)
		(property "Value" "SC1U25V3KX-1-GP"
			(at 0 -2.8194 90)
			(unlocked yes)
			(layer "F.Fab")
			(hide yes)
			(effects
				(font
					(size 1.016 1.016)
					(thickness 0.1524)
				)
			)
		)
		(property "Device Type" "C603H36"
			(at 0 -4.3434 90)
			(unlocked yes)
			(layer "F.Fab")
			(hide yes)
			(effects
				(font
					(size 1.016 1.016)
					(thickness 0.1524)
				)
			)
		)
		(duplicate_pad_numbers_are_jumpers no)
		(fp_line
			(start 0.508 0)
			(end -0.508 0)
			(stroke
				(width 0.2032)
				(type default)
			)
			(layer "F.SilkS")
		)
		(fp_rect
			(start -0.5842 1.3335)
			(end 0.5842 -1.3335)
			(stroke
				(width 0)
				(type default)
			)
			(fill no)
			(layer "F.CrtYd")
		)
		(fp_rect
			(start -0.5842 1.3335)
			(end 0.5842 -1.3335)
			(stroke
				(width 0)
				(type default)
			)
			(fill no)
			(layer "F.Fab")
		)
		(pad "1" smd custom
			(at 0 -0.762 90)
			(size 0.2159 0.2159)
			(layers "F.Cu" "F.Mask" "F.Paste")
			(net "P12V")
			(options
				(clearance outline)
				(anchor circle)
			)
			(primitives
				(gr_poly
					(pts
						(arc
							(start -0.3302 -0.4318)
							(mid -0.402042 -0.402042)
							(end -0.4318 -0.3302)
						)
						(arc
							(start -0.4318 0.3302)
							(mid -0.402042 0.402042)
							(end -0.3302 0.4318)
						)
						(arc
							(start 0.3302 0.4318)
							(mid 0.402042 0.402042)
							(end 0.4318 0.3302)
						)
						(arc
							(start 0.4318 -0.3302)
							(mid 0.402042 -0.402042)
							(end 0.3302 -0.4318)
						)
					)
					(width 0)
					(fill yes)
				)
			)
		)
		(pad "2" smd custom
			(at 0 0.762 90)
			(size 0.2159 0.2159)
			(layers "F.Cu" "F.Mask" "F.Paste")
			(net "GND")
			(options
				(clearance outline)
				(anchor circle)
			)
			(primitives
				(gr_poly
					(pts
						(arc
							(start -0.3302 -0.4318)
							(mid -0.402042 -0.402042)
							(end -0.4318 -0.3302)
						)
						(arc
							(start -0.4318 0.3302)
							(mid -0.402042 0.402042)
							(end -0.3302 0.4318)
						)
						(arc
							(start 0.3302 0.4318)
							(mid 0.402042 0.402042)
							(end 0.4318 0.3302)
						)
						(arc
							(start 0.4318 -0.3302)
							(mid 0.402042 -0.402042)
							(end 0.3302 -0.4318)
						)
					)
					(width 0)
					(fill yes)
				)
			)
		)
	)
	(footprint ""
		(layer "F.Cu")
		(at 20.7264 -26.162 90)
		(property "Reference" "R182"
			(at 0 0 90)
			(layer "F.SilkS")
			(hide yes)
			(effects
				(font
					(size 1.27 1.27)
				)
			)
		)
		(property "Value" "0R1206-PAD-1-GP"
			(at 0 -5.0292 90)
			(unlocked yes)
			(layer "F.Fab")
			(hide yes)
			(effects
				(font
					(size 1.016 1.016)
					(thickness 0.1524)
				)
			)
		)
		(property "Device Type" "0R1206-PAD-1"
			(at 0 -6.5532 90)
			(unlocked yes)
			(layer "F.Fab")
			(hide yes)
			(effects
				(font
					(size 1.016 1.016)
					(thickness 0.1524)
				)
			)
		)
		(duplicate_pad_numbers_are_jumpers no)
		(fp_line
			(start 1.016 -2.2352)
			(end -1.016 -2.2352)
			(stroke
				(width 0.1524)
				(type default)
			)
			(layer "F.SilkS")
		)
		(fp_line
			(start -1.016 -2.2352)
			(end -1.016 2.2352)
			(stroke
				(width 0.1524)
				(type default)
			)
			(layer "F.SilkS")
		)
		(fp_line
			(start 1.016 2.2352)
			(end 1.016 -2.2352)
			(stroke
				(width 0.1524)
				(type default)
			)
			(layer "F.SilkS")
		)
		(fp_line
			(start -1.016 2.2352)
			(end 1.016 2.2352)
			(stroke
				(width 0.1524)
				(type default)
			)
			(layer "F.SilkS")
		)
		(fp_rect
			(start -1.0922 2.3114)
			(end 1.0922 -2.3114)
			(stroke
				(width 0)
				(type default)
			)
			(fill no)
			(layer "F.CrtYd")
		)
		(fp_poly
			(pts
				(xy -1.0922 -2.3114) (xy 1.0922 -2.3114) (xy 1.0922 2.3114) (xy -1.0922 2.3114)
			)
			(stroke
				(width 0)
				(type default)
			)
			(fill no)
			(layer "F.Fab")
		)
		(pad "1" smd rect
			(at 0 -1.397 90)
			(size 1.651 2.0574)
			(drill
				(offset 0 0.3937)
			)
			(layers "F.Cu" "F.Mask" "F.Paste")
			(net "P12V_FAN6")
		)
		(pad "2" smd rect
			(at 0 1.397 90)
			(size 1.651 2.0574)
			(drill
				(offset 0 -0.3937)
			)
			(layers "F.Cu" "F.Mask" "F.Paste")
			(net "P12V")
		)
	)
	(footprint ""
		(layer "F.Cu")
		(at 16.4592 -260.35 -90)
		(property "Reference" "R84"
			(at 0 0 270)
			(layer "F.SilkS")
			(hide yes)
			(effects
				(font
					(size 1.27 1.27)
				)
			)
		)
		(property "Value" "27KR3F-GP"
			(at -0.0254 -2.5146 270)
			(unlocked yes)
			(layer "F.Fab")
			(hide yes)
			(effects
				(font
					(size 1.016 1.016)
					(thickness 0.1524)
				)
			)
		)
		(property "Device Type" "R603H22"
			(at -0.0254 -4.0386 270)
			(unlocked yes)
			(layer "F.Fab")
			(hide yes)
			(effects
				(font
					(size 1.016 1.016)
					(thickness 0.1524)
				)
			)
		)
		(duplicate_pad_numbers_are_jumpers no)
		(fp_line
			(start -0.4826 0)
			(end -0.2032 0)
			(stroke
				(width 0.2032)
				(type default)
			)
			(layer "F.SilkS")
		)
		(fp_line
			(start 0.2032 0)
			(end 0.4826 0)
			(stroke
				(width 0.2032)
				(type default)
			)
			(layer "F.SilkS")
		)
		(fp_rect
			(start -0.5842 1.3335)
			(end 0.5842 -1.3335)
			(stroke
				(width 0)
				(type default)
			)
			(fill no)
			(layer "F.CrtYd")
		)
		(fp_rect
			(start -0.5842 1.3335)
			(end 0.5842 -1.3335)
			(stroke
				(width 0)
				(type default)
			)
			(fill no)
			(layer "F.Fab")
		)
		(pad "1" smd custom
			(at 0 -0.762 270)
			(size 0.2159 0.2159)
			(layers "F.Cu" "F.Mask" "F.Paste")
			(net "FAN_TACH6")
			(options
				(clearance outline)
				(anchor circle)
			)
			(primitives
				(gr_poly
					(pts
						(arc
							(start -0.3302 -0.4318)
							(mid -0.402042 -0.402042)
							(end -0.4318 -0.3302)
						)
						(arc
							(start -0.4318 0.3302)
							(mid -0.402042 0.402042)
							(end -0.3302 0.4318)
						)
						(arc
							(start 0.3302 0.4318)
							(mid 0.402042 0.402042)
							(end 0.4318 0.3302)
						)
						(arc
							(start 0.4318 -0.3302)
							(mid 0.402042 -0.402042)
							(end 0.3302 -0.4318)
						)
					)
					(width 0)
					(fill yes)
				)
			)
		)
		(pad "2" smd custom
			(at 0 0.762 270)
			(size 0.2159 0.2159)
			(layers "F.Cu" "F.Mask" "F.Paste")
			(net "FANIN_6")
			(options
				(clearance outline)
				(anchor circle)
			)
			(primitives
				(gr_poly
					(pts
						(arc
							(start -0.3302 -0.4318)
							(mid -0.402042 -0.402042)
							(end -0.4318 -0.3302)
						)
						(arc
							(start -0.4318 0.3302)
							(mid -0.402042 0.402042)
							(end -0.3302 0.4318)
						)
						(arc
							(start 0.3302 0.4318)
							(mid 0.402042 0.402042)
							(end 0.4318 0.3302)
						)
						(arc
							(start 0.4318 -0.3302)
							(mid 0.402042 -0.402042)
							(end 0.3302 -0.4318)
						)
					)
					(width 0)
					(fill yes)
				)
			)
		)
	)
	(footprint ""
		(layer "F.Cu")
		(at 23.614634 -156.80309 -90)
		(property "Reference" "TP16"
			(at 0 0 270)
			(layer "F.SilkS")
			(hide yes)
			(effects
				(font
					(size 1.27 1.27)
				)
			)
		)
		(property "Value" "TPAD32-GP"
			(at 0 -3.166364 270)
			(unlocked yes)
			(layer "F.Fab")
			(hide yes)
			(effects
				(font
					(size 1.016 1.016)
					(thickness 0.1524)
				)
			)
		)
		(property "Device Type" "TPAD32"
			(at 0 -4.690618 270)
			(unlocked yes)
			(layer "F.Fab")
			(hide yes)
			(effects
				(font
					(size 1.016 1.016)
					(thickness 0.1524)
				)
			)
		)
		(duplicate_pad_numbers_are_jumpers no)
		(fp_poly
			(pts
				(arc
					(start 0.7112 0)
					(mid -0.7112 0)
					(end 0.7112 0)
				)
			)
			(stroke
				(width 0)
				(type default)
			)
			(fill no)
			(layer "F.CrtYd")
		)
		(fp_poly
			(pts
				(arc
					(start 0.7112 0)
					(mid -0.7112 0)
					(end 0.7112 0)
				)
			)
			(stroke
				(width 0)
				(type default)
			)
			(fill no)
			(layer "F.Fab")
		)
		(pad "1" smd circle
			(at 0 0 270)
			(size 0.8128 0.8128)
			(layers "F.Cu" "F.Mask" "F.Paste")
			(net "NCT7904_LED")
		)
	)
	(footprint ""
		(layer "F.Cu")
		(at 20.3454 -245.4148 -90)
		(property "Reference" "PC41"
			(at 0 0 270)
			(layer "F.SilkS")
			(hide yes)
			(effects
				(font
					(size 1.27 1.27)
				)
			)
		)
		(property "Value" "SCD1U16V2KX-3GP"
			(at 1.1811 -2.7051 270)
			(unlocked yes)
			(layer "F.Fab")
			(hide yes)
			(effects
				(font
					(size 1.016 1.016)
					(thickness 0.1524)
				)
			)
		)
		(property "Device Type" "C402H22"
			(at 1.1811 -4.2291 270)
			(unlocked yes)
			(layer "F.Fab")
			(hide yes)
			(effects
				(font
					(size 1.016 1.016)
					(thickness 0.1524)
				)
			)
		)
		(duplicate_pad_numbers_are_jumpers no)
		(fp_rect
			(start -0.4318 0.9525)
			(end 0.4318 -0.9525)
			(stroke
				(width 0)
				(type default)
			)
			(fill no)
			(layer "F.CrtYd")
		)
		(fp_rect
			(start -0.4318 0.9525)
			(end 0.4318 -0.9525)
			(stroke
				(width 0)
				(type default)
			)
			(fill no)
			(layer "F.Fab")
		)
		(pad "1" smd custom
			(at 0 -0.4445 270)
			(size 0.1524 0.1524)
			(layers "F.Cu" "F.Mask" "F.Paste")
			(net "P3V3_BS_NET")
			(options
				(clearance outline)
				(anchor circle)
			)
			(primitives
				(gr_poly
					(pts
						(arc
							(start 0.3048 -0.2032)
							(mid 0.275042 -0.275042)
							(end 0.2032 -0.3048)
						)
						(arc
							(start -0.2032 -0.3048)
							(mid -0.275042 -0.275042)
							(end -0.3048 -0.2032)
						)
						(arc
							(start -0.3048 0.2032)
							(mid -0.275042 0.275042)
							(end -0.2032 0.3048)
						)
						(arc
							(start 0.2032 0.3048)
							(mid 0.275042 0.275042)
							(end 0.3048 0.2032)
						)
					)
					(width 0)
					(fill yes)
				)
			)
		)
		(pad "2" smd custom
			(at 0 0.4445 270)
			(size 0.1524 0.1524)
			(layers "F.Cu" "F.Mask" "F.Paste")
			(net "P3V3_LX")
			(options
				(clearance outline)
				(anchor circle)
			)
			(primitives
				(gr_poly
					(pts
						(arc
							(start 0.3048 -0.2032)
							(mid 0.275042 -0.275042)
							(end 0.2032 -0.3048)
						)
						(arc
							(start -0.2032 -0.3048)
							(mid -0.275042 -0.275042)
							(end -0.3048 -0.2032)
						)
						(arc
							(start -0.3048 0.2032)
							(mid -0.275042 0.275042)
							(end -0.2032 0.3048)
						)
						(arc
							(start 0.2032 0.3048)
							(mid 0.275042 0.275042)
							(end 0.3048 0.2032)
						)
					)
					(width 0)
					(fill yes)
				)
			)
		)
	)
	(footprint ""
		(layer "F.Cu")
		(at 17.526 -16.129 -90)
		(property "Reference" "R65"
			(at 0 0 270)
			(layer "F.SilkS")
			(hide yes)
			(effects
				(font
					(size 1.27 1.27)
				)
			)
		)
		(property "Value" "4K7R2F-GP"
			(at 0.064008 -3.993896 270)
			(unlocked yes)
			(layer "F.Fab")
			(hide yes)
			(effects
				(font
					(size 1.016 1.016)
					(thickness 0.1524)
				)
			)
		)
		(property "Device Type" "R402H16"
			(at 0.064008 -5.517896 270)
			(unlocked yes)
			(layer "F.Fab")
			(hide yes)
			(effects
				(font
					(size 1.016 1.016)
					(thickness 0.1524)
				)
			)
		)
		(duplicate_pad_numbers_are_jumpers no)
		(fp_line
			(start -0.508 -0.9398)
			(end -0.508 0.9398)
			(stroke
				(width 0.1524)
				(type default)
			)
			(layer "F.SilkS")
		)
		(fp_line
			(start 0.508 -0.9398)
			(end -0.508 -0.9398)
			(stroke
				(width 0.1524)
				(type default)
			)
			(layer "F.SilkS")
		)
		(fp_rect
			(start -0.508 0.9398)
			(end 0.508 -0.9398)
			(stroke
				(width 0)
				(type default)
			)
			(fill no)
			(layer "F.CrtYd")
		)
		(fp_rect
			(start -0.508 0.9398)
			(end 0.508 -0.9398)
			(stroke
				(width 0)
				(type default)
			)
			(fill no)
			(layer "F.Fab")
		)
		(pad "1" smd custom
			(at 0 -0.4445 270)
			(size 0.1397 0.1397)
			(layers "F.Cu" "F.Mask" "F.Paste")
			(net "P12V")
			(options
				(clearance outline)
				(anchor circle)
			)
			(primitives
				(gr_poly
					(pts
						(arc
							(start -0.1778 -0.2794)
							(mid -0.249642 -0.249642)
							(end -0.2794 -0.1778)
						)
						(arc
							(start -0.2794 0.1778)
							(mid -0.249642 0.249642)
							(end -0.1778 0.2794)
						)
						(arc
							(start 0.1778 0.2794)
							(mid 0.249642 0.249642)
							(end 0.2794 0.1778)
						)
						(arc
							(start 0.2794 -0.1778)
							(mid 0.249642 -0.249642)
							(end 0.1778 -0.2794)
						)
					)
					(width 0)
					(fill yes)
				)
			)
		)
		(pad "2" smd custom
			(at 0 0.4445 270)
			(size 0.1397 0.1397)
			(layers "F.Cu" "F.Mask" "F.Paste")
			(net "PWM_OUT_FAN6_NET")
			(options
				(clearance outline)
				(anchor circle)
			)
			(primitives
				(gr_poly
					(pts
						(arc
							(start -0.1778 -0.2794)
							(mid -0.249642 -0.249642)
							(end -0.2794 -0.1778)
						)
						(arc
							(start -0.2794 0.1778)
							(mid -0.249642 0.249642)
							(end -0.1778 0.2794)
						)
						(arc
							(start 0.1778 0.2794)
							(mid 0.249642 0.249642)
							(end 0.2794 0.1778)
						)
						(arc
							(start 0.2794 -0.1778)
							(mid 0.249642 -0.249642)
							(end 0.1778 -0.2794)
						)
					)
					(width 0)
					(fill yes)
				)
			)
		)
	)
	(footprint ""
		(layer "F.Cu")
		(at 21.336 -375.285 -90)
		(property "Reference" "PC10"
			(at 0 0 270)
			(layer "F.SilkS")
			(hide yes)
			(effects
				(font
					(size 1.27 1.27)
				)
			)
		)
		(property "Value" "SC1U25V5KX-1GP"
			(at -0.0762 -6.1214 270)
			(unlocked yes)
			(layer "F.Fab")
			(hide yes)
			(effects
				(font
					(size 1.016 1.016)
					(thickness 0.1524)
				)
			)
		)
		(property "Device Type" "C805H58"
			(at -0.0762 -8.1534 270)
			(unlocked yes)
			(layer "F.Fab")
			(hide yes)
			(effects
				(font
					(size 1.016 1.016)
					(thickness 0.1524)
				)
			)
		)
		(duplicate_pad_numbers_are_jumpers no)
		(fp_line
			(start 0.635 0)
			(end -0.635 0)
			(stroke
				(width 0.508)
				(type default)
			)
			(layer "F.SilkS")
		)
		(fp_rect
			(start -0.9652 1.778)
			(end 0.9652 -1.778)
			(stroke
				(width 0)
				(type default)
			)
			(fill no)
			(layer "F.CrtYd")
		)
		(fp_poly
			(pts
				(xy -0.9652 -1.778) (xy 0.9652 -1.778) (xy 0.9652 1.778) (xy -0.9652 1.778)
			)
			(stroke
				(width 0)
				(type default)
			)
			(fill no)
			(layer "F.Fab")
		)
		(pad "1" smd rect
			(at 0 -0.9652 270)
			(size 1.397 1.143)
			(layers "F.Cu" "F.Mask" "F.Paste")
			(net "ADM1276_UV")
		)
		(pad "2" smd rect
			(at 0 0.9652 270)
			(size 1.397 1.143)
			(layers "F.Cu" "F.Mask" "F.Paste")
			(net "GND")
		)
	)
	(footprint ""
		(layer "F.Cu")
		(at 14.8844 -47.5742 -90)
		(property "Reference" "R185"
			(at 0 0 270)
			(layer "F.SilkS")
			(hide yes)
			(effects
				(font
					(size 1.27 1.27)
				)
			)
		)
		(property "Value" "0R2J-2-GP"
			(at 0.064008 -3.993896 270)
			(unlocked yes)
			(layer "F.Fab")
			(hide yes)
			(effects
				(font
					(size 1.016 1.016)
					(thickness 0.1524)
				)
			)
		)
		(property "Device Type" "R402H16"
			(at 0.064008 -5.517896 270)
			(unlocked yes)
			(layer "F.Fab")
			(hide yes)
			(effects
				(font
					(size 1.016 1.016)
					(thickness 0.1524)
				)
			)
		)
		(duplicate_pad_numbers_are_jumpers no)
		(fp_line
			(start -0.508 -0.9398)
			(end -0.508 0.9398)
			(stroke
				(width 0.1524)
				(type default)
			)
			(layer "F.SilkS")
		)
		(fp_line
			(start 0.508 -0.9398)
			(end -0.508 -0.9398)
			(stroke
				(width 0.1524)
				(type default)
			)
			(layer "F.SilkS")
		)
		(fp_rect
			(start -0.508 0.9398)
			(end 0.508 -0.9398)
			(stroke
				(width 0)
				(type default)
			)
			(fill no)
			(layer "F.CrtYd")
		)
		(fp_rect
			(start -0.508 0.9398)
			(end 0.508 -0.9398)
			(stroke
				(width 0)
				(type default)
			)
			(fill no)
			(layer "F.Fab")
		)
		(pad "1" smd custom
			(at 0 -0.4445 270)
			(size 0.1397 0.1397)
			(layers "F.Cu" "F.Mask" "F.Paste")
			(net "SD_LATCH_RELEASE_L")
			(options
				(clearance outline)
				(anchor circle)
			)
			(primitives
				(gr_poly
					(pts
						(arc
							(start -0.1778 -0.2794)
							(mid -0.249642 -0.249642)
							(end -0.2794 -0.1778)
						)
						(arc
							(start -0.2794 0.1778)
							(mid -0.249642 0.249642)
							(end -0.1778 0.2794)
						)
						(arc
							(start 0.1778 0.2794)
							(mid 0.249642 0.249642)
							(end 0.2794 0.1778)
						)
						(arc
							(start 0.2794 -0.1778)
							(mid 0.249642 -0.249642)
							(end 0.1778 -0.2794)
						)
					)
					(width 0)
					(fill yes)
				)
			)
		)
		(pad "2" smd custom
			(at 0 0.4445 270)
			(size 0.1397 0.1397)
			(layers "F.Cu" "F.Mask" "F.Paste")
			(net "D_LATCH_PRE#")
			(options
				(clearance outline)
				(anchor circle)
			)
			(primitives
				(gr_poly
					(pts
						(arc
							(start -0.1778 -0.2794)
							(mid -0.249642 -0.249642)
							(end -0.2794 -0.1778)
						)
						(arc
							(start -0.2794 0.1778)
							(mid -0.249642 0.249642)
							(end -0.1778 0.2794)
						)
						(arc
							(start 0.1778 0.2794)
							(mid 0.249642 0.249642)
							(end 0.2794 0.1778)
						)
						(arc
							(start 0.2794 -0.1778)
							(mid 0.249642 -0.249642)
							(end 0.1778 -0.2794)
						)
					)
					(width 0)
					(fill yes)
				)
			)
		)
	)
	(footprint ""
		(layer "F.Cu")
		(at 34.544 -240.3094 180)
		(property "Reference" "R55"
			(at 0 0 180)
			(layer "F.SilkS")
			(hide yes)
			(effects
				(font
					(size 1.27 1.27)
				)
			)
		)
		(property "Value" "4K7R2J-2-GP"
			(at 0.064008 -3.993896 180)
			(unlocked yes)
			(layer "F.Fab")
			(hide yes)
			(effects
				(font
					(size 1.016 1.016)
					(thickness 0.1524)
				)
			)
		)
		(property "Device Type" "R402H16"
			(at 0.064008 -5.517896 180)
			(unlocked yes)
			(layer "F.Fab")
			(hide yes)
			(effects
				(font
					(size 1.016 1.016)
					(thickness 0.1524)
				)
			)
		)
		(duplicate_pad_numbers_are_jumpers no)
		(fp_line
			(start 0.508 -0.9398)
			(end -0.508 -0.9398)
			(stroke
				(width 0.1524)
				(type default)
			)
			(layer "F.SilkS")
		)
		(fp_line
			(start -0.508 -0.9398)
			(end -0.508 0.9398)
			(stroke
				(width 0.1524)
				(type default)
			)
			(layer "F.SilkS")
		)
		(fp_rect
			(start -0.508 0.9398)
			(end 0.508 -0.9398)
			(stroke
				(width 0)
				(type default)
			)
			(fill no)
			(layer "F.CrtYd")
		)
		(fp_rect
			(start -0.508 0.9398)
			(end 0.508 -0.9398)
			(stroke
				(width 0)
				(type default)
			)
			(fill no)
			(layer "F.Fab")
		)
		(pad "1" smd custom
			(at 0 -0.4445 180)
			(size 0.1397 0.1397)
			(layers "F.Cu" "F.Mask" "F.Paste")
			(net "GND")
			(options
				(clearance outline)
				(anchor circle)
			)
			(primitives
				(gr_poly
					(pts
						(arc
							(start -0.1778 -0.2794)
							(mid -0.249642 -0.249642)
							(end -0.2794 -0.1778)
						)
						(arc
							(start -0.2794 0.1778)
							(mid -0.249642 0.249642)
							(end -0.1778 0.2794)
						)
						(arc
							(start 0.1778 0.2794)
							(mid 0.249642 0.249642)
							(end 0.2794 0.1778)
						)
						(arc
							(start 0.2794 -0.1778)
							(mid 0.249642 -0.249642)
							(end 0.1778 -0.2794)
						)
					)
					(width 0)
					(fill yes)
				)
			)
		)
		(pad "2" smd custom
			(at 0 0.4445 180)
			(size 0.1397 0.1397)
			(layers "F.Cu" "F.Mask" "F.Paste")
			(net "LED_DRV_A1")
			(options
				(clearance outline)
				(anchor circle)
			)
			(primitives
				(gr_poly
					(pts
						(arc
							(start -0.1778 -0.2794)
							(mid -0.249642 -0.249642)
							(end -0.2794 -0.1778)
						)
						(arc
							(start -0.2794 0.1778)
							(mid -0.249642 0.249642)
							(end -0.1778 0.2794)
						)
						(arc
							(start 0.1778 0.2794)
							(mid 0.249642 0.249642)
							(end 0.2794 0.1778)
						)
						(arc
							(start 0.2794 -0.1778)
							(mid 0.249642 -0.249642)
							(end 0.1778 -0.2794)
						)
					)
					(width 0)
					(fill yes)
				)
			)
		)
	)
	(footprint ""
		(layer "F.Cu")
		(at 18.7706 -141.5034 180)
		(property "Reference" "PR106"
			(at 0 0 180)
			(layer "F.SilkS")
			(hide yes)
			(effects
				(font
					(size 1.27 1.27)
				)
			)
		)
		(property "Value" "1KR2F-3-GP"
			(at 0.064008 -3.993896 180)
			(unlocked yes)
			(layer "F.Fab")
			(hide yes)
			(effects
				(font
					(size 1.016 1.016)
					(thickness 0.1524)
				)
			)
		)
		(property "Device Type" "R402H16"
			(at 0.064008 -5.517896 180)
			(unlocked yes)
			(layer "F.Fab")
			(hide yes)
			(effects
				(font
					(size 1.016 1.016)
					(thickness 0.1524)
				)
			)
		)
		(duplicate_pad_numbers_are_jumpers no)
		(fp_line
			(start 0.508 -0.9398)
			(end -0.508 -0.9398)
			(stroke
				(width 0.1524)
				(type default)
			)
			(layer "F.SilkS")
		)
		(fp_line
			(start -0.508 -0.9398)
			(end -0.508 0.9398)
			(stroke
				(width 0.1524)
				(type default)
			)
			(layer "F.SilkS")
		)
		(fp_rect
			(start -0.508 0.9398)
			(end 0.508 -0.9398)
			(stroke
				(width 0)
				(type default)
			)
			(fill no)
			(layer "F.CrtYd")
		)
		(fp_rect
			(start -0.508 0.9398)
			(end 0.508 -0.9398)
			(stroke
				(width 0)
				(type default)
			)
			(fill no)
			(layer "F.Fab")
		)
		(pad "1" smd custom
			(at 0 -0.4445 180)
			(size 0.1397 0.1397)
			(layers "F.Cu" "F.Mask" "F.Paste")
			(net "P12VU_2490_PG")
			(options
				(clearance outline)
				(anchor circle)
			)
			(primitives
				(gr_poly
					(pts
						(arc
							(start -0.1778 -0.2794)
							(mid -0.249642 -0.249642)
							(end -0.2794 -0.1778)
						)
						(arc
							(start -0.2794 0.1778)
							(mid -0.249642 0.249642)
							(end -0.1778 0.2794)
						)
						(arc
							(start 0.1778 0.2794)
							(mid 0.249642 0.249642)
							(end 0.2794 0.1778)
						)
						(arc
							(start 0.2794 -0.1778)
							(mid 0.249642 -0.249642)
							(end 0.1778 -0.2794)
						)
					)
					(width 0)
					(fill yes)
				)
			)
		)
		(pad "2" smd custom
			(at 0 0.4445 180)
			(size 0.1397 0.1397)
			(layers "F.Cu" "F.Mask" "F.Paste")
			(net "GND")
			(options
				(clearance outline)
				(anchor circle)
			)
			(primitives
				(gr_poly
					(pts
						(arc
							(start -0.1778 -0.2794)
							(mid -0.249642 -0.249642)
							(end -0.2794 -0.1778)
						)
						(arc
							(start -0.2794 0.1778)
							(mid -0.249642 0.249642)
							(end -0.1778 0.2794)
						)
						(arc
							(start 0.1778 0.2794)
							(mid 0.249642 0.249642)
							(end 0.2794 0.1778)
						)
						(arc
							(start 0.2794 -0.1778)
							(mid 0.249642 -0.249642)
							(end 0.1778 -0.2794)
						)
					)
					(width 0)
					(fill yes)
				)
			)
		)
	)
	(footprint ""
		(layer "F.Cu")
		(at 4.040124 -127.340106 -90)
		(property "Reference" "CN5"
			(at 0 0 270)
			(layer "F.SilkS")
			(hide yes)
			(effects
				(font
					(size 1.27 1.27)
				)
			)
		)
		(property "Value" "JWT-CON5-42-GP"
			(at -7.8105 2.9591 270)
			(unlocked yes)
			(layer "F.Fab")
			(hide yes)
			(effects
				(font
					(size 1.016 1.016)
					(thickness 0.1524)
				)
			)
		)
		(property "Device Type" "A2541WR0-1TX5PA-6T-0E"
			(at -7.8105 1.4351 270)
			(unlocked yes)
			(layer "F.Fab")
			(hide yes)
			(effects
				(font
					(size 1.016 1.016)
					(thickness 0.1524)
				)
			)
		)
		(duplicate_pad_numbers_are_jumpers no)
		(fp_line
			(start -6.604 10.287)
			(end 6.604 10.287)
			(stroke
				(width 0.1524)
				(type default)
			)
			(layer "F.SilkS")
		)
		(fp_line
			(start 6.604 10.287)
			(end 6.604 -0.9652)
			(stroke
				(width 0.1524)
				(type default)
			)
			(layer "F.SilkS")
		)
		(fp_line
			(start -6.604 -0.9652)
			(end -6.604 10.287)
			(stroke
				(width 0.1524)
				(type default)
			)
			(layer "F.SilkS")
		)
		(fp_line
			(start 6.604 -0.9652)
			(end -6.604 -0.9652)
			(stroke
				(width 0.1524)
				(type default)
			)
			(layer "F.SilkS")
		)
		(fp_line
			(start -6.731 -1.0922)
			(end -6.731 0.1778)
			(stroke
				(width 0.4064)
				(type default)
			)
			(layer "F.SilkS")
		)
		(fp_line
			(start -5.461 -1.0922)
			(end -6.731 -1.0922)
			(stroke
				(width 0.4064)
				(type default)
			)
			(layer "F.SilkS")
		)
		(fp_circle
			(center -5.08 0)
			(end -5.08 -1.0668)
			(stroke
				(width 0.3048)
				(type default)
			)
			(fill no)
			(layer "F.SilkS")
		)
		(fp_circle
			(center -2.54 0)
			(end -2.54 -1.0668)
			(stroke
				(width 0.3048)
				(type default)
			)
			(fill no)
			(layer "F.SilkS")
		)
		(fp_circle
			(center 0 0)
			(end 0 -1.0668)
			(stroke
				(width 0.3048)
				(type default)
			)
			(fill no)
			(layer "F.SilkS")
		)
		(fp_circle
			(center 2.54 0)
			(end 2.54 -1.0668)
			(stroke
				(width 0.3048)
				(type default)
			)
			(fill no)
			(layer "F.SilkS")
		)
		(fp_circle
			(center 5.08 0)
			(end 5.08 -1.0668)
			(stroke
				(width 0.3048)
				(type default)
			)
			(fill no)
			(layer "F.SilkS")
		)
		(fp_rect
			(start -6.35 10.033)
			(end 6.35 -0.3302)
			(stroke
				(width 0)
				(type default)
			)
			(fill no)
			(layer "F.CrtYd")
		)
		(fp_poly
			(pts
				(xy -6.35 -0.3302) (xy 6.858 -0.3302) (xy 6.858 -1.2192) (xy -6.858 -1.2192) (xy -6.858 10.541)
				(xy 6.858 10.541) (xy 6.858 -0.3175) (xy 6.35 -0.3175) (xy 6.35 10.033) (xy -6.35 10.033)
			)
			(stroke
				(width 0)
				(type default)
			)
			(fill no)
			(layer "F.CrtYd")
		)
		(fp_rect
			(start -6.858 10.541)
			(end 6.858 -1.2192)
			(stroke
				(width 0)
				(type default)
			)
			(fill no)
			(layer "F.Fab")
		)
		(pad "1" thru_hole circle
			(at -5.08 0 270)
			(size 1.4224 1.4224)
			(drill 1.016)
			(layers "*.Cu" "*.Mask")
			(remove_unused_layers no)
			(net "GND")
			(clearance 0.1524)
			(thermal_gap 0.1524)
		)
		(pad "2" thru_hole circle
			(at -2.54 0 270)
			(size 1.4224 1.4224)
			(drill 1.016)
			(layers "*.Cu" "*.Mask")
			(remove_unused_layers no)
			(net "P12V_FAN5")
			(clearance 0.1524)
			(thermal_gap 0.1524)
		)
		(pad "3" thru_hole circle
			(at 0 0 270)
			(size 1.4224 1.4224)
			(drill 1.016)
			(layers "*.Cu" "*.Mask")
			(remove_unused_layers no)
			(net "FAN_TACH10")
			(clearance 0.1524)
			(thermal_gap 0.1524)
		)
		(pad "4" thru_hole circle
			(at 2.54 0 270)
			(size 1.4224 1.4224)
			(drill 1.016)
			(layers "*.Cu" "*.Mask")
			(remove_unused_layers no)
			(net "PWM_OUT_FAN5_NET")
			(clearance 0.1524)
			(thermal_gap 0.1524)
		)
		(pad "5" thru_hole circle
			(at 5.08 0 270)
			(size 1.4224 1.4224)
			(drill 1.016)
			(layers "*.Cu" "*.Mask")
			(remove_unused_layers no)
			(net "FAN_TACH9")
			(clearance 0.1524)
			(thermal_gap 0.1524)
		)
	)
	(footprint ""
		(layer "F.Cu")
		(at 22.860762 -15.621508 90)
		(property "Reference" "R77"
			(at 0 0 90)
			(layer "F.SilkS")
			(hide yes)
			(effects
				(font
					(size 1.27 1.27)
				)
			)
		)
		(property "Value" "10KR2F-2-GP"
			(at 0.064008 -3.993896 90)
			(unlocked yes)
			(layer "F.Fab")
			(hide yes)
			(effects
				(font
					(size 1.016 1.016)
					(thickness 0.1524)
				)
			)
		)
		(property "Device Type" "R402H16"
			(at 0.064008 -5.517896 90)
			(unlocked yes)
			(layer "F.Fab")
			(hide yes)
			(effects
				(font
					(size 1.016 1.016)
					(thickness 0.1524)
				)
			)
		)
		(duplicate_pad_numbers_are_jumpers no)
		(fp_line
			(start 0.508 -0.9398)
			(end -0.508 -0.9398)
			(stroke
				(width 0.1524)
				(type default)
			)
			(layer "F.SilkS")
		)
		(fp_line
			(start -0.508 -0.9398)
			(end -0.508 0.9398)
			(stroke
				(width 0.1524)
				(type default)
			)
			(layer "F.SilkS")
		)
		(fp_rect
			(start -0.508 0.9398)
			(end 0.508 -0.9398)
			(stroke
				(width 0)
				(type default)
			)
			(fill no)
			(layer "F.CrtYd")
		)
		(fp_rect
			(start -0.508 0.9398)
			(end 0.508 -0.9398)
			(stroke
				(width 0)
				(type default)
			)
			(fill no)
			(layer "F.Fab")
		)
		(pad "1" smd custom
			(at 0 -0.4445 90)
			(size 0.1397 0.1397)
			(layers "F.Cu" "F.Mask" "F.Paste")
			(net "FANIN_11")
			(options
				(clearance outline)
				(anchor circle)
			)
			(primitives
				(gr_poly
					(pts
						(arc
							(start -0.1778 -0.2794)
							(mid -0.249642 -0.249642)
							(end -0.2794 -0.1778)
						)
						(arc
							(start -0.2794 0.1778)
							(mid -0.249642 0.249642)
							(end -0.1778 0.2794)
						)
						(arc
							(start 0.1778 0.2794)
							(mid 0.249642 0.249642)
							(end 0.2794 0.1778)
						)
						(arc
							(start 0.2794 -0.1778)
							(mid 0.249642 -0.249642)
							(end 0.1778 -0.2794)
						)
					)
					(width 0)
					(fill yes)
				)
			)
		)
		(pad "2" smd custom
			(at 0 0.4445 90)
			(size 0.1397 0.1397)
			(layers "F.Cu" "F.Mask" "F.Paste")
			(net "GND")
			(options
				(clearance outline)
				(anchor circle)
			)
			(primitives
				(gr_poly
					(pts
						(arc
							(start -0.1778 -0.2794)
							(mid -0.249642 -0.249642)
							(end -0.2794 -0.1778)
						)
						(arc
							(start -0.2794 0.1778)
							(mid -0.249642 0.249642)
							(end -0.1778 0.2794)
						)
						(arc
							(start 0.1778 0.2794)
							(mid 0.249642 0.249642)
							(end 0.2794 0.1778)
						)
						(arc
							(start 0.2794 -0.1778)
							(mid 0.249642 -0.249642)
							(end 0.1778 -0.2794)
						)
					)
					(width 0)
					(fill yes)
				)
			)
		)
	)
	(footprint ""
		(layer "F.Cu")
		(at 26.289 -151.3078)
		(property "Reference" "C5"
			(at 0 0 0)
			(layer "F.SilkS")
			(hide yes)
			(effects
				(font
					(size 1.27 1.27)
				)
			)
		)
		(property "Value" "SCD1U16V2KX-3GP"
			(at 1.1811 -2.7051 0)
			(unlocked yes)
			(layer "F.Fab")
			(hide yes)
			(effects
				(font
					(size 1.016 1.016)
					(thickness 0.1524)
				)
			)
		)
		(property "Device Type" "C402H22"
			(at 1.1811 -4.2291 0)
			(unlocked yes)
			(layer "F.Fab")
			(hide yes)
			(effects
				(font
					(size 1.016 1.016)
					(thickness 0.1524)
				)
			)
		)
		(duplicate_pad_numbers_are_jumpers no)
		(fp_rect
			(start -0.4318 0.9525)
			(end 0.4318 -0.9525)
			(stroke
				(width 0)
				(type default)
			)
			(fill no)
			(layer "F.CrtYd")
		)
		(fp_rect
			(start -0.4318 0.9525)
			(end 0.4318 -0.9525)
			(stroke
				(width 0)
				(type default)
			)
			(fill no)
			(layer "F.Fab")
		)
		(pad "1" smd custom
			(at 0 -0.4445)
			(size 0.1524 0.1524)
			(layers "F.Cu" "F.Mask" "F.Paste")
			(net "NCT7904_VREF")
			(options
				(clearance outline)
				(anchor circle)
			)
			(primitives
				(gr_poly
					(pts
						(arc
							(start 0.3048 -0.2032)
							(mid 0.275042 -0.275042)
							(end 0.2032 -0.3048)
						)
						(arc
							(start -0.2032 -0.3048)
							(mid -0.275042 -0.275042)
							(end -0.3048 -0.2032)
						)
						(arc
							(start -0.3048 0.2032)
							(mid -0.275042 0.275042)
							(end -0.2032 0.3048)
						)
						(arc
							(start 0.2032 0.3048)
							(mid 0.275042 0.275042)
							(end 0.3048 0.2032)
						)
					)
					(width 0)
					(fill yes)
				)
			)
		)
		(pad "2" smd custom
			(at 0 0.4445)
			(size 0.1524 0.1524)
			(layers "F.Cu" "F.Mask" "F.Paste")
			(net "GND")
			(options
				(clearance outline)
				(anchor circle)
			)
			(primitives
				(gr_poly
					(pts
						(arc
							(start 0.3048 -0.2032)
							(mid 0.275042 -0.275042)
							(end 0.2032 -0.3048)
						)
						(arc
							(start -0.2032 -0.3048)
							(mid -0.275042 -0.275042)
							(end -0.3048 -0.2032)
						)
						(arc
							(start -0.3048 0.2032)
							(mid -0.275042 0.275042)
							(end -0.2032 0.3048)
						)
						(arc
							(start 0.2032 0.3048)
							(mid 0.275042 0.275042)
							(end 0.3048 0.2032)
						)
					)
					(width 0)
					(fill yes)
				)
			)
		)
	)
	(footprint ""
		(layer "B.Cu")
		(at 40.999918 -463.049874 90)
		(property "Reference" "H11"
			(at 0 0 90)
			(layer "B.SilkS")
			(hide yes)
			(effects
				(font
					(size 1.27 1.27)
				)
				(justify mirror)
			)
		)
		(property "Value" "STF375R199H50-GP"
			(at 6.124702 -0.033274 90)
			(unlocked yes)
			(layer "B.Fab")
			(hide yes)
			(effects
				(font
					(size 1.016 1.016)
					(thickness 0.1524)
				)
				(justify mirror)
			)
		)
		(property "Device Type" "STF375R199H50"
			(at 6.124702 -1.557274 90)
			(unlocked yes)
			(layer "B.Fab")
			(hide yes)
			(effects
				(font
					(size 1.016 1.016)
					(thickness 0.1524)
				)
				(justify mirror)
			)
		)
		(duplicate_pad_numbers_are_jumpers no)
		(fp_circle
			(center 0 0)
			(end 0 5.1181)
			(stroke
				(width 0.3048)
				(type default)
			)
			(fill no)
			(layer "B.SilkS")
		)
		(fp_poly
			(pts
				(arc
					(start 0 4.0005)
					(mid 0 -4.0005)
					(end 0 4.0005)
				)
			)
			(stroke
				(width 0)
				(type default)
			)
			(fill no)
			(layer "B.CrtYd")
		)
		(fp_poly
			(pts
				(arc
					(start -5.2705 0.00254)
					(mid 5.270501 0)
					(end -5.2705 -0.00254)
				)
				(arc
					(start -4.0005 -0.00254)
					(mid 4.000501 0)
					(end -4.0005 0.00254)
				)
			)
			(stroke
				(width 0)
				(type default)
			)
			(fill no)
			(layer "B.CrtYd")
		)
		(fp_poly
			(pts
				(arc
					(start 0 5.2705)
					(mid 0 -5.2705)
					(end 0 5.2705)
				)
			)
			(stroke
				(width 0)
				(type default)
			)
			(fill no)
			(layer "F.CrtYd")
		)
		(fp_poly
			(pts
				(arc
					(start 0 5.2705)
					(mid 0 -5.2705)
					(end 0 5.2705)
				)
			)
			(stroke
				(width 0)
				(type default)
			)
			(fill no)
			(layer "B.Fab")
		)
		(fp_poly
			(pts
				(arc
					(start 0 5.2705)
					(mid 0 -5.2705)
					(end 0 5.2705)
				)
			)
			(stroke
				(width 0)
				(type default)
			)
			(fill no)
			(layer "F.Fab")
		)
		(pad "1" thru_hole circle
			(at 0 0 270)
			(size 9.525 9.525)
			(drill 5.0546)
			(layers "*.Cu" "*.Mask")
			(remove_unused_layers no)
			(net "GND")
			(clearance -1.7272)
			(padstack
				(mode front_inner_back)
				(layer "Inner"
					(shape circle)
					(size 5.461 5.461)
					(clearance 0.3048)
				)
				(layer "B.Cu"
					(shape circle)
					(size 9.525 9.525)
					(thermal_gap 0.3048)
					(clearance -1.7272)
				)
			)
		)
	)
	(footprint ""
		(layer "B.Cu")
		(at 40.999918 -443.95009 90)
		(property "Reference" "H12"
			(at 0 0 90)
			(layer "B.SilkS")
			(hide yes)
			(effects
				(font
					(size 1.27 1.27)
				)
				(justify mirror)
			)
		)
		(property "Value" "STF375R199H50-GP"
			(at 6.124702 -0.033274 90)
			(unlocked yes)
			(layer "B.Fab")
			(hide yes)
			(effects
				(font
					(size 1.016 1.016)
					(thickness 0.1524)
				)
				(justify mirror)
			)
		)
		(property "Device Type" "STF375R199H50"
			(at 6.124702 -1.557274 90)
			(unlocked yes)
			(layer "B.Fab")
			(hide yes)
			(effects
				(font
					(size 1.016 1.016)
					(thickness 0.1524)
				)
				(justify mirror)
			)
		)
		(duplicate_pad_numbers_are_jumpers no)
		(fp_circle
			(center 0 0)
			(end 0 5.1181)
			(stroke
				(width 0.3048)
				(type default)
			)
			(fill no)
			(layer "B.SilkS")
		)
		(fp_poly
			(pts
				(arc
					(start 0 4.0005)
					(mid 0 -4.0005)
					(end 0 4.0005)
				)
			)
			(stroke
				(width 0)
				(type default)
			)
			(fill no)
			(layer "B.CrtYd")
		)
		(fp_poly
			(pts
				(arc
					(start -5.2705 0.00254)
					(mid 5.270501 0)
					(end -5.2705 -0.00254)
				)
				(arc
					(start -4.0005 -0.00254)
					(mid 4.000501 0)
					(end -4.0005 0.00254)
				)
			)
			(stroke
				(width 0)
				(type default)
			)
			(fill no)
			(layer "B.CrtYd")
		)
		(fp_poly
			(pts
				(arc
					(start 0 5.2705)
					(mid 0 -5.2705)
					(end 0 5.2705)
				)
			)
			(stroke
				(width 0)
				(type default)
			)
			(fill no)
			(layer "F.CrtYd")
		)
		(fp_poly
			(pts
				(arc
					(start 0 5.2705)
					(mid 0 -5.2705)
					(end 0 5.2705)
				)
			)
			(stroke
				(width 0)
				(type default)
			)
			(fill no)
			(layer "B.Fab")
		)
		(fp_poly
			(pts
				(arc
					(start 0 5.2705)
					(mid 0 -5.2705)
					(end 0 5.2705)
				)
			)
			(stroke
				(width 0)
				(type default)
			)
			(fill no)
			(layer "F.Fab")
		)
		(pad "1" thru_hole circle
			(at 0 0 270)
			(size 9.525 9.525)
			(drill 5.0546)
			(layers "*.Cu" "*.Mask")
			(remove_unused_layers no)
			(net "GND")
			(clearance -1.7272)
			(padstack
				(mode front_inner_back)
				(layer "Inner"
					(shape circle)
					(size 5.461 5.461)
					(clearance 0.3048)
				)
				(layer "B.Cu"
					(shape circle)
					(size 9.525 9.525)
					(thermal_gap 0.3048)
					(clearance -1.7272)
				)
			)
		)
	)
	(footprint ""
		(layer "B.Cu")
		(at 45.449998 -337.49996 90)
		(property "Reference" "H13"
			(at 0 0 90)
			(layer "B.SilkS")
			(hide yes)
			(effects
				(font
					(size 1.27 1.27)
				)
				(justify mirror)
			)
		)
		(property "Value" "STF375R199H50-GP"
			(at 6.124702 -0.033274 90)
			(unlocked yes)
			(layer "B.Fab")
			(hide yes)
			(effects
				(font
					(size 1.016 1.016)
					(thickness 0.1524)
				)
				(justify mirror)
			)
		)
		(property "Device Type" "STF375R199H50"
			(at 6.124702 -1.557274 90)
			(unlocked yes)
			(layer "B.Fab")
			(hide yes)
			(effects
				(font
					(size 1.016 1.016)
					(thickness 0.1524)
				)
				(justify mirror)
			)
		)
		(duplicate_pad_numbers_are_jumpers no)
		(fp_circle
			(center 0 0)
			(end 0 5.1181)
			(stroke
				(width 0.3048)
				(type default)
			)
			(fill no)
			(layer "B.SilkS")
		)
		(fp_poly
			(pts
				(arc
					(start -4.0005 0)
					(mid 4.0005 0)
					(end -4.0005 0)
				)
			)
			(stroke
				(width 0)
				(type default)
			)
			(fill no)
			(layer "B.CrtYd")
		)
		(fp_poly
			(pts
				(arc
					(start -5.2705 0.00254)
					(mid 5.270501 0)
					(end -5.2705 -0.00254)
				)
				(arc
					(start -4.0005 -0.00254)
					(mid 4.000501 0)
					(end -4.0005 0.00254)
				)
			)
			(stroke
				(width 0)
				(type default)
			)
			(fill no)
			(layer "B.CrtYd")
		)
		(fp_poly
			(pts
				(arc
					(start -5.2705 0)
					(mid 5.2705 0)
					(end -5.2705 0)
				)
			)
			(stroke
				(width 0)
				(type default)
			)
			(fill no)
			(layer "F.CrtYd")
		)
		(fp_poly
			(pts
				(arc
					(start -5.2705 0)
					(mid 5.2705 0)
					(end -5.2705 0)
				)
			)
			(stroke
				(width 0)
				(type default)
			)
			(fill no)
			(layer "B.Fab")
		)
		(fp_poly
			(pts
				(arc
					(start -5.2705 0)
					(mid 5.2705 0)
					(end -5.2705 0)
				)
			)
			(stroke
				(width 0)
				(type default)
			)
			(fill no)
			(layer "F.Fab")
		)
		(pad "1" thru_hole circle
			(at 0 0 270)
			(size 9.525 9.525)
			(drill 5.0546)
			(layers "*.Cu" "*.Mask")
			(remove_unused_layers no)
			(net "GND")
			(clearance -1.7272)
			(padstack
				(mode front_inner_back)
				(layer "Inner"
					(shape circle)
					(size 5.461 5.461)
					(clearance 0.3048)
				)
				(layer "B.Cu"
					(shape circle)
					(size 9.525 9.525)
					(thermal_gap 0.3048)
					(clearance -1.7272)
				)
			)
		)
	)
	(footprint ""
		(layer "B.Cu")
		(at 24.500078 -463.049874 90)
		(property "Reference" "H9"
			(at 0 0 90)
			(layer "B.SilkS")
			(hide yes)
			(effects
				(font
					(size 1.27 1.27)
				)
				(justify mirror)
			)
		)
		(property "Value" "STF375R199H50-GP"
			(at 6.124702 -0.033274 90)
			(unlocked yes)
			(layer "B.Fab")
			(hide yes)
			(effects
				(font
					(size 1.016 1.016)
					(thickness 0.1524)
				)
				(justify mirror)
			)
		)
		(property "Device Type" "STF375R199H50"
			(at 6.124702 -1.557274 90)
			(unlocked yes)
			(layer "B.Fab")
			(hide yes)
			(effects
				(font
					(size 1.016 1.016)
					(thickness 0.1524)
				)
				(justify mirror)
			)
		)
		(duplicate_pad_numbers_are_jumpers no)
		(fp_circle
			(center 0 0)
			(end 0 5.1181)
			(stroke
				(width 0.3048)
				(type default)
			)
			(fill no)
			(layer "B.SilkS")
		)
		(fp_poly
			(pts
				(arc
					(start 0 4.0005)
					(mid 0 -4.0005)
					(end 0 4.0005)
				)
			)
			(stroke
				(width 0)
				(type default)
			)
			(fill no)
			(layer "B.CrtYd")
		)
		(fp_poly
			(pts
				(arc
					(start -5.2705 0.00254)
					(mid 5.270501 0)
					(end -5.2705 -0.00254)
				)
				(arc
					(start -4.0005 -0.00254)
					(mid 4.000501 0)
					(end -4.0005 0.00254)
				)
			)
			(stroke
				(width 0)
				(type default)
			)
			(fill no)
			(layer "B.CrtYd")
		)
		(fp_poly
			(pts
				(arc
					(start 0 5.2705)
					(mid 0 -5.2705)
					(end 0 5.2705)
				)
			)
			(stroke
				(width 0)
				(type default)
			)
			(fill no)
			(layer "F.CrtYd")
		)
		(fp_poly
			(pts
				(arc
					(start 0 5.2705)
					(mid 0 -5.2705)
					(end 0 5.2705)
				)
			)
			(stroke
				(width 0)
				(type default)
			)
			(fill no)
			(layer "B.Fab")
		)
		(fp_poly
			(pts
				(arc
					(start 0 5.2705)
					(mid 0 -5.2705)
					(end 0 5.2705)
				)
			)
			(stroke
				(width 0)
				(type default)
			)
			(fill no)
			(layer "F.Fab")
		)
		(pad "1" thru_hole circle
			(at 0 0 270)
			(size 9.525 9.525)
			(drill 5.0546)
			(layers "*.Cu" "*.Mask")
			(remove_unused_layers no)
			(net "P12V_AUX")
			(clearance -1.7272)
			(padstack
				(mode front_inner_back)
				(layer "Inner"
					(shape circle)
					(size 5.461 5.461)
					(clearance 0.3048)
				)
				(layer "B.Cu"
					(shape circle)
					(size 9.525 9.525)
					(thermal_gap 0.3048)
					(clearance -1.7272)
				)
			)
		)
	)
	(footprint ""
		(layer "B.Cu")
		(at 24.500078 -443.95009 90)
		(property "Reference" "H10"
			(at 0 0 90)
			(layer "B.SilkS")
			(hide yes)
			(effects
				(font
					(size 1.27 1.27)
				)
				(justify mirror)
			)
		)
		(property "Value" "STF375R199H50-GP"
			(at 6.124702 -0.033274 90)
			(unlocked yes)
			(layer "B.Fab")
			(hide yes)
			(effects
				(font
					(size 1.016 1.016)
					(thickness 0.1524)
				)
				(justify mirror)
			)
		)
		(property "Device Type" "STF375R199H50"
			(at 6.124702 -1.557274 90)
			(unlocked yes)
			(layer "B.Fab")
			(hide yes)
			(effects
				(font
					(size 1.016 1.016)
					(thickness 0.1524)
				)
				(justify mirror)
			)
		)
		(duplicate_pad_numbers_are_jumpers no)
		(fp_circle
			(center 0 0)
			(end 0 5.1181)
			(stroke
				(width 0.3048)
				(type default)
			)
			(fill no)
			(layer "B.SilkS")
		)
		(fp_poly
			(pts
				(arc
					(start 0 4.0005)
					(mid 0 -4.0005)
					(end 0 4.0005)
				)
			)
			(stroke
				(width 0)
				(type default)
			)
			(fill no)
			(layer "B.CrtYd")
		)
		(fp_poly
			(pts
				(arc
					(start -5.2705 0.00254)
					(mid 5.270501 0)
					(end -5.2705 -0.00254)
				)
				(arc
					(start -4.0005 -0.00254)
					(mid 4.000501 0)
					(end -4.0005 0.00254)
				)
			)
			(stroke
				(width 0)
				(type default)
			)
			(fill no)
			(layer "B.CrtYd")
		)
		(fp_poly
			(pts
				(arc
					(start 0 5.2705)
					(mid 0 -5.2705)
					(end 0 5.2705)
				)
			)
			(stroke
				(width 0)
				(type default)
			)
			(fill no)
			(layer "F.CrtYd")
		)
		(fp_poly
			(pts
				(arc
					(start 0 5.2705)
					(mid 0 -5.2705)
					(end 0 5.2705)
				)
			)
			(stroke
				(width 0)
				(type default)
			)
			(fill no)
			(layer "B.Fab")
		)
		(fp_poly
			(pts
				(arc
					(start 0 5.2705)
					(mid 0 -5.2705)
					(end 0 5.2705)
				)
			)
			(stroke
				(width 0)
				(type default)
			)
			(fill no)
			(layer "F.Fab")
		)
		(pad "1" thru_hole circle
			(at 0 0 270)
			(size 9.525 9.525)
			(drill 5.0546)
			(layers "*.Cu" "*.Mask")
			(remove_unused_layers no)
			(net "P12V_AUX")
			(clearance -1.7272)
			(padstack
				(mode front_inner_back)
				(layer "Inner"
					(shape circle)
					(size 5.461 5.461)
					(clearance 0.3048)
				)
				(layer "B.Cu"
					(shape circle)
					(size 9.525 9.525)
					(thermal_gap 0.3048)
					(clearance -1.7272)
				)
			)
		)
	)
	(gr_line
		(start 0 -499.000018)
		(end 0 -0.999998)
		(stroke
			(width 1.524)
			(type default)
		)
		(layer "In1.Cu")
	)
	(gr_arc
		(start 0 -499.000018)
		(mid 0.292892 -499.707125)
		(end 0.999998 -500.000016)
		(stroke
			(width 1.524)
			(type default)
		)
		(layer "In1.Cu")
	)
	(gr_arc
		(start 0.999998 0)
		(mid 0.292893 -0.292893)
		(end 0 -0.999998)
		(stroke
			(width 1.524)
			(type default)
		)
		(layer "In1.Cu")
	)
	(gr_line
		(start 0.999998 0)
		(end 16.500094 0)
		(stroke
			(width 1.524)
			(type default)
		)
		(layer "In1.Cu")
	)
	(gr_circle
		(center 4.040124 -487.780076)
		(end 5.160264 -487.780076)
		(stroke
			(width 0.2)
			(type default)
		)
		(fill no)
		(layer "In1.Cu")
	)
	(gr_circle
		(center 4.040124 -377.73991)
		(end 5.160264 -377.73991)
		(stroke
			(width 0.2)
			(type default)
		)
		(fill no)
		(layer "In1.Cu")
	)
	(gr_circle
		(center 4.040124 -311.740042)
		(end 5.160264 -311.740042)
		(stroke
			(width 0.2)
			(type default)
		)
		(fill no)
		(layer "In1.Cu")
	)
	(gr_circle
		(center 4.040124 -198.419974)
		(end 5.160264 -198.419974)
		(stroke
			(width 0.2)
			(type default)
		)
		(fill no)
		(layer "In1.Cu")
	)
	(gr_circle
		(center 4.040124 -22.37994)
		(end 5.160264 -22.37994)
		(stroke
			(width 0.2)
			(type default)
		)
		(fill no)
		(layer "In1.Cu")
	)
	(gr_line
		(start 12.827 -442.595)
		(end 12.827 -425.704)
		(stroke
			(width 0.381)
			(type default)
		)
		(layer "In1.Cu")
	)
	(gr_line
		(start 12.827 -425.704)
		(end 13.843 -424.688)
		(stroke
			(width 0.381)
			(type default)
		)
		(layer "In1.Cu")
	)
	(gr_line
		(start 13.843 -424.688)
		(end 32.131 -424.688)
		(stroke
			(width 0.381)
			(type default)
		)
		(layer "In1.Cu")
	)
	(gr_line
		(start 15.24 -474.98)
		(end 15.24 -445.008)
		(stroke
			(width 0.381)
			(type default)
		)
		(layer "In1.Cu")
	)
	(gr_line
		(start 15.24 -445.008)
		(end 12.827 -442.595)
		(stroke
			(width 0.381)
			(type default)
		)
		(layer "In1.Cu")
	)
	(gr_line
		(start 15.875 -475.615)
		(end 15.24 -474.98)
		(stroke
			(width 0.381)
			(type default)
		)
		(layer "In1.Cu")
	)
	(gr_line
		(start 16.500094 -500.000016)
		(end 0.999998 -500.000016)
		(stroke
			(width 1.524)
			(type default)
		)
		(layer "In1.Cu")
	)
	(gr_arc
		(start 16.500094 -500.000016)
		(mid 17.20721 -499.707127)
		(end 17.500092 -499.000018)
		(stroke
			(width 1.524)
			(type default)
		)
		(layer "In1.Cu")
	)
	(gr_line
		(start 17.500092 -491.000034)
		(end 17.500092 -499.000018)
		(stroke
			(width 1.524)
			(type default)
		)
		(layer "In1.Cu")
	)
	(gr_arc
		(start 17.500092 -8.999982)
		(mid 17.792985 -9.707087)
		(end 18.50009 -9.99998)
		(stroke
			(width 1.524)
			(type default)
		)
		(layer "In1.Cu")
	)
	(gr_arc
		(start 17.500092 -0.999998)
		(mid 17.207198 -0.292896)
		(end 16.500094 0)
		(stroke
			(width 1.524)
			(type default)
		)
		(layer "In1.Cu")
	)
	(gr_line
		(start 17.500092 -0.999998)
		(end 17.500092 -8.999982)
		(stroke
			(width 1.524)
			(type default)
		)
		(layer "In1.Cu")
	)
	(gr_arc
		(start 18.50009 -490.000036)
		(mid 17.792985 -490.292929)
		(end 17.500092 -491.000034)
		(stroke
			(width 1.524)
			(type default)
		)
		(layer "In1.Cu")
	)
	(gr_line
		(start 18.50009 -9.99998)
		(end 51.500024 -9.99998)
		(stroke
			(width 1.524)
			(type default)
		)
		(layer "In1.Cu")
	)
	(gr_line
		(start 20.574 -475.615)
		(end 15.875 -475.615)
		(stroke
			(width 0.381)
			(type default)
		)
		(layer "In1.Cu")
	)
	(gr_line
		(start 21.082 -489.458)
		(end 21.082 -476.123)
		(stroke
			(width 0.381)
			(type default)
		)
		(layer "In1.Cu")
	)
	(gr_line
		(start 21.082 -476.123)
		(end 20.574 -475.615)
		(stroke
			(width 0.381)
			(type default)
		)
		(layer "In1.Cu")
	)
	(gr_line
		(start 22.479 -475.996)
		(end 22.479 -489.458)
		(stroke
			(width 0.381)
			(type default)
		)
		(layer "In1.Cu")
	)
	(gr_line
		(start 22.86 -475.615)
		(end 22.479 -475.996)
		(stroke
			(width 0.381)
			(type default)
		)
		(layer "In1.Cu")
	)
	(gr_line
		(start 30.48 -475.615)
		(end 22.86 -475.615)
		(stroke
			(width 0.381)
			(type default)
		)
		(layer "In1.Cu")
	)
	(gr_line
		(start 31.623 -452.12)
		(end 32.893 -453.39)
		(stroke
			(width 0.381)
			(type default)
		)
		(layer "In1.Cu")
	)
	(gr_line
		(start 31.623 -451.231)
		(end 31.623 -452.12)
		(stroke
			(width 0.381)
			(type default)
		)
		(layer "In1.Cu")
	)
	(gr_line
		(start 32.131 -450.723)
		(end 31.623 -451.231)
		(stroke
			(width 0.381)
			(type default)
		)
		(layer "In1.Cu")
	)
	(gr_line
		(start 32.131 -424.688)
		(end 32.893 -425.45)
		(stroke
			(width 0.381)
			(type default)
		)
		(layer "In1.Cu")
	)
	(gr_line
		(start 32.766 -450.723)
		(end 32.131 -450.723)
		(stroke
			(width 0.381)
			(type default)
		)
		(layer "In1.Cu")
	)
	(gr_line
		(start 32.893 -473.202)
		(end 30.48 -475.615)
		(stroke
			(width 0.381)
			(type default)
		)
		(layer "In1.Cu")
	)
	(gr_line
		(start 32.893 -453.39)
		(end 32.893 -473.202)
		(stroke
			(width 0.381)
			(type default)
		)
		(layer "In1.Cu")
	)
	(gr_line
		(start 32.893 -450.596)
		(end 32.766 -450.723)
		(stroke
			(width 0.381)
			(type default)
		)
		(layer "In1.Cu")
	)
	(gr_line
		(start 32.893 -425.45)
		(end 32.893 -450.596)
		(stroke
			(width 0.381)
			(type default)
		)
		(layer "In1.Cu")
	)
	(gr_line
		(start 51.500024 -490.000036)
		(end 18.50009 -490.000036)
		(stroke
			(width 1.524)
			(type default)
		)
		(layer "In1.Cu")
	)
	(gr_arc
		(start 51.500024 -490.000036)
		(mid 52.207127 -489.707137)
		(end 52.500022 -489.000038)
		(stroke
			(width 1.524)
			(type default)
		)
		(layer "In1.Cu")
	)
	(gr_arc
		(start 52.500022 -10.999978)
		(mid 52.207123 -10.292878)
		(end 51.500024 -9.99998)
		(stroke
			(width 1.524)
			(type default)
		)
		(layer "In1.Cu")
	)
	(gr_line
		(start 52.500022 -10.999978)
		(end 52.500022 -489.000038)
		(stroke
			(width 1.524)
			(type default)
		)
		(layer "In1.Cu")
	)
	(gr_line
		(start 0 -499.000018)
		(end 0 -0.999998)
		(stroke
			(width 1.524)
			(type default)
		)
		(layer "In2.Cu")
	)
	(gr_arc
		(start 0 -499.000018)
		(mid 0.292892 -499.707125)
		(end 0.999998 -500.000016)
		(stroke
			(width 1.524)
			(type default)
		)
		(layer "In2.Cu")
	)
	(gr_arc
		(start 0.999998 0)
		(mid 0.292893 -0.292893)
		(end 0 -0.999998)
		(stroke
			(width 1.524)
			(type default)
		)
		(layer "In2.Cu")
	)
	(gr_line
		(start 0.999998 0)
		(end 16.500094 0)
		(stroke
			(width 1.524)
			(type default)
		)
		(layer "In2.Cu")
	)
	(gr_circle
		(center 4.499864 -340.000082)
		(end 9.499854 -340.000082)
		(stroke
			(width 0.2)
			(type default)
		)
		(fill no)
		(layer "In2.Cu")
	)
	(gr_circle
		(center 6.999986 -459.999842)
		(end 11.999976 -459.999842)
		(stroke
			(width 0.2)
			(type default)
		)
		(fill no)
		(layer "In2.Cu")
	)
	(gr_circle
		(center 6.999986 -159.999934)
		(end 11.999976 -159.999934)
		(stroke
			(width 0.2)
			(type default)
		)
		(fill no)
		(layer "In2.Cu")
	)
	(gr_circle
		(center 6.999986 -39.99992)
		(end 11.999976 -39.99992)
		(stroke
			(width 0.2)
			(type default)
		)
		(fill no)
		(layer "In2.Cu")
	)
	(gr_line
		(start 9.652 -110.744)
		(end 11.811 -112.903)
		(stroke
			(width 0.381)
			(type default)
		)
		(layer "In2.Cu")
	)
	(gr_line
		(start 9.652 -72.898)
		(end 9.652 -110.744)
		(stroke
			(width 0.381)
			(type default)
		)
		(layer "In2.Cu")
	)
	(gr_line
		(start 10.16 -120.269)
		(end 11.43 -121.539)
		(stroke
			(width 0.381)
			(type default)
		)
		(layer "In2.Cu")
	)
	(gr_line
		(start 10.16 -114.554)
		(end 10.16 -120.269)
		(stroke
			(width 0.381)
			(type default)
		)
		(layer "In2.Cu")
	)
	(gr_line
		(start 10.414 -72.136)
		(end 9.652 -72.898)
		(stroke
			(width 0.381)
			(type default)
		)
		(layer "In2.Cu")
	)
	(gr_line
		(start 11.43 -121.539)
		(end 25.654 -121.539)
		(stroke
			(width 0.381)
			(type default)
		)
		(layer "In2.Cu")
	)
	(gr_line
		(start 11.811 -112.903)
		(end 10.16 -114.554)
		(stroke
			(width 0.381)
			(type default)
		)
		(layer "In2.Cu")
	)
	(gr_line
		(start 12.446 -409.194)
		(end 13.843 -410.591)
		(stroke
			(width 0.381)
			(type default)
		)
		(layer "In2.Cu")
	)
	(gr_line
		(start 12.446 -401.701)
		(end 12.446 -409.194)
		(stroke
			(width 0.381)
			(type default)
		)
		(layer "In2.Cu")
	)
	(gr_line
		(start 12.827 -442.595)
		(end 15.24 -445.008)
		(stroke
			(width 0.381)
			(type default)
		)
		(layer "In2.Cu")
	)
	(gr_line
		(start 12.827 -411.607)
		(end 12.827 -442.595)
		(stroke
			(width 0.381)
			(type default)
		)
		(layer "In2.Cu")
	)
	(gr_line
		(start 12.954 -401.193)
		(end 12.446 -401.701)
		(stroke
			(width 0.381)
			(type default)
		)
		(layer "In2.Cu")
	)
	(gr_line
		(start 13.208 -411.099)
		(end 13.208 -410.21)
		(stroke
			(width 0.2)
			(type default)
		)
		(layer "In2.Cu")
	)
	(gr_line
		(start 13.208 -410.21)
		(end 13.462 -410.21)
		(stroke
			(width 0.2)
			(type default)
		)
		(layer "In2.Cu")
	)
	(gr_line
		(start 13.462 -411.099)
		(end 13.208 -411.099)
		(stroke
			(width 0.2)
			(type default)
		)
		(layer "In2.Cu")
	)
	(gr_line
		(start 13.462 -410.21)
		(end 13.716 -410.464)
		(stroke
			(width 0.2)
			(type default)
		)
		(layer "In2.Cu")
	)
	(gr_line
		(start 13.716 -410.845)
		(end 13.462 -411.099)
		(stroke
			(width 0.2)
			(type default)
		)
		(layer "In2.Cu")
	)
	(gr_line
		(start 13.716 -410.464)
		(end 13.716 -410.845)
		(stroke
			(width 0.2)
			(type default)
		)
		(layer "In2.Cu")
	)
	(gr_line
		(start 13.843 -410.591)
		(end 12.827 -411.607)
		(stroke
			(width 0.381)
			(type default)
		)
		(layer "In2.Cu")
	)
	(gr_line
		(start 13.843 -410.591)
		(end 46.99 -410.591)
		(stroke
			(width 0.381)
			(type default)
		)
		(layer "In2.Cu")
	)
	(gr_line
		(start 15.24 -474.98)
		(end 15.875 -475.615)
		(stroke
			(width 0.381)
			(type default)
		)
		(layer "In2.Cu")
	)
	(gr_line
		(start 15.24 -445.008)
		(end 15.24 -474.98)
		(stroke
			(width 0.381)
			(type default)
		)
		(layer "In2.Cu")
	)
	(gr_line
		(start 15.875 -475.615)
		(end 30.48 -475.615)
		(stroke
			(width 0.381)
			(type default)
		)
		(layer "In2.Cu")
	)
	(gr_line
		(start 16.500094 -500.000016)
		(end 0.999998 -500.000016)
		(stroke
			(width 1.524)
			(type default)
		)
		(layer "In2.Cu")
	)
	(gr_arc
		(start 16.500094 -500.000016)
		(mid 17.20721 -499.707127)
		(end 17.500092 -499.000018)
		(stroke
			(width 1.524)
			(type default)
		)
		(layer "In2.Cu")
	)
	(gr_line
		(start 17.399 -72.136)
		(end 10.414 -72.136)
		(stroke
			(width 0.381)
			(type default)
		)
		(layer "In2.Cu")
	)
	(gr_line
		(start 17.500092 -491.000034)
		(end 17.500092 -499.000018)
		(stroke
			(width 1.524)
			(type default)
		)
		(layer "In2.Cu")
	)
	(gr_arc
		(start 17.500092 -8.999982)
		(mid 17.792985 -9.707087)
		(end 18.50009 -9.99998)
		(stroke
			(width 1.524)
			(type default)
		)
		(layer "In2.Cu")
	)
	(gr_arc
		(start 17.500092 -0.999998)
		(mid 17.207198 -0.292896)
		(end 16.500094 0)
		(stroke
			(width 1.524)
			(type default)
		)
		(layer "In2.Cu")
	)
	(gr_line
		(start 17.500092 -0.999998)
		(end 17.500092 -8.999982)
		(stroke
			(width 1.524)
			(type default)
		)
		(layer "In2.Cu")
	)
	(gr_line
		(start 18.034 -71.501)
		(end 17.399 -72.136)
		(stroke
			(width 0.381)
			(type default)
		)
		(layer "In2.Cu")
	)
	(gr_line
		(start 18.034 -65.786)
		(end 18.034 -71.501)
		(stroke
			(width 0.381)
			(type default)
		)
		(layer "In2.Cu")
	)
	(gr_arc
		(start 18.50009 -490.000036)
		(mid 17.792985 -490.292929)
		(end 17.500092 -491.000034)
		(stroke
			(width 1.524)
			(type default)
		)
		(layer "In2.Cu")
	)
	(gr_line
		(start 18.50009 -9.99998)
		(end 51.500024 -9.99998)
		(stroke
			(width 1.524)
			(type default)
		)
		(layer "In2.Cu")
	)
	(gr_line
		(start 19.812 -64.008)
		(end 18.034 -65.786)
		(stroke
			(width 0.381)
			(type default)
		)
		(layer "In2.Cu")
	)
	(gr_line
		(start 21.971 -112.776)
		(end 21.971 -110.617)
		(stroke
			(width 0.381)
			(type default)
		)
		(layer "In2.Cu")
	)
	(gr_line
		(start 21.971 -110.617)
		(end 24.257 -108.331)
		(stroke
			(width 0.381)
			(type default)
		)
		(layer "In2.Cu")
	)
	(gr_line
		(start 23.622 -94.488)
		(end 23.622 -89.662)
		(stroke
			(width 0.381)
			(type default)
		)
		(layer "In2.Cu")
	)
	(gr_line
		(start 23.622 -89.662)
		(end 24.003 -89.281)
		(stroke
			(width 0.381)
			(type default)
		)
		(layer "In2.Cu")
	)
	(gr_line
		(start 24.003 -89.281)
		(end 24.511 -89.281)
		(stroke
			(width 0.381)
			(type default)
		)
		(layer "In2.Cu")
	)
	(gr_line
		(start 24.257 -108.331)
		(end 24.257 -95.123)
		(stroke
			(width 0.381)
			(type default)
		)
		(layer "In2.Cu")
	)
	(gr_line
		(start 24.257 -95.123)
		(end 23.622 -94.488)
		(stroke
			(width 0.381)
			(type default)
		)
		(layer "In2.Cu")
	)
	(gr_line
		(start 24.511 -89.281)
		(end 25.146 -88.646)
		(stroke
			(width 0.381)
			(type default)
		)
		(layer "In2.Cu")
	)
	(gr_line
		(start 25.146 -88.646)
		(end 25.146 -81.153)
		(stroke
			(width 0.381)
			(type default)
		)
		(layer "In2.Cu")
	)
	(gr_line
		(start 25.146 -81.153)
		(end 25.781 -80.518)
		(stroke
			(width 0.381)
			(type default)
		)
		(layer "In2.Cu")
	)
	(gr_line
		(start 25.654 -80.645)
		(end 30.099 -76.2)
		(stroke
			(width 0.381)
			(type default)
		)
		(layer "In2.Cu")
	)
	(gr_line
		(start 25.781 -80.518)
		(end 25.654 -80.645)
		(stroke
			(width 0.381)
			(type default)
		)
		(layer "In2.Cu")
	)
	(gr_line
		(start 25.908 -113.03)
		(end 30.226 -113.03)
		(stroke
			(width 0.381)
			(type default)
		)
		(layer "In2.Cu")
	)
	(gr_line
		(start 28.956 -109.22)
		(end 28.956 -95.631)
		(stroke
			(width 0.381)
			(type default)
		)
		(layer "In2.Cu")
	)
	(gr_line
		(start 28.956 -95.631)
		(end 29.718 -94.869)
		(stroke
			(width 0.381)
			(type default)
		)
		(layer "In2.Cu")
	)
	(gr_line
		(start 28.956 -89.154)
		(end 28.956 -79.756)
		(stroke
			(width 0.381)
			(type default)
		)
		(layer "In2.Cu")
	)
	(gr_line
		(start 28.956 -79.756)
		(end 35.433 -73.279)
		(stroke
			(width 0.381)
			(type default)
		)
		(layer "In2.Cu")
	)
	(gr_line
		(start 29.083 -64.008)
		(end 19.812 -64.008)
		(stroke
			(width 0.381)
			(type default)
		)
		(layer "In2.Cu")
	)
	(gr_line
		(start 29.718 -94.869)
		(end 29.718 -89.916)
		(stroke
			(width 0.381)
			(type default)
		)
		(layer "In2.Cu")
	)
	(gr_line
		(start 29.718 -89.916)
		(end 28.956 -89.154)
		(stroke
			(width 0.381)
			(type default)
		)
		(layer "In2.Cu")
	)
	(gr_line
		(start 30.099 -113.03)
		(end 11.684 -113.03)
		(stroke
			(width 0.381)
			(type default)
		)
		(layer "In2.Cu")
	)
	(gr_line
		(start 30.099 -76.2)
		(end 30.099 -65.024)
		(stroke
			(width 0.381)
			(type default)
		)
		(layer "In2.Cu")
	)
	(gr_line
		(start 30.099 -65.024)
		(end 29.083 -64.008)
		(stroke
			(width 0.381)
			(type default)
		)
		(layer "In2.Cu")
	)
	(gr_line
		(start 30.226 -113.03)
		(end 31.623 -114.427)
		(stroke
			(width 0.381)
			(type default)
		)
		(layer "In2.Cu")
	)
	(gr_line
		(start 30.48 -475.615)
		(end 32.893 -473.202)
		(stroke
			(width 0.381)
			(type default)
		)
		(layer "In2.Cu")
	)
	(gr_line
		(start 30.734 -121.539)
		(end 25.654 -121.539)
		(stroke
			(width 0.381)
			(type default)
		)
		(layer "In2.Cu")
	)
	(gr_line
		(start 31.623 -451.866)
		(end 31.877 -450.977)
		(stroke
			(width 0.381)
			(type default)
		)
		(layer "In2.Cu")
	)
	(gr_line
		(start 31.623 -120.65)
		(end 30.734 -121.539)
		(stroke
			(width 0.381)
			(type default)
		)
		(layer "In2.Cu")
	)
	(gr_line
		(start 31.623 -114.427)
		(end 31.623 -120.65)
		(stroke
			(width 0.381)
			(type default)
		)
		(layer "In2.Cu")
	)
	(gr_line
		(start 31.877 -450.977)
		(end 32.893 -450.469)
		(stroke
			(width 0.381)
			(type default)
		)
		(layer "In2.Cu")
	)
	(gr_line
		(start 32.131 -452.755)
		(end 31.623 -451.866)
		(stroke
			(width 0.381)
			(type default)
		)
		(layer "In2.Cu")
	)
	(gr_line
		(start 32.512 -120.904)
		(end 32.893 -121.285)
		(stroke
			(width 0.381)
			(type default)
		)
		(layer "In2.Cu")
	)
	(gr_line
		(start 32.512 -113.284)
		(end 32.512 -120.904)
		(stroke
			(width 0.381)
			(type default)
		)
		(layer "In2.Cu")
	)
	(gr_line
		(start 32.766 -113.03)
		(end 28.956 -109.22)
		(stroke
			(width 0.381)
			(type default)
		)
		(layer "In2.Cu")
	)
	(gr_line
		(start 32.766 -113.03)
		(end 32.512 -113.284)
		(stroke
			(width 0.381)
			(type default)
		)
		(layer "In2.Cu")
	)
	(gr_line
		(start 32.893 -473.202)
		(end 32.893 -453.136)
		(stroke
			(width 0.381)
			(type default)
		)
		(layer "In2.Cu")
	)
	(gr_line
		(start 32.893 -453.136)
		(end 32.131 -452.755)
		(stroke
			(width 0.381)
			(type default)
		)
		(layer "In2.Cu")
	)
	(gr_line
		(start 32.893 -450.469)
		(end 32.893 -425.704)
		(stroke
			(width 0.381)
			(type default)
		)
		(layer "In2.Cu")
	)
	(gr_line
		(start 32.893 -425.704)
		(end 34.798 -423.799)
		(stroke
			(width 0.381)
			(type default)
		)
		(layer "In2.Cu")
	)
	(gr_line
		(start 32.893 -121.285)
		(end 51.308 -121.285)
		(stroke
			(width 0.381)
			(type default)
		)
		(layer "In2.Cu")
	)
	(gr_line
		(start 34.798 -489.712)
		(end 34.798 -489.585)
		(stroke
			(width 0.381)
			(type default)
		)
		(layer "In2.Cu")
	)
	(gr_line
		(start 34.798 -489.585)
		(end 35.179 -489.204)
		(stroke
			(width 0.381)
			(type default)
		)
		(layer "In2.Cu")
	)
	(gr_line
		(start 34.798 -423.799)
		(end 46.736 -423.799)
		(stroke
			(width 0.381)
			(type default)
		)
		(layer "In2.Cu")
	)
	(gr_line
		(start 35.179 -490.093)
		(end 35.179 -481.965)
		(stroke
			(width 0.381)
			(type default)
		)
		(layer "In2.Cu")
	)
	(gr_line
		(start 35.179 -489.204)
		(end 35.56 -489.585)
		(stroke
			(width 0.381)
			(type default)
		)
		(layer "In2.Cu")
	)
	(gr_line
		(start 35.179 -481.965)
		(end 36.83 -480.314)
		(stroke
			(width 0.381)
			(type default)
		)
		(layer "In2.Cu")
	)
	(gr_line
		(start 35.433 -73.279)
		(end 35.433 -65.024)
		(stroke
			(width 0.381)
			(type default)
		)
		(layer "In2.Cu")
	)
	(gr_line
		(start 35.433 -65.024)
		(end 36.957 -63.5)
		(stroke
			(width 0.381)
			(type default)
		)
		(layer "In2.Cu")
	)
	(gr_line
		(start 36.068 -473.202)
		(end 32.893 -473.202)
		(stroke
			(width 0.381)
			(type default)
		)
		(layer "In2.Cu")
	)
	(gr_line
		(start 36.83 -480.314)
		(end 36.83 -473.964)
		(stroke
			(width 0.381)
			(type default)
		)
		(layer "In2.Cu")
	)
	(gr_line
		(start 36.83 -473.964)
		(end 36.068 -473.202)
		(stroke
			(width 0.381)
			(type default)
		)
		(layer "In2.Cu")
	)
	(gr_line
		(start 36.957 -63.5)
		(end 46.863 -63.5)
		(stroke
			(width 0.381)
			(type default)
		)
		(layer "In2.Cu")
	)
	(gr_line
		(start 39.497 -113.03)
		(end 32.766 -113.03)
		(stroke
			(width 0.381)
			(type default)
		)
		(layer "In2.Cu")
	)
	(gr_line
		(start 45.085 -81.788)
		(end 45.085 -112.903)
		(stroke
			(width 0.381)
			(type default)
		)
		(layer "In2.Cu")
	)
	(gr_circle
		(center 45.449998 -337.49996)
		(end 52.95011 -337.49996)
		(stroke
			(width 0.2)
			(type default)
		)
		(fill no)
		(layer "In2.Cu")
	)
	(gr_circle
		(center 45.499782 -144.999964)
		(end 50.499772 -144.999964)
		(stroke
			(width 0.2)
			(type default)
		)
		(fill no)
		(layer "In2.Cu")
	)
	(gr_circle
		(center 45.500036 -480.000056)
		(end 50.500026 -480.000056)
		(stroke
			(width 0.2)
			(type default)
		)
		(fill no)
		(layer "In2.Cu")
	)
	(gr_circle
		(center 45.500036 -294.999918)
		(end 50.500026 -294.999918)
		(stroke
			(width 0.2)
			(type default)
		)
		(fill no)
		(layer "In2.Cu")
	)
	(gr_circle
		(center 45.500036 -19.99996)
		(end 50.500026 -19.99996)
		(stroke
			(width 0.2)
			(type default)
		)
		(fill no)
		(layer "In2.Cu")
	)
	(gr_line
		(start 45.974 -410.591)
		(end 46.863 -410.591)
		(stroke
			(width 0.381)
			(type default)
		)
		(layer "In2.Cu")
	)
	(gr_line
		(start 46.736 -410.591)
		(end 45.974 -410.591)
		(stroke
			(width 0.381)
			(type default)
		)
		(layer "In2.Cu")
	)
	(gr_line
		(start 46.863 -401.193)
		(end 12.954 -401.193)
		(stroke
			(width 0.381)
			(type default)
		)
		(layer "In2.Cu")
	)
	(gr_line
		(start 46.863 -63.5)
		(end 47.752 -64.389)
		(stroke
			(width 0.381)
			(type default)
		)
		(layer "In2.Cu")
	)
	(gr_line
		(start 46.99 -410.591)
		(end 47.752 -409.829)
		(stroke
			(width 0.381)
			(type default)
		)
		(layer "In2.Cu")
	)
	(gr_line
		(start 47.117 -423.418)
		(end 46.736 -423.799)
		(stroke
			(width 0.381)
			(type default)
		)
		(layer "In2.Cu")
	)
	(gr_line
		(start 47.117 -423.418)
		(end 47.117 -410.972)
		(stroke
			(width 0.381)
			(type default)
		)
		(layer "In2.Cu")
	)
	(gr_line
		(start 47.117 -410.972)
		(end 46.736 -410.591)
		(stroke
			(width 0.381)
			(type default)
		)
		(layer "In2.Cu")
	)
	(gr_line
		(start 47.117 -410.972)
		(end 47.117 -410.464)
		(stroke
			(width 0.381)
			(type default)
		)
		(layer "In2.Cu")
	)
	(gr_line
		(start 47.117 -410.464)
		(end 47.752 -409.829)
		(stroke
			(width 0.381)
			(type default)
		)
		(layer "In2.Cu")
	)
	(gr_line
		(start 47.752 -409.829)
		(end 47.752 -402.082)
		(stroke
			(width 0.381)
			(type default)
		)
		(layer "In2.Cu")
	)
	(gr_line
		(start 47.752 -402.59)
		(end 48.133 -402.209)
		(stroke
			(width 0.381)
			(type default)
		)
		(layer "In2.Cu")
	)
	(gr_line
		(start 47.752 -402.082)
		(end 46.863 -401.193)
		(stroke
			(width 0.381)
			(type default)
		)
		(layer "In2.Cu")
	)
	(gr_line
		(start 47.752 -402.082)
		(end 52.324 -402.082)
		(stroke
			(width 0.381)
			(type default)
		)
		(layer "In2.Cu")
	)
	(gr_line
		(start 47.752 -79.121)
		(end 45.085 -81.788)
		(stroke
			(width 0.381)
			(type default)
		)
		(layer "In2.Cu")
	)
	(gr_line
		(start 47.752 -64.389)
		(end 47.752 -79.121)
		(stroke
			(width 0.381)
			(type default)
		)
		(layer "In2.Cu")
	)
	(gr_line
		(start 51.308 -121.285)
		(end 51.816 -120.777)
		(stroke
			(width 0.381)
			(type default)
		)
		(layer "In2.Cu")
	)
	(gr_line
		(start 51.500024 -490.000036)
		(end 18.50009 -490.000036)
		(stroke
			(width 1.524)
			(type default)
		)
		(layer "In2.Cu")
	)
	(gr_arc
		(start 51.500024 -490.000036)
		(mid 52.207127 -489.707137)
		(end 52.500022 -489.000038)
		(stroke
			(width 1.524)
			(type default)
		)
		(layer "In2.Cu")
	)
	(gr_line
		(start 51.562 -402.082)
		(end 52.07 -401.574)
		(stroke
			(width 0.381)
			(type default)
		)
		(layer "In2.Cu")
	)
	(gr_line
		(start 51.689 -113.03)
		(end 32.766 -113.03)
		(stroke
			(width 0.381)
			(type default)
		)
		(layer "In2.Cu")
	)
	(gr_line
		(start 51.943 -402.463)
		(end 51.562 -402.082)
		(stroke
			(width 0.381)
			(type default)
		)
		(layer "In2.Cu")
	)
	(gr_arc
		(start 52.500022 -10.999978)
		(mid 52.207123 -10.292878)
		(end 51.500024 -9.99998)
		(stroke
			(width 1.524)
			(type default)
		)
		(layer "In2.Cu")
	)
	(gr_line
		(start 52.500022 -10.999978)
		(end 52.500022 -489.000038)
		(stroke
			(width 1.524)
			(type default)
		)
		(layer "In2.Cu")
	)
	(gr_line
		(start 0 -499.000018)
		(end 0 -0.999998)
		(stroke
			(width 0.05)
			(type default)
		)
		(layer "Edge.Cuts")
	)
	(gr_arc
		(start 0 -499.000018)
		(mid 0.292892 -499.707125)
		(end 0.999998 -500.000016)
		(stroke
			(width 0.05)
			(type default)
		)
		(layer "Edge.Cuts")
	)
	(gr_arc
		(start 0.999998 0)
		(mid 0.292893 -0.292893)
		(end 0 -0.999998)
		(stroke
			(width 0.05)
			(type default)
		)
		(layer "Edge.Cuts")
	)
	(gr_line
		(start 0.999998 0)
		(end 16.500094 0)
		(stroke
			(width 0.05)
			(type default)
		)
		(layer "Edge.Cuts")
	)
	(gr_arc
		(start 2.750058 -340.000082)
		(mid 4.500118 -341.750142)
		(end 6.249924 -340.000082)
		(stroke
			(width 0.05)
			(type default)
		)
		(layer "Edge.Cuts")
	)
	(gr_arc
		(start 4.99999 -39.99992)
		(mid 6.999986 -41.999916)
		(end 8.999982 -39.99992)
		(stroke
			(width 0.05)
			(type default)
		)
		(layer "Edge.Cuts")
	)
	(gr_arc
		(start 5.249926 -460.000096)
		(mid 6.999986 -461.750156)
		(end 8.750046 -460.000096)
		(stroke
			(width 0.05)
			(type default)
		)
		(layer "Edge.Cuts")
	)
	(gr_arc
		(start 5.249926 -159.999934)
		(mid 6.999986 -161.749994)
		(end 8.750046 -159.999934)
		(stroke
			(width 0.05)
			(type default)
		)
		(layer "Edge.Cuts")
	)
	(gr_arc
		(start 5.80009 -493.700054)
		(mid 7.600188 -495.500152)
		(end 9.400032 -493.700054)
		(stroke
			(width 0.05)
			(type default)
		)
		(layer "Edge.Cuts")
	)
	(gr_arc
		(start 5.80009 -471.700098)
		(mid 7.600188 -473.500196)
		(end 9.400032 -471.700098)
		(stroke
			(width 0.05)
			(type default)
		)
		(layer "Edge.Cuts")
	)
	(gr_arc
		(start 5.80009 -383.659888)
		(mid 7.600188 -385.459986)
		(end 9.400032 -383.659888)
		(stroke
			(width 0.05)
			(type default)
		)
		(layer "Edge.Cuts")
	)
	(gr_arc
		(start 5.80009 -361.659932)
		(mid 7.600188 -363.46003)
		(end 9.400032 -361.659932)
		(stroke
			(width 0.05)
			(type default)
		)
		(layer "Edge.Cuts")
	)
	(gr_arc
		(start 5.80009 -317.66002)
		(mid 7.600188 -319.460118)
		(end 9.400032 -317.66002)
		(stroke
			(width 0.05)
			(type default)
		)
		(layer "Edge.Cuts")
	)
	(gr_arc
		(start 5.80009 -295.660064)
		(mid 7.600188 -297.460162)
		(end 9.400032 -295.660064)
		(stroke
			(width 0.05)
			(type default)
		)
		(layer "Edge.Cuts")
	)
	(gr_arc
		(start 5.80009 -204.339952)
		(mid 7.600188 -206.14005)
		(end 9.400032 -204.339952)
		(stroke
			(width 0.05)
			(type default)
		)
		(layer "Edge.Cuts")
	)
	(gr_arc
		(start 5.80009 -182.339996)
		(mid 7.600188 -184.140094)
		(end 9.400032 -182.339996)
		(stroke
			(width 0.05)
			(type default)
		)
		(layer "Edge.Cuts")
	)
	(gr_arc
		(start 5.80009 -138.340084)
		(mid 7.600188 -140.140182)
		(end 9.400032 -138.340084)
		(stroke
			(width 0.05)
			(type default)
		)
		(layer "Edge.Cuts")
	)
	(gr_arc
		(start 5.80009 -116.339874)
		(mid 7.600188 -118.139972)
		(end 9.400032 -116.339874)
		(stroke
			(width 0.05)
			(type default)
		)
		(layer "Edge.Cuts")
	)
	(gr_arc
		(start 5.80009 -28.299918)
		(mid 7.600188 -30.100016)
		(end 9.400032 -28.299918)
		(stroke
			(width 0.05)
			(type default)
		)
		(layer "Edge.Cuts")
	)
	(gr_arc
		(start 5.80009 -6.299962)
		(mid 7.600188 -8.10006)
		(end 9.400032 -6.299962)
		(stroke
			(width 0.05)
			(type default)
		)
		(layer "Edge.Cuts")
	)
	(gr_arc
		(start 6.249924 -340.000082)
		(mid 4.500118 -338.250276)
		(end 2.750058 -340.000082)
		(stroke
			(width 0.05)
			(type default)
		)
		(layer "Edge.Cuts")
	)
	(gr_arc
		(start 8.750046 -460.000096)
		(mid 6.999986 -458.250036)
		(end 5.249926 -460.000096)
		(stroke
			(width 0.05)
			(type default)
		)
		(layer "Edge.Cuts")
	)
	(gr_arc
		(start 8.750046 -159.999934)
		(mid 6.999986 -158.249874)
		(end 5.249926 -159.999934)
		(stroke
			(width 0.05)
			(type default)
		)
		(layer "Edge.Cuts")
	)
	(gr_arc
		(start 8.999982 -39.99992)
		(mid 6.999986 -37.999924)
		(end 4.99999 -39.99992)
		(stroke
			(width 0.05)
			(type default)
		)
		(layer "Edge.Cuts")
	)
	(gr_arc
		(start 9.400032 -493.700054)
		(mid 7.600188 -491.90021)
		(end 5.80009 -493.700054)
		(stroke
			(width 0.05)
			(type default)
		)
		(layer "Edge.Cuts")
	)
	(gr_arc
		(start 9.400032 -471.700098)
		(mid 7.600188 -469.900254)
		(end 5.80009 -471.700098)
		(stroke
			(width 0.05)
			(type default)
		)
		(layer "Edge.Cuts")
	)
	(gr_arc
		(start 9.400032 -383.659888)
		(mid 7.600188 -381.860044)
		(end 5.80009 -383.659888)
		(stroke
			(width 0.05)
			(type default)
		)
		(layer "Edge.Cuts")
	)
	(gr_arc
		(start 9.400032 -361.659932)
		(mid 7.600188 -359.860088)
		(end 5.80009 -361.659932)
		(stroke
			(width 0.05)
			(type default)
		)
		(layer "Edge.Cuts")
	)
	(gr_arc
		(start 9.400032 -317.66002)
		(mid 7.600188 -315.860176)
		(end 5.80009 -317.66002)
		(stroke
			(width 0.05)
			(type default)
		)
		(layer "Edge.Cuts")
	)
	(gr_arc
		(start 9.400032 -295.660064)
		(mid 7.600188 -293.86022)
		(end 5.80009 -295.660064)
		(stroke
			(width 0.05)
			(type default)
		)
		(layer "Edge.Cuts")
	)
	(gr_arc
		(start 9.400032 -204.339952)
		(mid 7.600188 -202.540108)
		(end 5.80009 -204.339952)
		(stroke
			(width 0.05)
			(type default)
		)
		(layer "Edge.Cuts")
	)
	(gr_arc
		(start 9.400032 -182.339996)
		(mid 7.600188 -180.540152)
		(end 5.80009 -182.339996)
		(stroke
			(width 0.05)
			(type default)
		)
		(layer "Edge.Cuts")
	)
	(gr_arc
		(start 9.400032 -138.340084)
		(mid 7.600188 -136.54024)
		(end 5.80009 -138.340084)
		(stroke
			(width 0.05)
			(type default)
		)
		(layer "Edge.Cuts")
	)
	(gr_arc
		(start 9.400032 -116.339874)
		(mid 7.600188 -114.54003)
		(end 5.80009 -116.339874)
		(stroke
			(width 0.05)
			(type default)
		)
		(layer "Edge.Cuts")
	)
	(gr_arc
		(start 9.400032 -28.299918)
		(mid 7.600188 -26.500074)
		(end 5.80009 -28.299918)
		(stroke
			(width 0.05)
			(type default)
		)
		(layer "Edge.Cuts")
	)
	(gr_arc
		(start 9.400032 -6.299962)
		(mid 7.600188 -4.500118)
		(end 5.80009 -6.299962)
		(stroke
			(width 0.05)
			(type default)
		)
		(layer "Edge.Cuts")
	)
	(gr_arc
		(start 10.54989 -482.700076)
		(mid 11.999976 -484.150162)
		(end 13.450062 -482.700076)
		(stroke
			(width 0.05)
			(type default)
		)
		(layer "Edge.Cuts")
	)
	(gr_arc
		(start 10.54989 -372.65991)
		(mid 11.999976 -374.109996)
		(end 13.450062 -372.65991)
		(stroke
			(width 0.05)
			(type default)
		)
		(layer "Edge.Cuts")
	)
	(gr_arc
		(start 10.54989 -306.660042)
		(mid 11.999976 -308.110128)
		(end 13.450062 -306.660042)
		(stroke
			(width 0.05)
			(type default)
		)
		(layer "Edge.Cuts")
	)
	(gr_arc
		(start 10.54989 -193.339974)
		(mid 11.999976 -194.79006)
		(end 13.450062 -193.339974)
		(stroke
			(width 0.05)
			(type default)
		)
		(layer "Edge.Cuts")
	)
	(gr_arc
		(start 10.54989 -127.340106)
		(mid 11.999976 -128.790192)
		(end 13.450062 -127.340106)
		(stroke
			(width 0.05)
			(type default)
		)
		(layer "Edge.Cuts")
	)
	(gr_arc
		(start 10.54989 -17.29994)
		(mid 11.999976 -18.750026)
		(end 13.450062 -17.29994)
		(stroke
			(width 0.05)
			(type default)
		)
		(layer "Edge.Cuts")
	)
	(gr_arc
		(start 13.450062 -482.700076)
		(mid 11.999976 -481.24999)
		(end 10.54989 -482.700076)
		(stroke
			(width 0.05)
			(type default)
		)
		(layer "Edge.Cuts")
	)
	(gr_arc
		(start 13.450062 -372.65991)
		(mid 11.999976 -371.209824)
		(end 10.54989 -372.65991)
		(stroke
			(width 0.05)
			(type default)
		)
		(layer "Edge.Cuts")
	)
	(gr_arc
		(start 13.450062 -306.660042)
		(mid 11.999976 -305.209956)
		(end 10.54989 -306.660042)
		(stroke
			(width 0.05)
			(type default)
		)
		(layer "Edge.Cuts")
	)
	(gr_arc
		(start 13.450062 -193.339974)
		(mid 11.999976 -191.889888)
		(end 10.54989 -193.339974)
		(stroke
			(width 0.05)
			(type default)
		)
		(layer "Edge.Cuts")
	)
	(gr_arc
		(start 13.450062 -127.340106)
		(mid 11.999976 -125.89002)
		(end 10.54989 -127.340106)
		(stroke
			(width 0.05)
			(type default)
		)
		(layer "Edge.Cuts")
	)
	(gr_arc
		(start 13.450062 -17.29994)
		(mid 11.999976 -15.849854)
		(end 10.54989 -17.29994)
		(stroke
			(width 0.05)
			(type default)
		)
		(layer "Edge.Cuts")
	)
	(gr_line
		(start 16.500094 -500.000016)
		(end 0.999998 -500.000016)
		(stroke
			(width 0.05)
			(type default)
		)
		(layer "Edge.Cuts")
	)
	(gr_arc
		(start 16.500094 -500.000016)
		(mid 17.20721 -499.707127)
		(end 17.500092 -499.000018)
		(stroke
			(width 0.05)
			(type default)
		)
		(layer "Edge.Cuts")
	)
	(gr_line
		(start 17.500092 -491.000034)
		(end 17.500092 -499.000018)
		(stroke
			(width 0.05)
			(type default)
		)
		(layer "Edge.Cuts")
	)
	(gr_arc
		(start 17.500092 -8.999982)
		(mid 17.792985 -9.707087)
		(end 18.50009 -9.99998)
		(stroke
			(width 0.05)
			(type default)
		)
		(layer "Edge.Cuts")
	)
	(gr_arc
		(start 17.500092 -0.999998)
		(mid 17.207198 -0.292896)
		(end 16.500094 0)
		(stroke
			(width 0.05)
			(type default)
		)
		(layer "Edge.Cuts")
	)
	(gr_line
		(start 17.500092 -0.999998)
		(end 17.500092 -8.999982)
		(stroke
			(width 0.05)
			(type default)
		)
		(layer "Edge.Cuts")
	)
	(gr_arc
		(start 18.50009 -490.000036)
		(mid 17.792985 -490.292929)
		(end 17.500092 -491.000034)
		(stroke
			(width 0.05)
			(type default)
		)
		(layer "Edge.Cuts")
	)
	(gr_line
		(start 18.50009 -9.99998)
		(end 51.500024 -9.99998)
		(stroke
			(width 0.05)
			(type default)
		)
		(layer "Edge.Cuts")
	)
	(gr_arc
		(start 24.500078 -465.549996)
		(mid 26.999946 -463.050128)
		(end 24.500078 -460.550006)
		(stroke
			(width 0.05)
			(type default)
		)
		(layer "Edge.Cuts")
	)
	(gr_arc
		(start 24.500078 -460.550006)
		(mid 21.999956 -463.050128)
		(end 24.500078 -465.549996)
		(stroke
			(width 0.05)
			(type default)
		)
		(layer "Edge.Cuts")
	)
	(gr_arc
		(start 24.500078 -446.449958)
		(mid 26.999946 -443.95009)
		(end 24.500078 -441.449968)
		(stroke
			(width 0.05)
			(type default)
		)
		(layer "Edge.Cuts")
	)
	(gr_arc
		(start 24.500078 -441.449968)
		(mid 21.999956 -443.95009)
		(end 24.500078 -446.449958)
		(stroke
			(width 0.05)
			(type default)
		)
		(layer "Edge.Cuts")
	)
	(gr_arc
		(start 40.999918 -465.549996)
		(mid 43.499786 -463.050128)
		(end 40.999918 -460.550006)
		(stroke
			(width 0.05)
			(type default)
		)
		(layer "Edge.Cuts")
	)
	(gr_arc
		(start 40.999918 -460.550006)
		(mid 38.499796 -463.050128)
		(end 40.999918 -465.549996)
		(stroke
			(width 0.05)
			(type default)
		)
		(layer "Edge.Cuts")
	)
	(gr_arc
		(start 40.999918 -446.449958)
		(mid 43.499786 -443.95009)
		(end 40.999918 -441.449968)
		(stroke
			(width 0.05)
			(type default)
		)
		(layer "Edge.Cuts")
	)
	(gr_arc
		(start 40.999918 -441.449968)
		(mid 38.499796 -443.95009)
		(end 40.999918 -446.449958)
		(stroke
			(width 0.05)
			(type default)
		)
		(layer "Edge.Cuts")
	)
	(gr_arc
		(start 43.50004 -480.000056)
		(mid 45.500036 -482.000052)
		(end 47.500032 -480.000056)
		(stroke
			(width 0.05)
			(type default)
		)
		(layer "Edge.Cuts")
	)
	(gr_arc
		(start 43.749976 -294.999918)
		(mid 45.500036 -296.749978)
		(end 47.250096 -294.999918)
		(stroke
			(width 0.05)
			(type default)
		)
		(layer "Edge.Cuts")
	)
	(gr_arc
		(start 43.749976 -144.999964)
		(mid 45.500036 -146.750024)
		(end 47.250096 -144.999964)
		(stroke
			(width 0.05)
			(type default)
		)
		(layer "Edge.Cuts")
	)
	(gr_arc
		(start 43.749976 -19.99996)
		(mid 45.500036 -21.75002)
		(end 47.250096 -19.99996)
		(stroke
			(width 0.05)
			(type default)
		)
		(layer "Edge.Cuts")
	)
	(gr_arc
		(start 45.449998 -340.000082)
		(mid 47.949866 -337.500214)
		(end 45.449998 -335.000092)
		(stroke
			(width 0.05)
			(type default)
		)
		(layer "Edge.Cuts")
	)
	(gr_arc
		(start 45.449998 -335.000092)
		(mid 42.949876 -337.500214)
		(end 45.449998 -340.000082)
		(stroke
			(width 0.05)
			(type default)
		)
		(layer "Edge.Cuts")
	)
	(gr_arc
		(start 47.250096 -294.999918)
		(mid 45.500036 -293.249858)
		(end 43.749976 -294.999918)
		(stroke
			(width 0.05)
			(type default)
		)
		(layer "Edge.Cuts")
	)
	(gr_arc
		(start 47.250096 -144.999964)
		(mid 45.500036 -143.249904)
		(end 43.749976 -144.999964)
		(stroke
			(width 0.05)
			(type default)
		)
		(layer "Edge.Cuts")
	)
	(gr_arc
		(start 47.250096 -19.99996)
		(mid 45.500036 -18.2499)
		(end 43.749976 -19.99996)
		(stroke
			(width 0.05)
			(type default)
		)
		(layer "Edge.Cuts")
	)
	(gr_arc
		(start 47.500032 -480.000056)
		(mid 45.500036 -478.00006)
		(end 43.50004 -480.000056)
		(stroke
			(width 0.05)
			(type default)
		)
		(layer "Edge.Cuts")
	)
	(gr_line
		(start 51.500024 -490.000036)
		(end 18.50009 -490.000036)
		(stroke
			(width 0.05)
			(type default)
		)
		(layer "Edge.Cuts")
	)
	(gr_arc
		(start 51.500024 -490.000036)
		(mid 52.207127 -489.707137)
		(end 52.500022 -489.000038)
		(stroke
			(width 0.05)
			(type default)
		)
		(layer "Edge.Cuts")
	)
	(gr_arc
		(start 52.500022 -10.999978)
		(mid 52.207123 -10.292878)
		(end 51.500024 -9.99998)
		(stroke
			(width 0.05)
			(type default)
		)
		(layer "Edge.Cuts")
	)
	(gr_line
		(start 52.500022 -10.999978)
		(end 52.500022 -489.000038)
		(stroke
			(width 0.05)
			(type default)
		)
		(layer "Edge.Cuts")
	)
	(segment
		(start 27.3558 -356.87)
		(end 27.7368 -356.489)
		(width 0.1397)
		(layer "F.Cu")
		(net "TEMP_ALM#_G")
	)
	(segment
		(start 26.4287 -357.6574)
		(end 26.4287 -357.2637)
		(width 0.1397)
		(layer "F.Cu")
		(net "TEMP_ALM#_G")
	)
	(segment
		(start 27.7368 -355.07676)
		(end 27.5336 -354.87356)
		(width 0.1397)
		(layer "F.Cu")
		(net "TEMP_ALM#_G")
	)
	(segment
		(start 27.0256 -355.5238)
		(end 27.5082 -355.5238)
		(width 0.1397)
		(layer "F.Cu")
		(net "TEMP_ALM#_G")
	)
	(segment
		(start 25.273 -357.505)
		(end 25.4254 -357.6574)
		(width 0.1397)
		(layer "F.Cu")
		(net "TEMP_ALM#_G")
	)
	(segment
		(start 27.7368 -355.7524)
		(end 27.7368 -355.07676)
		(width 0.1397)
		(layer "F.Cu")
		(net "TEMP_ALM#_G")
	)
	(segment
		(start 26.8224 -356.87)
		(end 27.3558 -356.87)
		(width 0.1397)
		(layer "F.Cu")
		(net "TEMP_ALM#_G")
	)
	(segment
		(start 25.4254 -357.6574)
		(end 26.4287 -357.6574)
		(width 0.1397)
		(layer "F.Cu")
		(net "TEMP_ALM#_G")
	)
	(segment
		(start 27.5336 -354.87356)
		(end 27.0256 -354.87356)
		(width 0.1397)
		(layer "F.Cu")
		(net "TEMP_ALM#_G")
	)
	(segment
		(start 27.7368 -356.489)
		(end 27.7368 -355.7524)
		(width 0.1397)
		(layer "F.Cu")
		(net "TEMP_ALM#_G")
	)
	(segment
		(start 26.4287 -357.2637)
		(end 26.8224 -356.87)
		(width 0.1397)
		(layer "F.Cu")
		(net "TEMP_ALM#_G")
	)
	(segment
		(start 27.5082 -355.5238)
		(end 27.7368 -355.7524)
		(width 0.1397)
		(layer "F.Cu")
		(net "TEMP_ALM#_G")
	)
	(via
		(at 25.273 -357.505)
		(size 0.7112)
		(drill 0.3556)
		(layers "F.Cu" "B.Cu")
		(net "TEMP_ALM#_G")
	)
	(segment
		(start 28.9052 -356.17404)
		(end 29.39796 -356.17404)
		(width 0.1397)
		(layer "F.Cu")
		(net "TEMP_ALM#_JP_2")
	)
	(segment
		(start 29.39796 -356.17404)
		(end 29.819346 -355.752654)
		(width 0.1397)
		(layer "F.Cu")
		(net "TEMP_ALM#_JP_2")
	)
	(segment
		(start 25.273 -350.647)
		(end 41.91 -350.647)
		(width 0.1397)
		(layer "F.Cu")
		(net "TEMP_ALM#_JP_2")
	)
	(segment
		(start 29.819346 -355.752654)
		(end 29.819346 -354.076)
		(width 0.1397)
		(layer "F.Cu")
		(net "TEMP_ALM#_JP_2")
	)
	(segment
		(start 29.311346 -353.568)
		(end 25.146 -353.568)
		(width 0.1397)
		(layer "F.Cu")
		(net "TEMP_ALM#_JP_2")
	)
	(segment
		(start 24.765 -351.155)
		(end 25.273 -350.647)
		(width 0.1397)
		(layer "F.Cu")
		(net "TEMP_ALM#_JP_2")
	)
	(segment
		(start 24.765 -353.187)
		(end 24.765 -351.155)
		(width 0.1397)
		(layer "F.Cu")
		(net "TEMP_ALM#_JP_2")
	)
	(segment
		(start 25.146 -353.568)
		(end 24.765 -353.187)
		(width 0.1397)
		(layer "F.Cu")
		(net "TEMP_ALM#_JP_2")
	)
	(segment
		(start 29.819346 -354.076)
		(end 29.311346 -353.568)
		(width 0.1397)
		(layer "F.Cu")
		(net "TEMP_ALM#_JP_2")
	)
	(segment
		(start 39.987474 -362.415074)
		(end 39.784274 -362.618274)
		(width 0.1397)
		(layer "F.Cu")
		(net "TEMP_ALM#_JP_1")
	)
	(segment
		(start 40.851074 -362.415074)
		(end 39.987474 -362.415074)
		(width 0.1397)
		(layer "F.Cu")
		(net "TEMP_ALM#_JP_1")
	)
	(segment
		(start 39.7002 -361.5436)
		(end 43.1546 -358.0892)
		(width 0.1397)
		(layer "F.Cu")
		(net "TEMP_ALM#_JP_1")
	)
	(segment
		(start 39.784274 -362.618274)
		(end 39.784274 -361.818174)
		(width 0.1397)
		(layer "F.Cu")
		(net "TEMP_ALM#_JP_1")
	)
	(segment
		(start 39.5097 -361.5436)
		(end 39.7002 -361.5436)
		(width 0.1397)
		(layer "F.Cu")
		(net "TEMP_ALM#_JP_1")
	)
	(segment
		(start 39.784274 -361.818174)
		(end 39.5097 -361.5436)
		(width 0.1397)
		(layer "F.Cu")
		(net "TEMP_ALM#_JP_1")
	)
	(segment
		(start 43.1546 -349.3516)
		(end 41.91 -348.107)
		(width 0.1397)
		(layer "F.Cu")
		(net "TEMP_ALM#_JP_1")
	)
	(segment
		(start 43.1546 -358.0892)
		(end 43.1546 -349.3516)
		(width 0.1397)
		(layer "F.Cu")
		(net "TEMP_ALM#_JP_1")
	)
	(segment
		(start 34.29 -358.8766)
		(end 34.29 -358.610916)
		(width 0.1397)
		(layer "F.Cu")
		(net "OTP_RETRY_DIODE")
	)
	(segment
		(start 33.39465 -359.77195)
		(end 34.29 -358.8766)
		(width 0.1397)
		(layer "F.Cu")
		(net "OTP_RETRY_DIODE")
	)
	(segment
		(start 34.29 -358.610916)
		(end 35.392868 -358.610916)
		(width 0.1397)
		(layer "F.Cu")
		(net "OTP_RETRY_DIODE")
	)
	(segment
		(start 35.392868 -358.610916)
		(end 35.8394 -358.164384)
		(width 0.1397)
		(layer "F.Cu")
		(net "OTP_RETRY_DIODE")
	)
	(segment
		(start 32.766 -359.77195)
		(end 33.39465 -359.77195)
		(width 0.1397)
		(layer "F.Cu")
		(net "OTP_RETRY_DIODE")
	)
	(via
		(at 32.766 -359.77195)
		(size 0.7112)
		(drill 0.3556)
		(layers "F.Cu" "B.Cu")
		(net "OTP_RETRY_DIODE")
	)
	(segment
		(start 37.9222 -356.8954)
		(end 37.59835 -356.57155)
		(width 0.1397)
		(layer "F.Cu")
		(net "OTP_RETRY_B")
	)
	(segment
		(start 38.3794 -355.1174)
		(end 37.59835 -355.89845)
		(width 0.1397)
		(layer "F.Cu")
		(net "OTP_RETRY_B")
	)
	(segment
		(start 37.59835 -355.89845)
		(end 37.59835 -355.969316)
		(width 0.1397)
		(layer "F.Cu")
		(net "OTP_RETRY_B")
	)
	(segment
		(start 41.148 -356.8954)
		(end 37.9222 -356.8954)
		(width 0.1397)
		(layer "F.Cu")
		(net "OTP_RETRY_B")
	)
	(segment
		(start 40.13835 -360.4768)
		(end 41.529 -359.08615)
		(width 0.1397)
		(layer "F.Cu")
		(net "OTP_RETRY_B")
	)
	(segment
		(start 37.59835 -356.57155)
		(end 37.59835 -355.969316)
		(width 0.1397)
		(layer "F.Cu")
		(net "OTP_RETRY_B")
	)
	(segment
		(start 38.3794 -354.165916)
		(end 38.3794 -355.1174)
		(width 0.1397)
		(layer "F.Cu")
		(net "OTP_RETRY_B")
	)
	(segment
		(start 38.469316 -354.076)
		(end 41.021 -354.076)
		(width 0.1397)
		(layer "F.Cu")
		(net "OTP_RETRY_B")
	)
	(segment
		(start 39.508684 -360.4768)
		(end 40.13835 -360.4768)
		(width 0.1397)
		(layer "F.Cu")
		(net "OTP_RETRY_B")
	)
	(segment
		(start 41.021 -354.076)
		(end 41.91 -353.187)
		(width 0.1397)
		(layer "F.Cu")
		(net "OTP_RETRY_B")
	)
	(segment
		(start 41.529 -357.2764)
		(end 41.148 -356.8954)
		(width 0.1397)
		(layer "F.Cu")
		(net "OTP_RETRY_B")
	)
	(segment
		(start 38.469316 -354.076)
		(end 38.3794 -354.165916)
		(width 0.1397)
		(layer "F.Cu")
		(net "OTP_RETRY_B")
	)
	(segment
		(start 41.529 -359.08615)
		(end 41.529 -357.2764)
		(width 0.1397)
		(layer "F.Cu")
		(net "OTP_RETRY_B")
	)
	(segment
		(start 40.582596 -359.250996)
		(end 40.423592 -359.41)
		(width 0.1397)
		(layer "F.Cu")
		(net "OTP_RETRY_C")
	)
	(segment
		(start 39.508684 -359.41)
		(end 39.508684 -358.8004)
		(width 0.1397)
		(layer "F.Cu")
		(net "OTP_RETRY_C")
	)
	(segment
		(start 38.5826 -357.874316)
		(end 37.682932 -357.874316)
		(width 0.1397)
		(layer "F.Cu")
		(net "OTP_RETRY_C")
	)
	(segment
		(start 37.682932 -357.874316)
		(end 35.8394 -356.030784)
		(width 0.1397)
		(layer "F.Cu")
		(net "OTP_RETRY_C")
	)
	(segment
		(start 39.508684 -358.8004)
		(end 38.5826 -357.874316)
		(width 0.1397)
		(layer "F.Cu")
		(net "OTP_RETRY_C")
	)
	(segment
		(start 40.423592 -359.41)
		(end 39.508684 -359.41)
		(width 0.1397)
		(layer "F.Cu")
		(net "OTP_RETRY_C")
	)
	(via
		(at 40.582596 -359.250996)
		(size 0.7112)
		(drill 0.3556)
		(layers "F.Cu" "B.Cu")
		(net "OTP_RETRY_C")
	)
	(segment
		(start 29.718 -352.425)
		(end 30.226 -351.917)
		(width 0.1397)
		(layer "F.Cu")
		(net "OTP_RETRY_G")
	)
	(segment
		(start 34.403284 -356.629716)
		(end 34.2138 -356.629716)
		(width 0.1397)
		(layer "F.Cu")
		(net "OTP_RETRY_G")
	)
	(segment
		(start 30.226 -351.917)
		(end 31.206948 -351.917)
		(width 0.1397)
		(layer "F.Cu")
		(net "OTP_RETRY_G")
	)
	(segment
		(start 30.353 -355.683566)
		(end 30.353 -353.568)
		(width 0.1397)
		(layer "F.Cu")
		(net "OTP_RETRY_G")
	)
	(segment
		(start 36.322 -352.425)
		(end 35.433 -353.314)
		(width 0.1397)
		(layer "F.Cu")
		(net "OTP_RETRY_G")
	)
	(segment
		(start 35.814 -351.917)
		(end 36.322 -352.425)
		(width 0.1397)
		(layer "F.Cu")
		(net "OTP_RETRY_G")
	)
	(segment
		(start 35.433 -353.314)
		(end 34.796984 -353.314)
		(width 0.1397)
		(layer "F.Cu")
		(net "OTP_RETRY_G")
	)
	(segment
		(start 34.925 -356.108)
		(end 34.403284 -356.629716)
		(width 0.1397)
		(layer "F.Cu")
		(net "OTP_RETRY_G")
	)
	(segment
		(start 31.206948 -351.917)
		(end 35.814 -351.917)
		(width 0.1397)
		(layer "F.Cu")
		(net "OTP_RETRY_G")
	)
	(segment
		(start 29.718 -352.933)
		(end 29.718 -352.425)
		(width 0.1397)
		(layer "F.Cu")
		(net "OTP_RETRY_G")
	)
	(segment
		(start 34.925 -354.102416)
		(end 34.925 -356.108)
		(width 0.1397)
		(layer "F.Cu")
		(net "OTP_RETRY_G")
	)
	(segment
		(start 34.466784 -353.6442)
		(end 34.925 -354.102416)
		(width 0.1397)
		(layer "F.Cu")
		(net "OTP_RETRY_G")
	)
	(segment
		(start 34.796984 -353.314)
		(end 34.466784 -353.6442)
		(width 0.1397)
		(layer "F.Cu")
		(net "OTP_RETRY_G")
	)
	(segment
		(start 34.29 -357.721916)
		(end 34.29 -356.705916)
		(width 0.1397)
		(layer "F.Cu")
		(net "OTP_RETRY_G")
	)
	(segment
		(start 30.353 -353.568)
		(end 29.718 -352.933)
		(width 0.1397)
		(layer "F.Cu")
		(net "OTP_RETRY_G")
	)
	(segment
		(start 34.29 -356.705916)
		(end 34.2138 -356.629716)
		(width 0.1397)
		(layer "F.Cu")
		(net "OTP_RETRY_G")
	)
	(segment
		(start 30.76575 -356.096316)
		(end 30.353 -355.683566)
		(width 0.1397)
		(layer "F.Cu")
		(net "OTP_RETRY_G")
	)
	(via
		(at 31.206948 -351.917)
		(size 0.7112)
		(drill 0.3556)
		(layers "F.Cu" "B.Cu")
		(net "OTP_RETRY_G")
	)
	(segment
		(start 33.8455 -362.7882)
		(end 34.3027 -362.331)
		(width 0.1397)
		(layer "F.Cu")
		(net "TEMP_ALM#_REVERSE_R")
	)
	(segment
		(start 36.195 -360.807)
		(end 35.745674 -361.256326)
		(width 0.1397)
		(layer "F.Cu")
		(net "TEMP_ALM#_REVERSE_R")
	)
	(segment
		(start 36.818316 -365.0615)
		(end 35.484816 -363.728)
		(width 0.1397)
		(layer "F.Cu")
		(net "TEMP_ALM#_REVERSE_R")
	)
	(segment
		(start 36.5506 -362.1532)
		(end 39.650416 -365.253016)
		(width 0.1397)
		(layer "F.Cu")
		(net "TEMP_ALM#_REVERSE_R")
	)
	(segment
		(start 34.3027 -362.331)
		(end 34.771076 -362.331)
		(width 0.1397)
		(layer "F.Cu")
		(net "TEMP_ALM#_REVERSE_R")
	)
	(segment
		(start 15.3924 -49.5427)
		(end 15.3924 -50.5587)
		(width 0.1397)
		(layer "F.Cu")
		(net "TEMP_ALM#_REVERSE_R")
	)
	(segment
		(start 16.6751 -49.5427)
		(end 17.907 -48.3108)
		(width 0.1397)
		(layer "F.Cu")
		(net "TEMP_ALM#_REVERSE_R")
	)
	(segment
		(start 36.195 -360.807)
		(end 36.5506 -361.1626)
		(width 0.1397)
		(layer "F.Cu")
		(net "TEMP_ALM#_REVERSE_R")
	)
	(segment
		(start 36.5506 -361.1626)
		(end 36.5506 -362.1532)
		(width 0.1397)
		(layer "F.Cu")
		(net "TEMP_ALM#_REVERSE_R")
	)
	(segment
		(start 34.771076 -362.331)
		(end 35.228276 -361.8738)
		(width 0.1397)
		(layer "F.Cu")
		(net "TEMP_ALM#_REVERSE_R")
	)
	(segment
		(start 15.3924 -49.5427)
		(end 16.6751 -49.5427)
		(width 0.1397)
		(layer "F.Cu")
		(net "TEMP_ALM#_REVERSE_R")
	)
	(segment
		(start 39.650416 -365.253016)
		(end 40.2844 -365.253016)
		(width 0.1397)
		(layer "F.Cu")
		(net "TEMP_ALM#_REVERSE_R")
	)
	(segment
		(start 15.3924 -50.5587)
		(end 15.3289 -50.6222)
		(width 0.1397)
		(layer "F.Cu")
		(net "TEMP_ALM#_REVERSE_R")
	)
	(segment
		(start 33.8455 -362.7882)
		(end 33.8455 -363.728)
		(width 0.1397)
		(layer "F.Cu")
		(net "TEMP_ALM#_REVERSE_R")
	)
	(segment
		(start 37.465 -365.0615)
		(end 36.818316 -365.0615)
		(width 0.1397)
		(layer "F.Cu")
		(net "TEMP_ALM#_REVERSE_R")
	)
	(segment
		(start 35.745674 -361.256326)
		(end 35.228276 -361.256326)
		(width 0.1397)
		(layer "F.Cu")
		(net "TEMP_ALM#_REVERSE_R")
	)
	(segment
		(start 35.228276 -361.8738)
		(end 35.228276 -361.256326)
		(width 0.1397)
		(layer "F.Cu")
		(net "TEMP_ALM#_REVERSE_R")
	)
	(segment
		(start 35.484816 -363.728)
		(end 33.8455 -363.728)
		(width 0.1397)
		(layer "F.Cu")
		(net "TEMP_ALM#_REVERSE_R")
	)
	(via
		(at 48.769778 -122.578622)
		(size 0.7112)
		(drill 0.3556)
		(layers "F.Cu" "B.Cu")
		(net "TEMP_ALM#_REVERSE_R")
	)
	(via
		(at 36.195 -360.807)
		(size 0.5588)
		(drill 0.3048)
		(layers "F.Cu" "B.Cu")
		(net "TEMP_ALM#_REVERSE_R")
	)
	(via
		(at 17.907 -48.3108)
		(size 0.5588)
		(drill 0.3048)
		(layers "F.Cu" "B.Cu")
		(net "TEMP_ALM#_REVERSE_R")
	)
	(segment
		(start 46.6852 -157.0482)
		(end 38.43655 -148.79955)
		(width 0.1397)
		(layer "B.Cu")
		(net "TEMP_ALM#_REVERSE_R")
	)
	(segment
		(start 46.546516 -66.180716)
		(end 45.238162 -66.180716)
		(width 0.1397)
		(layer "B.Cu")
		(net "TEMP_ALM#_REVERSE_R")
	)
	(segment
		(start 42.70375 -193.472054)
		(end 42.70375 -185.521854)
		(width 0.1397)
		(layer "B.Cu")
		(net "TEMP_ALM#_REVERSE_R")
	)
	(segment
		(start 42.1132 -57.023)
		(end 40.724836 -55.634636)
		(width 0.1397)
		(layer "B.Cu")
		(net "TEMP_ALM#_REVERSE_R")
	)
	(segment
		(start 43.7642 -184.461404)
		(end 43.7642 -177.1904)
		(width 0.1397)
		(layer "B.Cu")
		(net "TEMP_ALM#_REVERSE_R")
	)
	(segment
		(start 45.9994 -174.9552)
		(end 45.9994 -163.6776)
		(width 0.1397)
		(layer "B.Cu")
		(net "TEMP_ALM#_REVERSE_R")
	)
	(segment
		(start 29.591 -47.371)
		(end 22.909022 -47.371)
		(width 0.1397)
		(layer "B.Cu")
		(net "TEMP_ALM#_REVERSE_R")
	)
	(segment
		(start 46.81855 -135.0264)
		(end 46.81855 -124.52985)
		(width 0.1397)
		(layer "B.Cu")
		(net "TEMP_ALM#_REVERSE_R")
	)
	(segment
		(start 44.69892 -65.32372)
		(end 42.1132 -62.738)
		(width 0.1397)
		(layer "B.Cu")
		(net "TEMP_ALM#_REVERSE_R")
	)
	(segment
		(start 36.195 -360.807)
		(end 36.195 -279.654)
		(width 0.1397)
		(layer "B.Cu")
		(net "TEMP_ALM#_REVERSE_R")
	)
	(segment
		(start 49.47285 -69.10705)
		(end 46.546516 -66.180716)
		(width 0.1397)
		(layer "B.Cu")
		(net "TEMP_ALM#_REVERSE_R")
	)
	(segment
		(start 48.769778 -122.578622)
		(end 50.419 -120.9294)
		(width 0.1397)
		(layer "B.Cu")
		(net "TEMP_ALM#_REVERSE_R")
	)
	(segment
		(start 46.81855 -124.52985)
		(end 48.769778 -122.578622)
		(width 0.1397)
		(layer "B.Cu")
		(net "TEMP_ALM#_REVERSE_R")
	)
	(segment
		(start 46.31055 -240.72215)
		(end 46.31055 -197.078854)
		(width 0.1397)
		(layer "B.Cu")
		(net "TEMP_ALM#_REVERSE_R")
	)
	(segment
		(start 37.854636 -55.634636)
		(end 29.591 -47.371)
		(width 0.1397)
		(layer "B.Cu")
		(net "TEMP_ALM#_REVERSE_R")
	)
	(segment
		(start 36.195 -279.654)
		(end 37.846 -278.003)
		(width 0.1397)
		(layer "B.Cu")
		(net "TEMP_ALM#_REVERSE_R")
	)
	(segment
		(start 20.881594 -45.279056)
		(end 20.118578 -45.279056)
		(width 0.1397)
		(layer "B.Cu")
		(net "TEMP_ALM#_REVERSE_R")
	)
	(segment
		(start 46.78045 -241.19205)
		(end 46.31055 -240.72215)
		(width 0.1397)
		(layer "B.Cu")
		(net "TEMP_ALM#_REVERSE_R")
	)
	(segment
		(start 20.118578 -45.279056)
		(end 17.907 -47.490634)
		(width 0.1397)
		(layer "B.Cu")
		(net "TEMP_ALM#_REVERSE_R")
	)
	(segment
		(start 44.69892 -65.641474)
		(end 44.69892 -65.32372)
		(width 0.1397)
		(layer "B.Cu")
		(net "TEMP_ALM#_REVERSE_R")
	)
	(segment
		(start 49.47285 -106.90225)
		(end 49.47285 -69.10705)
		(width 0.1397)
		(layer "B.Cu")
		(net "TEMP_ALM#_REVERSE_R")
	)
	(segment
		(start 49.93005 -112.49025)
		(end 49.93005 -107.35945)
		(width 0.1397)
		(layer "B.Cu")
		(net "TEMP_ALM#_REVERSE_R")
	)
	(segment
		(start 43.7642 -177.1904)
		(end 45.9994 -174.9552)
		(width 0.1397)
		(layer "B.Cu")
		(net "TEMP_ALM#_REVERSE_R")
	)
	(segment
		(start 17.907 -47.490634)
		(end 17.907 -48.3108)
		(width 0.1397)
		(layer "B.Cu")
		(net "TEMP_ALM#_REVERSE_R")
	)
	(segment
		(start 21.4376 -45.835062)
		(end 20.881594 -45.279056)
		(width 0.1397)
		(layer "B.Cu")
		(net "TEMP_ALM#_REVERSE_R")
	)
	(segment
		(start 46.78045 -249.99315)
		(end 46.78045 -241.19205)
		(width 0.1397)
		(layer "B.Cu")
		(net "TEMP_ALM#_REVERSE_R")
	)
	(segment
		(start 38.43655 -148.79955)
		(end 38.43655 -143.4084)
		(width 0.1397)
		(layer "B.Cu")
		(net "TEMP_ALM#_REVERSE_R")
	)
	(segment
		(start 37.846 -278.003)
		(end 37.846 -261.493)
		(width 0.1397)
		(layer "B.Cu")
		(net "TEMP_ALM#_REVERSE_R")
	)
	(segment
		(start 45.238162 -66.180716)
		(end 44.69892 -65.641474)
		(width 0.1397)
		(layer "B.Cu")
		(net "TEMP_ALM#_REVERSE_R")
	)
	(segment
		(start 45.72 -251.0536)
		(end 46.78045 -249.99315)
		(width 0.1397)
		(layer "B.Cu")
		(net "TEMP_ALM#_REVERSE_R")
	)
	(segment
		(start 45.72 -253.619)
		(end 45.72 -251.0536)
		(width 0.1397)
		(layer "B.Cu")
		(net "TEMP_ALM#_REVERSE_R")
	)
	(segment
		(start 46.31055 -197.078854)
		(end 42.70375 -193.472054)
		(width 0.1397)
		(layer "B.Cu")
		(net "TEMP_ALM#_REVERSE_R")
	)
	(segment
		(start 37.846 -261.493)
		(end 45.72 -253.619)
		(width 0.1397)
		(layer "B.Cu")
		(net "TEMP_ALM#_REVERSE_R")
	)
	(segment
		(start 45.9994 -163.6776)
		(end 46.6852 -162.9918)
		(width 0.1397)
		(layer "B.Cu")
		(net "TEMP_ALM#_REVERSE_R")
	)
	(segment
		(start 50.419 -112.9792)
		(end 49.93005 -112.49025)
		(width 0.1397)
		(layer "B.Cu")
		(net "TEMP_ALM#_REVERSE_R")
	)
	(segment
		(start 22.909022 -47.371)
		(end 21.4376 -45.899578)
		(width 0.1397)
		(layer "B.Cu")
		(net "TEMP_ALM#_REVERSE_R")
	)
	(segment
		(start 49.93005 -107.35945)
		(end 49.47285 -106.90225)
		(width 0.1397)
		(layer "B.Cu")
		(net "TEMP_ALM#_REVERSE_R")
	)
	(segment
		(start 40.724836 -55.634636)
		(end 37.854636 -55.634636)
		(width 0.1397)
		(layer "B.Cu")
		(net "TEMP_ALM#_REVERSE_R")
	)
	(segment
		(start 50.419 -120.9294)
		(end 50.419 -112.9792)
		(width 0.1397)
		(layer "B.Cu")
		(net "TEMP_ALM#_REVERSE_R")
	)
	(segment
		(start 46.6852 -162.9918)
		(end 46.6852 -157.0482)
		(width 0.1397)
		(layer "B.Cu")
		(net "TEMP_ALM#_REVERSE_R")
	)
	(segment
		(start 21.4376 -45.899578)
		(end 21.4376 -45.835062)
		(width 0.1397)
		(layer "B.Cu")
		(net "TEMP_ALM#_REVERSE_R")
	)
	(segment
		(start 42.70375 -185.521854)
		(end 43.7642 -184.461404)
		(width 0.1397)
		(layer "B.Cu")
		(net "TEMP_ALM#_REVERSE_R")
	)
	(segment
		(start 42.1132 -62.738)
		(end 42.1132 -57.023)
		(width 0.1397)
		(layer "B.Cu")
		(net "TEMP_ALM#_REVERSE_R")
	)
	(segment
		(start 38.43655 -143.4084)
		(end 46.81855 -135.0264)
		(width 0.1397)
		(layer "B.Cu")
		(net "TEMP_ALM#_REVERSE_R")
	)
	(segment
		(start 15.3289 -47.5742)
		(end 15.573756 -47.819056)
		(width 0.1397)
		(layer "F.Cu")
		(net "SD_LATCH_RELEASE_L")
	)
	(segment
		(start 15.573756 -47.819056)
		(end 29.404056 -47.819056)
		(width 0.1397)
		(layer "F.Cu")
		(net "SD_LATCH_RELEASE_L")
	)
	(segment
		(start 37.219636 -55.634636)
		(end 38.9001 -55.634636)
		(width 0.1397)
		(layer "F.Cu")
		(net "SD_LATCH_RELEASE_L")
	)
	(segment
		(start 39.0906 -55.825136)
		(end 44.254674 -55.825136)
		(width 0.1397)
		(layer "F.Cu")
		(net "SD_LATCH_RELEASE_L")
	)
	(segment
		(start 44.254674 -55.825136)
		(end 45.619924 -54.459886)
		(width 0.1397)
		(layer "F.Cu")
		(net "SD_LATCH_RELEASE_L")
	)
	(segment
		(start 15.3289 -47.5742)
		(end 15.3289 -48.5902)
		(width 0.1397)
		(layer "F.Cu")
		(net "SD_LATCH_RELEASE_L")
	)
	(segment
		(start 29.404056 -47.819056)
		(end 37.219636 -55.634636)
		(width 0.1397)
		(layer "F.Cu")
		(net "SD_LATCH_RELEASE_L")
	)
	(segment
		(start 15.3289 -48.5902)
		(end 15.3924 -48.6537)
		(width 0.1397)
		(layer "F.Cu")
		(net "SD_LATCH_RELEASE_L")
	)
	(segment
		(start 38.9001 -55.634636)
		(end 39.0906 -55.825136)
		(width 0.1397)
		(layer "F.Cu")
		(net "SD_LATCH_RELEASE_L")
	)
	(segment
		(start 14.8209 -51.0032)
		(end 14.4399 -50.6222)
		(width 0.1397)
		(layer "F.Cu")
		(net "SD_LATCH_RELEASE_U")
	)
	(segment
		(start 14.95425 -51.09845)
		(end 14.859 -51.0032)
		(width 0.1397)
		(layer "F.Cu")
		(net "SD_LATCH_RELEASE_U")
	)
	(segment
		(start 14.4399 -50.6222)
		(end 14.4399 -49.6062)
		(width 0.1397)
		(layer "F.Cu")
		(net "SD_LATCH_RELEASE_U")
	)
	(segment
		(start 14.859 -51.0032)
		(end 14.8209 -51.0032)
		(width 0.1397)
		(layer "F.Cu")
		(net "SD_LATCH_RELEASE_U")
	)
	(segment
		(start 16.256 -50.7238)
		(end 15.88135 -51.09845)
		(width 0.1397)
		(layer "F.Cu")
		(net "SD_LATCH_RELEASE_U")
	)
	(segment
		(start 15.88135 -51.09845)
		(end 14.95425 -51.09845)
		(width 0.1397)
		(layer "F.Cu")
		(net "SD_LATCH_RELEASE_U")
	)
	(segment
		(start 14.4399 -49.6062)
		(end 14.3764 -49.5427)
		(width 0.1397)
		(layer "F.Cu")
		(net "SD_LATCH_RELEASE_U")
	)
	(via
		(at 16.256 -50.7238)
		(size 0.5588)
		(drill 0.3048)
		(layers "F.Cu" "B.Cu")
		(net "SD_LATCH_RELEASE_U")
	)
	(segment
		(start 20.881594 -47.819056)
		(end 21.4376 -48.375062)
		(width 0.1397)
		(layer "B.Cu")
		(net "SD_LATCH_RELEASE_U")
	)
	(segment
		(start 21.4376 -48.439578)
		(end 22.883622 -49.8856)
		(width 0.1397)
		(layer "B.Cu")
		(net "SD_LATCH_RELEASE_U")
	)
	(segment
		(start 20.118578 -47.819056)
		(end 20.881594 -47.819056)
		(width 0.1397)
		(layer "B.Cu")
		(net "SD_LATCH_RELEASE_U")
	)
	(segment
		(start 21.4376 -48.375062)
		(end 21.4376 -48.439578)
		(width 0.1397)
		(layer "B.Cu")
		(net "SD_LATCH_RELEASE_U")
	)
	(segment
		(start 27.178 -53.5178)
		(end 28.120086 -54.459886)
		(width 0.1397)
		(layer "B.Cu")
		(net "SD_LATCH_RELEASE_U")
	)
	(segment
		(start 25.476708 -49.8856)
		(end 27.178 -51.586892)
		(width 0.1397)
		(layer "B.Cu")
		(net "SD_LATCH_RELEASE_U")
	)
	(segment
		(start 22.883622 -49.8856)
		(end 25.476708 -49.8856)
		(width 0.1397)
		(layer "B.Cu")
		(net "SD_LATCH_RELEASE_U")
	)
	(segment
		(start 17.213834 -50.7238)
		(end 20.118578 -47.819056)
		(width 0.1397)
		(layer "B.Cu")
		(net "SD_LATCH_RELEASE_U")
	)
	(segment
		(start 16.256 -50.7238)
		(end 17.213834 -50.7238)
		(width 0.1397)
		(layer "B.Cu")
		(net "SD_LATCH_RELEASE_U")
	)
	(segment
		(start 27.178 -51.586892)
		(end 27.178 -53.5178)
		(width 0.1397)
		(layer "B.Cu")
		(net "SD_LATCH_RELEASE_U")
	)
	(segment
		(start 18.28673 -173.42993)
		(end 18.28673 -173.000924)
		(width 0.1397)
		(layer "F.Cu")
		(net "THERMHOT#_R")
	)
	(segment
		(start 20.3073 -173.2788)
		(end 20.3073 -172.7073)
		(width 0.1397)
		(layer "F.Cu")
		(net "THERMHOT#_R")
	)
	(segment
		(start 20.774914 -172.239686)
		(end 21.2979 -172.239686)
		(width 0.1397)
		(layer "F.Cu")
		(net "THERMHOT#_R")
	)
	(segment
		(start 19.3294 -174.4726)
		(end 18.28673 -173.42993)
		(width 0.1397)
		(layer "F.Cu")
		(net "THERMHOT#_R")
	)
	(segment
		(start 20.3073 -172.7073)
		(end 20.774914 -172.239686)
		(width 0.1397)
		(layer "F.Cu")
		(net "THERMHOT#_R")
	)
	(via
		(at 20.441666 -173.715934)
		(size 0.7112)
		(drill 0.3556)
		(layers "F.Cu" "B.Cu")
		(net "THERMHOT#_R")
	)
	(via
		(at 19.3294 -174.4726)
		(size 0.5588)
		(drill 0.3048)
		(layers "F.Cu" "B.Cu")
		(net "THERMHOT#_R")
	)
	(via
		(at 21.2979 -172.239686)
		(size 0.5588)
		(drill 0.3048)
		(layers "F.Cu" "B.Cu")
		(net "THERMHOT#_R")
	)
	(segment
		(start 19.3294 -174.4726)
		(end 19.685 -174.4726)
		(width 0.1397)
		(layer "B.Cu")
		(net "THERMHOT#_R")
	)
	(segment
		(start 20.441666 -173.715934)
		(end 21.2979 -172.8597)
		(width 0.1397)
		(layer "B.Cu")
		(net "THERMHOT#_R")
	)
	(segment
		(start 21.2979 -172.8597)
		(end 21.2979 -172.239686)
		(width 0.1397)
		(layer "B.Cu")
		(net "THERMHOT#_R")
	)
	(segment
		(start 19.685 -174.4726)
		(end 20.441666 -173.715934)
		(width 0.1397)
		(layer "B.Cu")
		(net "THERMHOT#_R")
	)
	(segment
		(start 28.20924 -216.19464)
		(end 28.321 -216.3064)
		(width 0.1397)
		(layer "F.Cu")
		(net "PWM_BUFFER_IN_FAN3_FAN4")
	)
	(segment
		(start 28.85948 -220.600016)
		(end 28.85948 -219.05468)
		(width 0.1397)
		(layer "F.Cu")
		(net "PWM_BUFFER_IN_FAN3_FAN4")
	)
	(segment
		(start 27.813 -168.4909)
		(end 27.5209 -168.1988)
		(width 0.1397)
		(layer "F.Cu")
		(net "PWM_BUFFER_IN_FAN3_FAN4")
	)
	(segment
		(start 28.956 -168.4909)
		(end 27.813 -168.4909)
		(width 0.1397)
		(layer "F.Cu")
		(net "PWM_BUFFER_IN_FAN3_FAN4")
	)
	(segment
		(start 29.3497 -167.6908)
		(end 28.956 -168.0845)
		(width 0.1397)
		(layer "F.Cu")
		(net "PWM_BUFFER_IN_FAN3_FAN4")
	)
	(segment
		(start 28.20924 -214.961216)
		(end 28.20924 -216.19464)
		(width 0.1397)
		(layer "F.Cu")
		(net "PWM_BUFFER_IN_FAN3_FAN4")
	)
	(segment
		(start 11.0236 -69.1642)
		(end 9.2075 -69.1642)
		(width 0.1397)
		(layer "F.Cu")
		(net "PWM_BUFFER_IN_FAN3_FAN4")
	)
	(segment
		(start 28.956 -168.0845)
		(end 28.956 -168.4909)
		(width 0.1397)
		(layer "F.Cu")
		(net "PWM_BUFFER_IN_FAN3_FAN4")
	)
	(segment
		(start 28.85948 -219.05468)
		(end 28.8036 -218.9988)
		(width 0.1397)
		(layer "F.Cu")
		(net "PWM_BUFFER_IN_FAN3_FAN4")
	)
	(via
		(at 29.566108 -197.968108)
		(size 0.7112)
		(drill 0.3556)
		(layers "F.Cu" "B.Cu")
		(net "PWM_BUFFER_IN_FAN3_FAN4")
	)
	(via
		(at 11.0236 -69.1642)
		(size 0.5588)
		(drill 0.3048)
		(layers "F.Cu" "B.Cu")
		(net "PWM_BUFFER_IN_FAN3_FAN4")
	)
	(via
		(at 28.321 -216.3064)
		(size 0.5588)
		(drill 0.3048)
		(layers "F.Cu" "B.Cu")
		(net "PWM_BUFFER_IN_FAN3_FAN4")
	)
	(via
		(at 28.956 -168.4909)
		(size 0.5588)
		(drill 0.3048)
		(layers "F.Cu" "B.Cu")
		(net "PWM_BUFFER_IN_FAN3_FAN4")
	)
	(via
		(at 28.8036 -218.9988)
		(size 0.5588)
		(drill 0.3048)
		(layers "F.Cu" "B.Cu")
		(net "PWM_BUFFER_IN_FAN3_FAN4")
	)
	(segment
		(start 10.134346 -110.369096)
		(end 10.134346 -109.092238)
		(width 0.1397)
		(layer "B.Cu")
		(net "PWM_BUFFER_IN_FAN3_FAN4")
	)
	(segment
		(start 10.5918 -92.061792)
		(end 10.5918 -69.596)
		(width 0.1397)
		(layer "B.Cu")
		(net "PWM_BUFFER_IN_FAN3_FAN4")
	)
	(segment
		(start 28.321 -218.5162)
		(end 28.8036 -218.9988)
		(width 0.1397)
		(layer "B.Cu")
		(net "PWM_BUFFER_IN_FAN3_FAN4")
	)
	(segment
		(start 10.16 -132.887974)
		(end 10.16 -123.8758)
		(width 0.1397)
		(layer "B.Cu")
		(net "PWM_BUFFER_IN_FAN3_FAN4")
	)
	(segment
		(start 19.9644 -150.8506)
		(end 15.9512 -146.8374)
		(width 0.1397)
		(layer "B.Cu")
		(net "PWM_BUFFER_IN_FAN3_FAN4")
	)
	(segment
		(start 28.321 -216.3064)
		(end 28.321 -214.1728)
		(width 0.1397)
		(layer "B.Cu")
		(net "PWM_BUFFER_IN_FAN3_FAN4")
	)
	(segment
		(start 11.4173 -112.757458)
		(end 10.134092 -111.47425)
		(width 0.1397)
		(layer "B.Cu")
		(net "PWM_BUFFER_IN_FAN3_FAN4")
	)
	(segment
		(start 28.956 -168.4909)
		(end 29.616146 -167.830754)
		(width 0.1397)
		(layer "B.Cu")
		(net "PWM_BUFFER_IN_FAN3_FAN4")
	)
	(segment
		(start 19.9644 -154.202892)
		(end 19.9644 -150.8506)
		(width 0.1397)
		(layer "B.Cu")
		(net "PWM_BUFFER_IN_FAN3_FAN4")
	)
	(segment
		(start 10.1346 -109.091984)
		(end 10.1346 -92.518738)
		(width 0.1397)
		(layer "B.Cu")
		(net "PWM_BUFFER_IN_FAN3_FAN4")
	)
	(segment
		(start 28.321 -214.1728)
		(end 30.13075 -212.36305)
		(width 0.1397)
		(layer "B.Cu")
		(net "PWM_BUFFER_IN_FAN3_FAN4")
	)
	(segment
		(start 10.1346 -92.518738)
		(end 10.394696 -92.258642)
		(width 0.1397)
		(layer "B.Cu")
		(net "PWM_BUFFER_IN_FAN3_FAN4")
	)
	(segment
		(start 31.59125 -165.829742)
		(end 19.9644 -154.202892)
		(width 0.1397)
		(layer "B.Cu")
		(net "PWM_BUFFER_IN_FAN3_FAN4")
	)
	(segment
		(start 27.90825 -177.78095)
		(end 28.2956 -177.3936)
		(width 0.1397)
		(layer "B.Cu")
		(net "PWM_BUFFER_IN_FAN3_FAN4")
	)
	(segment
		(start 10.134346 -109.092238)
		(end 10.1346 -109.091984)
		(width 0.1397)
		(layer "B.Cu")
		(net "PWM_BUFFER_IN_FAN3_FAN4")
	)
	(segment
		(start 29.984954 -167.830754)
		(end 31.59125 -166.224458)
		(width 0.1397)
		(layer "B.Cu")
		(net "PWM_BUFFER_IN_FAN3_FAN4")
	)
	(segment
		(start 29.616146 -167.830754)
		(end 29.984954 -167.830754)
		(width 0.1397)
		(layer "B.Cu")
		(net "PWM_BUFFER_IN_FAN3_FAN4")
	)
	(segment
		(start 11.4173 -122.6185)
		(end 11.4173 -112.757458)
		(width 0.1397)
		(layer "B.Cu")
		(net "PWM_BUFFER_IN_FAN3_FAN4")
	)
	(segment
		(start 13.462 -142.748)
		(end 13.462 -136.189974)
		(width 0.1397)
		(layer "B.Cu")
		(net "PWM_BUFFER_IN_FAN3_FAN4")
	)
	(segment
		(start 28.2956 -177.3936)
		(end 28.2956 -169.1513)
		(width 0.1397)
		(layer "B.Cu")
		(net "PWM_BUFFER_IN_FAN3_FAN4")
	)
	(segment
		(start 10.5918 -69.596)
		(end 11.0236 -69.1642)
		(width 0.1397)
		(layer "B.Cu")
		(net "PWM_BUFFER_IN_FAN3_FAN4")
	)
	(segment
		(start 31.59125 -166.224458)
		(end 31.59125 -165.829742)
		(width 0.1397)
		(layer "B.Cu")
		(net "PWM_BUFFER_IN_FAN3_FAN4")
	)
	(segment
		(start 15.9512 -146.8374)
		(end 15.9512 -145.2372)
		(width 0.1397)
		(layer "B.Cu")
		(net "PWM_BUFFER_IN_FAN3_FAN4")
	)
	(segment
		(start 10.394696 -92.258642)
		(end 10.39495 -92.258642)
		(width 0.1397)
		(layer "B.Cu")
		(net "PWM_BUFFER_IN_FAN3_FAN4")
	)
	(segment
		(start 13.462 -136.189974)
		(end 10.16 -132.887974)
		(width 0.1397)
		(layer "B.Cu")
		(net "PWM_BUFFER_IN_FAN3_FAN4")
	)
	(segment
		(start 10.134092 -111.47425)
		(end 10.134092 -110.36935)
		(width 0.1397)
		(layer "B.Cu")
		(net "PWM_BUFFER_IN_FAN3_FAN4")
	)
	(segment
		(start 30.13075 -198.53275)
		(end 29.566108 -197.968108)
		(width 0.1397)
		(layer "B.Cu")
		(net "PWM_BUFFER_IN_FAN3_FAN4")
	)
	(segment
		(start 10.16 -123.8758)
		(end 11.4173 -122.6185)
		(width 0.1397)
		(layer "B.Cu")
		(net "PWM_BUFFER_IN_FAN3_FAN4")
	)
	(segment
		(start 28.2956 -169.1513)
		(end 28.956 -168.4909)
		(width 0.1397)
		(layer "B.Cu")
		(net "PWM_BUFFER_IN_FAN3_FAN4")
	)
	(segment
		(start 28.321 -216.3064)
		(end 28.321 -218.5162)
		(width 0.1397)
		(layer "B.Cu")
		(net "PWM_BUFFER_IN_FAN3_FAN4")
	)
	(segment
		(start 29.566108 -197.968108)
		(end 27.90825 -196.31025)
		(width 0.1397)
		(layer "B.Cu")
		(net "PWM_BUFFER_IN_FAN3_FAN4")
	)
	(segment
		(start 27.90825 -196.31025)
		(end 27.90825 -177.78095)
		(width 0.1397)
		(layer "B.Cu")
		(net "PWM_BUFFER_IN_FAN3_FAN4")
	)
	(segment
		(start 10.134092 -110.36935)
		(end 10.134346 -110.369096)
		(width 0.1397)
		(layer "B.Cu")
		(net "PWM_BUFFER_IN_FAN3_FAN4")
	)
	(segment
		(start 15.9512 -145.2372)
		(end 13.462 -142.748)
		(width 0.1397)
		(layer "B.Cu")
		(net "PWM_BUFFER_IN_FAN3_FAN4")
	)
	(segment
		(start 10.39495 -92.258642)
		(end 10.5918 -92.061792)
		(width 0.1397)
		(layer "B.Cu")
		(net "PWM_BUFFER_IN_FAN3_FAN4")
	)
	(segment
		(start 30.13075 -212.36305)
		(end 30.13075 -198.53275)
		(width 0.1397)
		(layer "B.Cu")
		(net "PWM_BUFFER_IN_FAN3_FAN4")
	)
	(segment
		(start 27.68727 -169.13606)
		(end 27.56916 -169.13606)
		(width 0.1397)
		(layer "F.Cu")
		(net "PWM_BUFFER_IN_FAN5_FAN6")
	)
	(segment
		(start 27.56916 -169.13606)
		(end 26.6446 -168.2115)
		(width 0.1397)
		(layer "F.Cu")
		(net "PWM_BUFFER_IN_FAN5_FAN6")
	)
	(segment
		(start 24.1808 -168.2115)
		(end 24.3713 -168.021)
		(width 0.1397)
		(layer "F.Cu")
		(net "PWM_BUFFER_IN_FAN5_FAN6")
	)
	(segment
		(start 26.90876 -214.961216)
		(end 26.90876 -213.675214)
		(width 0.1397)
		(layer "F.Cu")
		(net "PWM_BUFFER_IN_FAN5_FAN6")
	)
	(segment
		(start 26.6446 -168.2115)
		(end 26.6319 -168.1988)
		(width 0.1397)
		(layer "F.Cu")
		(net "PWM_BUFFER_IN_FAN5_FAN6")
	)
	(segment
		(start 26.90876 -213.675214)
		(end 27.026616 -213.557358)
		(width 0.1397)
		(layer "F.Cu")
		(net "PWM_BUFFER_IN_FAN5_FAN6")
	)
	(segment
		(start 27.026616 -213.557358)
		(end 27.026616 -213.5378)
		(width 0.1397)
		(layer "F.Cu")
		(net "PWM_BUFFER_IN_FAN5_FAN6")
	)
	(segment
		(start 25.60955 -214.961216)
		(end 25.60955 -213.74735)
		(width 0.1397)
		(layer "F.Cu")
		(net "PWM_BUFFER_IN_FAN5_FAN6")
	)
	(segment
		(start 25.60955 -213.74735)
		(end 25.4762 -213.614)
		(width 0.1397)
		(layer "F.Cu")
		(net "PWM_BUFFER_IN_FAN5_FAN6")
	)
	(segment
		(start 24.3713 -168.021)
		(end 26.4541 -168.021)
		(width 0.1397)
		(layer "F.Cu")
		(net "PWM_BUFFER_IN_FAN5_FAN6")
	)
	(segment
		(start 26.4541 -168.021)
		(end 26.6319 -168.1988)
		(width 0.1397)
		(layer "F.Cu")
		(net "PWM_BUFFER_IN_FAN5_FAN6")
	)
	(via
		(at 27.68727 -169.13606)
		(size 0.5588)
		(drill 0.3048)
		(layers "F.Cu" "B.Cu")
		(net "PWM_BUFFER_IN_FAN5_FAN6")
	)
	(via
		(at 28.2194 -200.2028)
		(size 0.7112)
		(drill 0.3556)
		(layers "F.Cu" "B.Cu")
		(net "PWM_BUFFER_IN_FAN5_FAN6")
	)
	(via
		(at 27.026616 -213.5378)
		(size 0.5588)
		(drill 0.3048)
		(layers "F.Cu" "B.Cu")
		(net "PWM_BUFFER_IN_FAN5_FAN6")
	)
	(via
		(at 25.4762 -213.614)
		(size 0.5588)
		(drill 0.3048)
		(layers "F.Cu" "B.Cu")
		(net "PWM_BUFFER_IN_FAN5_FAN6")
	)
	(segment
		(start 27.40025 -198.11365)
		(end 27.40025 -187.2234)
		(width 0.1397)
		(layer "B.Cu")
		(net "PWM_BUFFER_IN_FAN5_FAN6")
	)
	(segment
		(start 28.2194 -200.2028)
		(end 28.2194 -198.9328)
		(width 0.1397)
		(layer "B.Cu")
		(net "PWM_BUFFER_IN_FAN5_FAN6")
	)
	(segment
		(start 27.758898 -169.207688)
		(end 27.68727 -169.13606)
		(width 0.1397)
		(layer "B.Cu")
		(net "PWM_BUFFER_IN_FAN5_FAN6")
	)
	(segment
		(start 27.399742 -187.222892)
		(end 27.399742 -180.283866)
		(width 0.1397)
		(layer "B.Cu")
		(net "PWM_BUFFER_IN_FAN5_FAN6")
	)
	(segment
		(start 27.399742 -177.285904)
		(end 27.006042 -176.892204)
		(width 0.1397)
		(layer "B.Cu")
		(net "PWM_BUFFER_IN_FAN5_FAN6")
	)
	(segment
		(start 27.399742 -180.283866)
		(end 27.40025 -180.283358)
		(width 0.1397)
		(layer "B.Cu")
		(net "PWM_BUFFER_IN_FAN5_FAN6")
	)
	(segment
		(start 28.2194 -207.4672)
		(end 28.2194 -200.2028)
		(width 0.1397)
		(layer "B.Cu")
		(net "PWM_BUFFER_IN_FAN5_FAN6")
	)
	(segment
		(start 27.471116 -213.5378)
		(end 29.68625 -211.322666)
		(width 0.1397)
		(layer "B.Cu")
		(net "PWM_BUFFER_IN_FAN5_FAN6")
	)
	(segment
		(start 27.759152 -171.757848)
		(end 27.759152 -170.967146)
		(width 0.1397)
		(layer "B.Cu")
		(net "PWM_BUFFER_IN_FAN5_FAN6")
	)
	(segment
		(start 29.68625 -208.93405)
		(end 28.2194 -207.4672)
		(width 0.1397)
		(layer "B.Cu")
		(net "PWM_BUFFER_IN_FAN5_FAN6")
	)
	(segment
		(start 27.006042 -172.510958)
		(end 27.759152 -171.757848)
		(width 0.1397)
		(layer "B.Cu")
		(net "PWM_BUFFER_IN_FAN5_FAN6")
	)
	(segment
		(start 28.2194 -198.9328)
		(end 27.40025 -198.11365)
		(width 0.1397)
		(layer "B.Cu")
		(net "PWM_BUFFER_IN_FAN5_FAN6")
	)
	(segment
		(start 27.40025 -179.888642)
		(end 27.399742 -179.888134)
		(width 0.1397)
		(layer "B.Cu")
		(net "PWM_BUFFER_IN_FAN5_FAN6")
	)
	(segment
		(start 27.759152 -170.967146)
		(end 27.758898 -170.966892)
		(width 0.1397)
		(layer "B.Cu")
		(net "PWM_BUFFER_IN_FAN5_FAN6")
	)
	(segment
		(start 27.40025 -180.283358)
		(end 27.40025 -179.888642)
		(width 0.1397)
		(layer "B.Cu")
		(net "PWM_BUFFER_IN_FAN5_FAN6")
	)
	(segment
		(start 25.4762 -213.614)
		(end 26.950416 -213.614)
		(width 0.1397)
		(layer "B.Cu")
		(net "PWM_BUFFER_IN_FAN5_FAN6")
	)
	(segment
		(start 29.68625 -211.322666)
		(end 29.68625 -208.93405)
		(width 0.1397)
		(layer "B.Cu")
		(net "PWM_BUFFER_IN_FAN5_FAN6")
	)
	(segment
		(start 27.399742 -179.888134)
		(end 27.399742 -177.285904)
		(width 0.1397)
		(layer "B.Cu")
		(net "PWM_BUFFER_IN_FAN5_FAN6")
	)
	(segment
		(start 27.006042 -176.892204)
		(end 27.006042 -172.510958)
		(width 0.1397)
		(layer "B.Cu")
		(net "PWM_BUFFER_IN_FAN5_FAN6")
	)
	(segment
		(start 26.950416 -213.614)
		(end 27.026616 -213.5378)
		(width 0.1397)
		(layer "B.Cu")
		(net "PWM_BUFFER_IN_FAN5_FAN6")
	)
	(segment
		(start 27.40025 -187.2234)
		(end 27.399742 -187.222892)
		(width 0.1397)
		(layer "B.Cu")
		(net "PWM_BUFFER_IN_FAN5_FAN6")
	)
	(segment
		(start 27.758898 -170.966892)
		(end 27.758898 -169.207688)
		(width 0.1397)
		(layer "B.Cu")
		(net "PWM_BUFFER_IN_FAN5_FAN6")
	)
	(segment
		(start 27.026616 -213.5378)
		(end 27.471116 -213.5378)
		(width 0.1397)
		(layer "B.Cu")
		(net "PWM_BUFFER_IN_FAN5_FAN6")
	)
	(segment
		(start 29.06395 -169.85615)
		(end 29.06395 -169.13225)
		(width 0.1397)
		(layer "F.Cu")
		(net "PWM_BUFFER_IN_FAN1_FAN2")
	)
	(segment
		(start 25.9842 -219.313252)
		(end 26.25852 -219.587572)
		(width 0.1397)
		(layer "F.Cu")
		(net "PWM_BUFFER_IN_FAN1_FAN2")
	)
	(segment
		(start 14.4399 -71.12)
		(end 12.192 -71.12)
		(width 0.1397)
		(layer "F.Cu")
		(net "PWM_BUFFER_IN_FAN1_FAN2")
	)
	(segment
		(start 29.06395 -169.13225)
		(end 29.6926 -168.5036)
		(width 0.1397)
		(layer "F.Cu")
		(net "PWM_BUFFER_IN_FAN1_FAN2")
	)
	(segment
		(start 29.5402 -170.3324)
		(end 29.06395 -169.85615)
		(width 0.1397)
		(layer "F.Cu")
		(net "PWM_BUFFER_IN_FAN1_FAN2")
	)
	(segment
		(start 12.192 -71.12)
		(end 11.6332 -70.5612)
		(width 0.1397)
		(layer "F.Cu")
		(net "PWM_BUFFER_IN_FAN1_FAN2")
	)
	(segment
		(start 26.25852 -219.587572)
		(end 26.25852 -220.600016)
		(width 0.1397)
		(layer "F.Cu")
		(net "PWM_BUFFER_IN_FAN1_FAN2")
	)
	(segment
		(start 30.004258 -168.5036)
		(end 30.2387 -168.269158)
		(width 0.1397)
		(layer "F.Cu")
		(net "PWM_BUFFER_IN_FAN1_FAN2")
	)
	(segment
		(start 27.559 -220.600016)
		(end 27.559 -219.359734)
		(width 0.1397)
		(layer "F.Cu")
		(net "PWM_BUFFER_IN_FAN1_FAN2")
	)
	(segment
		(start 29.6926 -168.5036)
		(end 30.004258 -168.5036)
		(width 0.1397)
		(layer "F.Cu")
		(net "PWM_BUFFER_IN_FAN1_FAN2")
	)
	(segment
		(start 29.5529 -170.3324)
		(end 29.5402 -170.3324)
		(width 0.1397)
		(layer "F.Cu")
		(net "PWM_BUFFER_IN_FAN1_FAN2")
	)
	(segment
		(start 27.559 -219.359734)
		(end 27.219656 -219.02039)
		(width 0.1397)
		(layer "F.Cu")
		(net "PWM_BUFFER_IN_FAN1_FAN2")
	)
	(segment
		(start 30.2387 -168.269158)
		(end 30.2387 -167.6908)
		(width 0.1397)
		(layer "F.Cu")
		(net "PWM_BUFFER_IN_FAN1_FAN2")
	)
	(via
		(at 27.219656 -219.02039)
		(size 0.5588)
		(drill 0.3048)
		(layers "F.Cu" "B.Cu")
		(net "PWM_BUFFER_IN_FAN1_FAN2")
	)
	(via
		(at 11.6332 -70.5612)
		(size 0.5588)
		(drill 0.3048)
		(layers "F.Cu" "B.Cu")
		(net "PWM_BUFFER_IN_FAN1_FAN2")
	)
	(via
		(at 25.9842 -219.313252)
		(size 0.5588)
		(drill 0.3048)
		(layers "F.Cu" "B.Cu")
		(net "PWM_BUFFER_IN_FAN1_FAN2")
	)
	(via
		(at 30.004258 -168.5036)
		(size 0.5588)
		(drill 0.3048)
		(layers "F.Cu" "B.Cu")
		(net "PWM_BUFFER_IN_FAN1_FAN2")
	)
	(via
		(at 29.265118 -194.441318)
		(size 0.7112)
		(drill 0.3556)
		(layers "F.Cu" "B.Cu")
		(net "PWM_BUFFER_IN_FAN1_FAN2")
	)
	(segment
		(start 32.03575 -166.46525)
		(end 30.004258 -168.496742)
		(width 0.1397)
		(layer "B.Cu")
		(net "PWM_BUFFER_IN_FAN1_FAN2")
	)
	(segment
		(start 10.578846 -110.553246)
		(end 10.578592 -110.5535)
		(width 0.1397)
		(layer "B.Cu")
		(net "PWM_BUFFER_IN_FAN1_FAN2")
	)
	(segment
		(start 10.5791 -92.703142)
		(end 10.5791 -109.276134)
		(width 0.1397)
		(layer "B.Cu")
		(net "PWM_BUFFER_IN_FAN1_FAN2")
	)
	(segment
		(start 20.4216 -150.6728)
		(end 20.4216 -154.031442)
		(width 0.1397)
		(layer "B.Cu")
		(net "PWM_BUFFER_IN_FAN1_FAN2")
	)
	(segment
		(start 11.0363 -71.1581)
		(end 11.0363 -92.245942)
		(width 0.1397)
		(layer "B.Cu")
		(net "PWM_BUFFER_IN_FAN1_FAN2")
	)
	(segment
		(start 32.17545 -216.300558)
		(end 32.17545 -197.35165)
		(width 0.1397)
		(layer "B.Cu")
		(net "PWM_BUFFER_IN_FAN1_FAN2")
	)
	(segment
		(start 14.1224 -125.0696)
		(end 14.1224 -142.7734)
		(width 0.1397)
		(layer "B.Cu")
		(net "PWM_BUFFER_IN_FAN1_FAN2")
	)
	(segment
		(start 11.6332 -70.5612)
		(end 11.0363 -71.1581)
		(width 0.1397)
		(layer "B.Cu")
		(net "PWM_BUFFER_IN_FAN1_FAN2")
	)
	(segment
		(start 28.7528 -169.755058)
		(end 30.004258 -168.5036)
		(width 0.1397)
		(layer "B.Cu")
		(net "PWM_BUFFER_IN_FAN1_FAN2")
	)
	(segment
		(start 27.219656 -219.02039)
		(end 26.277062 -219.02039)
		(width 0.1397)
		(layer "B.Cu")
		(net "PWM_BUFFER_IN_FAN1_FAN2")
	)
	(segment
		(start 10.5791 -109.276134)
		(end 10.578846 -109.276388)
		(width 0.1397)
		(layer "B.Cu")
		(net "PWM_BUFFER_IN_FAN1_FAN2")
	)
	(segment
		(start 11.8618 -122.809)
		(end 14.1224 -125.0696)
		(width 0.1397)
		(layer "B.Cu")
		(net "PWM_BUFFER_IN_FAN1_FAN2")
	)
	(segment
		(start 29.000958 -219.47505)
		(end 32.17545 -216.300558)
		(width 0.1397)
		(layer "B.Cu")
		(net "PWM_BUFFER_IN_FAN1_FAN2")
	)
	(segment
		(start 11.0363 -92.245942)
		(end 10.5791 -92.703142)
		(width 0.1397)
		(layer "B.Cu")
		(net "PWM_BUFFER_IN_FAN1_FAN2")
	)
	(segment
		(start 29.265118 -194.441318)
		(end 28.35275 -193.52895)
		(width 0.1397)
		(layer "B.Cu")
		(net "PWM_BUFFER_IN_FAN1_FAN2")
	)
	(segment
		(start 28.35275 -193.52895)
		(end 28.35275 -177.97145)
		(width 0.1397)
		(layer "B.Cu")
		(net "PWM_BUFFER_IN_FAN1_FAN2")
	)
	(segment
		(start 10.578592 -111.2901)
		(end 11.8618 -112.573308)
		(width 0.1397)
		(layer "B.Cu")
		(net "PWM_BUFFER_IN_FAN1_FAN2")
	)
	(segment
		(start 32.17545 -197.35165)
		(end 29.265118 -194.441318)
		(width 0.1397)
		(layer "B.Cu")
		(net "PWM_BUFFER_IN_FAN1_FAN2")
	)
	(segment
		(start 20.4216 -154.031442)
		(end 32.03575 -165.645592)
		(width 0.1397)
		(layer "B.Cu")
		(net "PWM_BUFFER_IN_FAN1_FAN2")
	)
	(segment
		(start 28.7528 -177.5714)
		(end 28.7528 -169.755058)
		(width 0.1397)
		(layer "B.Cu")
		(net "PWM_BUFFER_IN_FAN1_FAN2")
	)
	(segment
		(start 10.578592 -110.5535)
		(end 10.578592 -111.2901)
		(width 0.1397)
		(layer "B.Cu")
		(net "PWM_BUFFER_IN_FAN1_FAN2")
	)
	(segment
		(start 27.219656 -219.02039)
		(end 27.674316 -219.47505)
		(width 0.1397)
		(layer "B.Cu")
		(net "PWM_BUFFER_IN_FAN1_FAN2")
	)
	(segment
		(start 26.277062 -219.02039)
		(end 25.9842 -219.313252)
		(width 0.1397)
		(layer "B.Cu")
		(net "PWM_BUFFER_IN_FAN1_FAN2")
	)
	(segment
		(start 14.1224 -142.7734)
		(end 16.4084 -145.0594)
		(width 0.1397)
		(layer "B.Cu")
		(net "PWM_BUFFER_IN_FAN1_FAN2")
	)
	(segment
		(start 28.35275 -177.97145)
		(end 28.7528 -177.5714)
		(width 0.1397)
		(layer "B.Cu")
		(net "PWM_BUFFER_IN_FAN1_FAN2")
	)
	(segment
		(start 10.578846 -109.276388)
		(end 10.578846 -110.553246)
		(width 0.1397)
		(layer "B.Cu")
		(net "PWM_BUFFER_IN_FAN1_FAN2")
	)
	(segment
		(start 30.004258 -168.496742)
		(end 30.004258 -168.5036)
		(width 0.1397)
		(layer "B.Cu")
		(net "PWM_BUFFER_IN_FAN1_FAN2")
	)
	(segment
		(start 11.8618 -112.573308)
		(end 11.8618 -122.809)
		(width 0.1397)
		(layer "B.Cu")
		(net "PWM_BUFFER_IN_FAN1_FAN2")
	)
	(segment
		(start 16.4084 -145.0594)
		(end 16.4084 -146.6596)
		(width 0.1397)
		(layer "B.Cu")
		(net "PWM_BUFFER_IN_FAN1_FAN2")
	)
	(segment
		(start 16.4084 -146.6596)
		(end 20.4216 -150.6728)
		(width 0.1397)
		(layer "B.Cu")
		(net "PWM_BUFFER_IN_FAN1_FAN2")
	)
	(segment
		(start 27.674316 -219.47505)
		(end 29.000958 -219.47505)
		(width 0.1397)
		(layer "B.Cu")
		(net "PWM_BUFFER_IN_FAN1_FAN2")
	)
	(segment
		(start 32.03575 -165.645592)
		(end 32.03575 -166.46525)
		(width 0.1397)
		(layer "B.Cu")
		(net "PWM_BUFFER_IN_FAN1_FAN2")
	)
	(segment
		(start 26.6954 -142.4432)
		(end 27.3304 -141.8082)
		(width 0.1397)
		(layer "F.Cu")
		(net "P12VU_2490_EN_2")
	)
	(segment
		(start 25.781 -142.4432)
		(end 26.6954 -142.4432)
		(width 0.1397)
		(layer "F.Cu")
		(net "P12VU_2490_EN_2")
	)
	(segment
		(start 23.9649 -144.7165)
		(end 24.511 -144.1704)
		(width 0.1397)
		(layer "F.Cu")
		(net "P12VU_2490_EN_2")
	)
	(segment
		(start 24.511 -144.1704)
		(end 24.511 -143.1798)
		(width 0.1397)
		(layer "F.Cu")
		(net "P12VU_2490_EN_2")
	)
	(segment
		(start 22.69109 -142.5067)
		(end 22.69109 -144.21739)
		(width 0.1397)
		(layer "F.Cu")
		(net "P12VU_2490_EN_2")
	)
	(segment
		(start 22.69109 -144.21739)
		(end 23.1902 -144.7165)
		(width 0.1397)
		(layer "F.Cu")
		(net "P12VU_2490_EN_2")
	)
	(segment
		(start 25.0952 -143.129)
		(end 25.781 -142.4432)
		(width 0.1397)
		(layer "F.Cu")
		(net "P12VU_2490_EN_2")
	)
	(segment
		(start 27.199336 -61.159136)
		(end 25.580086 -59.539886)
		(width 0.1397)
		(layer "F.Cu")
		(net "P12VU_2490_EN_2")
	)
	(segment
		(start 27.3304 -141.8082)
		(end 27.3304 -141.4272)
		(width 0.1397)
		(layer "F.Cu")
		(net "P12VU_2490_EN_2")
	)
	(segment
		(start 30.983936 -61.159136)
		(end 27.199336 -61.159136)
		(width 0.1397)
		(layer "F.Cu")
		(net "P12VU_2490_EN_2")
	)
	(segment
		(start 32.3088 -62.484)
		(end 30.983936 -61.159136)
		(width 0.1397)
		(layer "F.Cu")
		(net "P12VU_2490_EN_2")
	)
	(segment
		(start 28.6004 -140.1572)
		(end 29.2862 -140.1572)
		(width 0.1397)
		(layer "F.Cu")
		(net "P12VU_2490_EN_2")
	)
	(segment
		(start 23.1902 -144.7165)
		(end 23.9649 -144.7165)
		(width 0.1397)
		(layer "F.Cu")
		(net "P12VU_2490_EN_2")
	)
	(segment
		(start 24.511 -143.1798)
		(end 24.4602 -143.129)
		(width 0.1397)
		(layer "F.Cu")
		(net "P12VU_2490_EN_2")
	)
	(segment
		(start 27.3304 -141.4272)
		(end 28.6004 -140.1572)
		(width 0.1397)
		(layer "F.Cu")
		(net "P12VU_2490_EN_2")
	)
	(segment
		(start 24.4602 -143.129)
		(end 25.0952 -143.129)
		(width 0.1397)
		(layer "F.Cu")
		(net "P12VU_2490_EN_2")
	)
	(via
		(at 29.2862 -140.1572)
		(size 0.5588)
		(drill 0.3048)
		(layers "F.Cu" "B.Cu")
		(net "P12VU_2490_EN_2")
	)
	(via
		(at 24.511 -144.1704)
		(size 0.7112)
		(drill 0.3556)
		(layers "F.Cu" "B.Cu")
		(net "P12VU_2490_EN_2")
	)
	(via
		(at 32.3088 -62.484)
		(size 0.5588)
		(drill 0.3048)
		(layers "F.Cu" "B.Cu")
		(net "P12VU_2490_EN_2")
	)
	(segment
		(start 32.3088 -110.795054)
		(end 32.3088 -62.484)
		(width 0.1397)
		(layer "B.Cu")
		(net "P12VU_2490_EN_2")
	)
	(segment
		(start 37.12845 -115.341146)
		(end 34.772854 -112.98555)
		(width 0.1397)
		(layer "B.Cu")
		(net "P12VU_2490_EN_2")
	)
	(segment
		(start 29.2862 -140.1572)
		(end 29.622496 -140.1572)
		(width 0.1397)
		(layer "B.Cu")
		(net "P12VU_2490_EN_2")
	)
	(segment
		(start 37.12845 -132.651246)
		(end 37.12845 -115.341146)
		(width 0.1397)
		(layer "B.Cu")
		(net "P12VU_2490_EN_2")
	)
	(segment
		(start 34.499296 -112.98555)
		(end 32.3088 -110.795054)
		(width 0.1397)
		(layer "B.Cu")
		(net "P12VU_2490_EN_2")
	)
	(segment
		(start 34.772854 -112.98555)
		(end 34.499296 -112.98555)
		(width 0.1397)
		(layer "B.Cu")
		(net "P12VU_2490_EN_2")
	)
	(segment
		(start 29.622496 -140.1572)
		(end 37.12845 -132.651246)
		(width 0.1397)
		(layer "B.Cu")
		(net "P12VU_2490_EN_2")
	)
	(segment
		(start 38.5191 -149.3774)
		(end 38.7985 -149.098)
		(width 0.1397)
		(layer "F.Cu")
		(net "P12VU_2490_EN_1")
	)
	(segment
		(start 37.5666 -149.3774)
		(end 38.5191 -149.3774)
		(width 0.1397)
		(layer "F.Cu")
		(net "P12VU_2490_EN_1")
	)
	(via
		(at 37.5666 -149.3774)
		(size 0.5588)
		(drill 0.3048)
		(layers "F.Cu" "B.Cu")
		(net "P12VU_2490_EN_1")
	)
	(segment
		(start 26.0858 -62.5856)
		(end 26.0858 -62.5602)
		(width 0.1397)
		(layer "B.Cu")
		(net "P12VU_2490_EN_1")
	)
	(segment
		(start 38.4048 -114.808)
		(end 34.798 -111.2012)
		(width 0.1397)
		(layer "B.Cu")
		(net "P12VU_2490_EN_1")
	)
	(segment
		(start 28.6258 -63.2714)
		(end 26.7716 -63.2714)
		(width 0.1397)
		(layer "B.Cu")
		(net "P12VU_2490_EN_1")
	)
	(segment
		(start 34.798 -111.2012)
		(end 34.798 -108.6104)
		(width 0.1397)
		(layer "B.Cu")
		(net "P12VU_2490_EN_1")
	)
	(segment
		(start 35.9156 -107.4928)
		(end 35.9156 -97.4344)
		(width 0.1397)
		(layer "B.Cu")
		(net "P12VU_2490_EN_1")
	)
	(segment
		(start 30.48 -61.4172)
		(end 28.6258 -63.2714)
		(width 0.1397)
		(layer "B.Cu")
		(net "P12VU_2490_EN_1")
	)
	(segment
		(start 34.4932 -96.012)
		(end 34.4932 -62.5348)
		(width 0.1397)
		(layer "B.Cu")
		(net "P12VU_2490_EN_1")
	)
	(segment
		(start 33.3756 -61.4172)
		(end 30.48 -61.4172)
		(width 0.1397)
		(layer "B.Cu")
		(net "P12VU_2490_EN_1")
	)
	(segment
		(start 37.4904 -149.3012)
		(end 37.4904 -141.5034)
		(width 0.1397)
		(layer "B.Cu")
		(net "P12VU_2490_EN_1")
	)
	(segment
		(start 26.0604 -62.5602)
		(end 25.580086 -62.079886)
		(width 0.1397)
		(layer "B.Cu")
		(net "P12VU_2490_EN_1")
	)
	(segment
		(start 34.4932 -62.5348)
		(end 33.3756 -61.4172)
		(width 0.1397)
		(layer "B.Cu")
		(net "P12VU_2490_EN_1")
	)
	(segment
		(start 37.4904 -141.5034)
		(end 38.4048 -140.589)
		(width 0.1397)
		(layer "B.Cu")
		(net "P12VU_2490_EN_1")
	)
	(segment
		(start 38.4048 -140.589)
		(end 38.4048 -114.808)
		(width 0.1397)
		(layer "B.Cu")
		(net "P12VU_2490_EN_1")
	)
	(segment
		(start 34.798 -108.6104)
		(end 35.9156 -107.4928)
		(width 0.1397)
		(layer "B.Cu")
		(net "P12VU_2490_EN_1")
	)
	(segment
		(start 26.7716 -63.2714)
		(end 26.0858 -62.5856)
		(width 0.1397)
		(layer "B.Cu")
		(net "P12VU_2490_EN_1")
	)
	(segment
		(start 37.5666 -149.3774)
		(end 37.4904 -149.3012)
		(width 0.1397)
		(layer "B.Cu")
		(net "P12VU_2490_EN_1")
	)
	(segment
		(start 26.0858 -62.5602)
		(end 26.0604 -62.5602)
		(width 0.1397)
		(layer "B.Cu")
		(net "P12VU_2490_EN_1")
	)
	(segment
		(start 35.9156 -97.4344)
		(end 34.4932 -96.012)
		(width 0.1397)
		(layer "B.Cu")
		(net "P12VU_2490_EN_1")
	)
	(segment
		(start 15.718536 -169.642536)
		(end 16.24965 -170.17365)
		(width 0.1397)
		(layer "F.Cu")
		(net "SEB_PEER_1A_1B_HB_OUT")
	)
	(segment
		(start 12.08786 -172.8724)
		(end 12.547854 -172.8724)
		(width 0.1397)
		(layer "F.Cu")
		(net "SEB_PEER_1A_1B_HB_OUT")
	)
	(segment
		(start 16.5989 -170.17365)
		(end 16.98625 -170.561)
		(width 0.1397)
		(layer "F.Cu")
		(net "SEB_PEER_1A_1B_HB_OUT")
	)
	(segment
		(start 14.5288 -169.642536)
		(end 15.718536 -169.642536)
		(width 0.1397)
		(layer "F.Cu")
		(net "SEB_PEER_1A_1B_HB_OUT")
	)
	(segment
		(start 12.547854 -172.8724)
		(end 13.95095 -171.469304)
		(width 0.1397)
		(layer "F.Cu")
		(net "SEB_PEER_1A_1B_HB_OUT")
	)
	(segment
		(start 14.5288 -170.9801)
		(end 14.5288 -169.642536)
		(width 0.1397)
		(layer "F.Cu")
		(net "SEB_PEER_1A_1B_HB_OUT")
	)
	(segment
		(start 14.5796 -171.0309)
		(end 14.5288 -170.9801)
		(width 0.1397)
		(layer "F.Cu")
		(net "SEB_PEER_1A_1B_HB_OUT")
	)
	(segment
		(start 16.24965 -170.17365)
		(end 16.5989 -170.17365)
		(width 0.1397)
		(layer "F.Cu")
		(net "SEB_PEER_1A_1B_HB_OUT")
	)
	(segment
		(start 13.95095 -171.469304)
		(end 13.95095 -171.46905)
		(width 0.1397)
		(layer "F.Cu")
		(net "SEB_PEER_1A_1B_HB_OUT")
	)
	(segment
		(start 16.98625 -170.561)
		(end 16.98625 -171.349924)
		(width 0.1397)
		(layer "F.Cu")
		(net "SEB_PEER_1A_1B_HB_OUT")
	)
	(segment
		(start 13.95095 -171.46905)
		(end 14.3891 -171.0309)
		(width 0.1397)
		(layer "F.Cu")
		(net "SEB_PEER_1A_1B_HB_OUT")
	)
	(segment
		(start 10.8585 -174.10176)
		(end 12.08786 -172.8724)
		(width 0.1397)
		(layer "F.Cu")
		(net "SEB_PEER_1A_1B_HB_OUT")
	)
	(segment
		(start 14.3891 -171.0309)
		(end 14.5796 -171.0309)
		(width 0.1397)
		(layer "F.Cu")
		(net "SEB_PEER_1A_1B_HB_OUT")
	)
	(via
		(at 14.5288 -169.642536)
		(size 0.7112)
		(drill 0.3556)
		(layers "F.Cu" "B.Cu")
		(net "SEB_PEER_1A_1B_HB_OUT")
	)
	(segment
		(start 12.2682 -50.7238)
		(end 12.1412 -50.5968)
		(width 0.1397)
		(layer "F.Cu")
		(net "SELF_1A_HB")
	)
	(segment
		(start 13.3604 -44.5262)
		(end 13.335 -44.5008)
		(width 0.1397)
		(layer "F.Cu")
		(net "SELF_1A_HB")
	)
	(segment
		(start 13.589 -50.7238)
		(end 12.2682 -50.7238)
		(width 0.1397)
		(layer "F.Cu")
		(net "SELF_1A_HB")
	)
	(segment
		(start 14.4399 -44.5262)
		(end 13.3604 -44.5262)
		(width 0.1397)
		(layer "F.Cu")
		(net "SELF_1A_HB")
	)
	(via
		(at 13.589 -50.7238)
		(size 0.5588)
		(drill 0.3048)
		(layers "F.Cu" "B.Cu")
		(net "SELF_1A_HB")
	)
	(via
		(at 12.1412 -50.5968)
		(size 0.5588)
		(drill 0.3048)
		(layers "F.Cu" "B.Cu")
		(net "SELF_1A_HB")
	)
	(via
		(at 13.335 -44.5008)
		(size 0.5588)
		(drill 0.3048)
		(layers "F.Cu" "B.Cu")
		(net "SELF_1A_HB")
	)
	(segment
		(start 13.589 -50.7238)
		(end 14.06525 -51.20005)
		(width 0.1397)
		(layer "B.Cu")
		(net "SELF_1A_HB")
	)
	(segment
		(start 21.5138 -50.3428)
		(end 25.305258 -50.3428)
		(width 0.1397)
		(layer "B.Cu")
		(net "SELF_1A_HB")
	)
	(segment
		(start 12.1412 -50.5968)
		(end 12.192 -50.546)
		(width 0.1397)
		(layer "B.Cu")
		(net "SELF_1A_HB")
	)
	(segment
		(start 12.192 -50.546)
		(end 12.192 -47.9044)
		(width 0.1397)
		(layer "B.Cu")
		(net "SELF_1A_HB")
	)
	(segment
		(start 26.500836 -56.079136)
		(end 25.580086 -56.999886)
		(width 0.1397)
		(layer "B.Cu")
		(net "SELF_1A_HB")
	)
	(segment
		(start 17.366234 -51.20005)
		(end 18.452084 -50.1142)
		(width 0.1397)
		(layer "B.Cu")
		(net "SELF_1A_HB")
	)
	(segment
		(start 13.335 -46.7614)
		(end 13.335 -44.5008)
		(width 0.1397)
		(layer "B.Cu")
		(net "SELF_1A_HB")
	)
	(segment
		(start 21.281136 -50.110136)
		(end 21.5138 -50.3428)
		(width 0.1397)
		(layer "B.Cu")
		(net "SELF_1A_HB")
	)
	(segment
		(start 19.714464 -50.110136)
		(end 21.281136 -50.110136)
		(width 0.1397)
		(layer "B.Cu")
		(net "SELF_1A_HB")
	)
	(segment
		(start 12.192 -47.9044)
		(end 13.335 -46.7614)
		(width 0.1397)
		(layer "B.Cu")
		(net "SELF_1A_HB")
	)
	(segment
		(start 14.06525 -51.20005)
		(end 17.366234 -51.20005)
		(width 0.1397)
		(layer "B.Cu")
		(net "SELF_1A_HB")
	)
	(segment
		(start 26.500836 -51.538378)
		(end 26.500836 -56.079136)
		(width 0.1397)
		(layer "B.Cu")
		(net "SELF_1A_HB")
	)
	(segment
		(start 18.452084 -50.1142)
		(end 19.7104 -50.1142)
		(width 0.1397)
		(layer "B.Cu")
		(net "SELF_1A_HB")
	)
	(segment
		(start 19.7104 -50.1142)
		(end 19.714464 -50.110136)
		(width 0.1397)
		(layer "B.Cu")
		(net "SELF_1A_HB")
	)
	(segment
		(start 25.305258 -50.3428)
		(end 26.500836 -51.538378)
		(width 0.1397)
		(layer "B.Cu")
		(net "SELF_1A_HB")
	)
	(segment
		(start 15.4686 -170.2308)
		(end 15.5956 -170.3578)
		(width 0.1397)
		(layer "F.Cu")
		(net "SEB_PEER_2A_2B_HB_OUT")
	)
	(segment
		(start 16.701262 -172.156374)
		(end 16.22425 -171.679362)
		(width 0.1397)
		(layer "F.Cu")
		(net "SEB_PEER_2A_2B_HB_OUT")
	)
	(segment
		(start 17.63649 -171.84751)
		(end 17.327626 -172.156374)
		(width 0.1397)
		(layer "F.Cu")
		(net "SEB_PEER_2A_2B_HB_OUT")
	)
	(segment
		(start 15.5956 -170.3578)
		(end 15.5956 -171.0309)
		(width 0.1397)
		(layer "F.Cu")
		(net "SEB_PEER_2A_2B_HB_OUT")
	)
	(segment
		(start 17.327626 -172.156374)
		(end 16.701262 -172.156374)
		(width 0.1397)
		(layer "F.Cu")
		(net "SEB_PEER_2A_2B_HB_OUT")
	)
	(segment
		(start 15.856204 -171.29125)
		(end 15.85595 -171.29125)
		(width 0.1397)
		(layer "F.Cu")
		(net "SEB_PEER_2A_2B_HB_OUT")
	)
	(segment
		(start 16.22425 -171.659296)
		(end 15.856204 -171.29125)
		(width 0.1397)
		(layer "F.Cu")
		(net "SEB_PEER_2A_2B_HB_OUT")
	)
	(segment
		(start 15.35684 -173.36516)
		(end 14.7955 -173.9265)
		(width 0.1397)
		(layer "F.Cu")
		(net "SEB_PEER_2A_2B_HB_OUT")
	)
	(segment
		(start 15.367 -173.36516)
		(end 15.35684 -173.36516)
		(width 0.1397)
		(layer "F.Cu")
		(net "SEB_PEER_2A_2B_HB_OUT")
	)
	(segment
		(start 17.63649 -171.349924)
		(end 17.63649 -171.84751)
		(width 0.1397)
		(layer "F.Cu")
		(net "SEB_PEER_2A_2B_HB_OUT")
	)
	(segment
		(start 16.22425 -171.679362)
		(end 16.22425 -171.659296)
		(width 0.1397)
		(layer "F.Cu")
		(net "SEB_PEER_2A_2B_HB_OUT")
	)
	(segment
		(start 15.85595 -171.29125)
		(end 15.5956 -171.0309)
		(width 0.1397)
		(layer "F.Cu")
		(net "SEB_PEER_2A_2B_HB_OUT")
	)
	(segment
		(start 14.7955 -173.9265)
		(end 14.7955 -174.10176)
		(width 0.1397)
		(layer "F.Cu")
		(net "SEB_PEER_2A_2B_HB_OUT")
	)
	(via
		(at 15.4686 -170.2308)
		(size 0.5588)
		(drill 0.3048)
		(layers "F.Cu" "B.Cu")
		(net "SEB_PEER_2A_2B_HB_OUT")
	)
	(via
		(at 15.367 -171.3738)
		(size 0.7112)
		(drill 0.3556)
		(layers "F.Cu" "B.Cu")
		(net "SEB_PEER_2A_2B_HB_OUT")
	)
	(via
		(at 15.367 -173.36516)
		(size 0.5588)
		(drill 0.3048)
		(layers "F.Cu" "B.Cu")
		(net "SEB_PEER_2A_2B_HB_OUT")
	)
	(segment
		(start 15.367 -171.3738)
		(end 15.367 -173.36516)
		(width 0.1397)
		(layer "B.Cu")
		(net "SEB_PEER_2A_2B_HB_OUT")
	)
	(segment
		(start 15.367 -170.3324)
		(end 15.367 -171.3738)
		(width 0.1397)
		(layer "B.Cu")
		(net "SEB_PEER_2A_2B_HB_OUT")
	)
	(segment
		(start 15.4686 -170.2308)
		(end 15.367 -170.3324)
		(width 0.1397)
		(layer "B.Cu")
		(net "SEB_PEER_2A_2B_HB_OUT")
	)
	(segment
		(start 16.3576 -46.5836)
		(end 15.3543 -46.5836)
		(width 0.1397)
		(layer "F.Cu")
		(net "SELF_2A_HB")
	)
	(segment
		(start 15.3543 -46.5836)
		(end 15.3289 -46.5582)
		(width 0.1397)
		(layer "F.Cu")
		(net "SELF_2A_HB")
	)
	(via
		(at 16.3576 -46.5836)
		(size 0.5588)
		(drill 0.3048)
		(layers "F.Cu" "B.Cu")
		(net "SELF_2A_HB")
	)
	(segment
		(start 18.185384 -46.5836)
		(end 16.3576 -46.5836)
		(width 0.1397)
		(layer "B.Cu")
		(net "SELF_2A_HB")
	)
	(segment
		(start 41.270936 -53.539136)
		(end 36.83 -53.539136)
		(width 0.1397)
		(layer "B.Cu")
		(net "SELF_2A_HB")
	)
	(segment
		(start 43.07967 -56.999886)
		(end 41.8084 -55.728616)
		(width 0.1397)
		(layer "B.Cu")
		(net "SELF_2A_HB")
	)
	(segment
		(start 43.079924 -56.999886)
		(end 43.07967 -56.999886)
		(width 0.1397)
		(layer "B.Cu")
		(net "SELF_2A_HB")
	)
	(segment
		(start 41.8084 -55.728616)
		(end 41.8084 -54.0766)
		(width 0.1397)
		(layer "B.Cu")
		(net "SELF_2A_HB")
	)
	(segment
		(start 21.463 -45.212)
		(end 21.085556 -44.834556)
		(width 0.1397)
		(layer "B.Cu")
		(net "SELF_2A_HB")
	)
	(segment
		(start 36.83 -53.539136)
		(end 28.502864 -45.212)
		(width 0.1397)
		(layer "B.Cu")
		(net "SELF_2A_HB")
	)
	(segment
		(start 21.085556 -44.834556)
		(end 19.934428 -44.834556)
		(width 0.1397)
		(layer "B.Cu")
		(net "SELF_2A_HB")
	)
	(segment
		(start 28.502864 -45.212)
		(end 21.463 -45.212)
		(width 0.1397)
		(layer "B.Cu")
		(net "SELF_2A_HB")
	)
	(segment
		(start 41.8084 -54.0766)
		(end 41.270936 -53.539136)
		(width 0.1397)
		(layer "B.Cu")
		(net "SELF_2A_HB")
	)
	(segment
		(start 19.934428 -44.834556)
		(end 18.185384 -46.5836)
		(width 0.1397)
		(layer "B.Cu")
		(net "SELF_2A_HB")
	)
	(segment
		(start 36.013136 -50.999136)
		(end 38.426136 -50.999136)
		(width 0.1397)
		(layer "F.Cu")
		(net "SELF_2B_HB")
	)
	(segment
		(start 15.3289 -42.4942)
		(end 17.5514 -44.7167)
		(width 0.1397)
		(layer "F.Cu")
		(net "SELF_2B_HB")
	)
	(segment
		(start 40.53967 -54.459886)
		(end 40.539924 -54.459886)
		(width 0.1397)
		(layer "F.Cu")
		(net "SELF_2B_HB")
	)
	(segment
		(start 29.203904 -44.716446)
		(end 29.571696 -44.716446)
		(width 0.1397)
		(layer "F.Cu")
		(net "SELF_2B_HB")
	)
	(segment
		(start 29.571696 -44.716446)
		(end 29.57195 -44.7167)
		(width 0.1397)
		(layer "F.Cu")
		(net "SELF_2B_HB")
	)
	(segment
		(start 38.9382 -51.5112)
		(end 38.9382 -52.858416)
		(width 0.1397)
		(layer "F.Cu")
		(net "SELF_2B_HB")
	)
	(segment
		(start 38.9382 -52.858416)
		(end 40.53967 -54.459886)
		(width 0.1397)
		(layer "F.Cu")
		(net "SELF_2B_HB")
	)
	(segment
		(start 29.7307 -44.7167)
		(end 36.013136 -50.999136)
		(width 0.1397)
		(layer "F.Cu")
		(net "SELF_2B_HB")
	)
	(segment
		(start 29.20365 -44.7167)
		(end 29.203904 -44.716446)
		(width 0.1397)
		(layer "F.Cu")
		(net "SELF_2B_HB")
	)
	(segment
		(start 29.57195 -44.7167)
		(end 29.7307 -44.7167)
		(width 0.1397)
		(layer "F.Cu")
		(net "SELF_2B_HB")
	)
	(segment
		(start 38.426136 -50.999136)
		(end 38.9382 -51.5112)
		(width 0.1397)
		(layer "F.Cu")
		(net "SELF_2B_HB")
	)
	(segment
		(start 17.5514 -44.7167)
		(end 29.20365 -44.7167)
		(width 0.1397)
		(layer "F.Cu")
		(net "SELF_2B_HB")
	)
	(segment
		(start 13.8176 -40.4622)
		(end 14.4399 -40.4622)
		(width 0.1397)
		(layer "F.Cu")
		(net "SELF_1B_HB")
	)
	(segment
		(start 21.7932 -53.213)
		(end 23.040086 -54.459886)
		(width 0.1397)
		(layer "F.Cu")
		(net "SELF_1B_HB")
	)
	(segment
		(start 12.6238 -53.047646)
		(end 13.506196 -52.16525)
		(width 0.1397)
		(layer "F.Cu")
		(net "SELF_1B_HB")
	)
	(segment
		(start 13.3858 -41.2242)
		(end 13.3858 -40.894)
		(width 0.1397)
		(layer "F.Cu")
		(net "SELF_1B_HB")
	)
	(segment
		(start 13.506196 -52.16525)
		(end 18.99285 -52.16525)
		(width 0.1397)
		(layer "F.Cu")
		(net "SELF_1B_HB")
	)
	(segment
		(start 12.6238 -53.2638)
		(end 12.6238 -53.047646)
		(width 0.1397)
		(layer "F.Cu")
		(net "SELF_1B_HB")
	)
	(segment
		(start 20.0406 -53.213)
		(end 21.7932 -53.213)
		(width 0.1397)
		(layer "F.Cu")
		(net "SELF_1B_HB")
	)
	(segment
		(start 13.3858 -40.894)
		(end 13.8176 -40.4622)
		(width 0.1397)
		(layer "F.Cu")
		(net "SELF_1B_HB")
	)
	(segment
		(start 18.99285 -52.16525)
		(end 20.0406 -53.213)
		(width 0.1397)
		(layer "F.Cu")
		(net "SELF_1B_HB")
	)
	(via
		(at 13.3858 -41.2242)
		(size 0.5588)
		(drill 0.3048)
		(layers "F.Cu" "B.Cu")
		(net "SELF_1B_HB")
	)
	(via
		(at 12.6238 -53.2638)
		(size 0.5588)
		(drill 0.3048)
		(layers "F.Cu" "B.Cu")
		(net "SELF_1B_HB")
	)
	(segment
		(start 13.3858 -41.2242)
		(end 13.3858 -42.2148)
		(width 0.1397)
		(layer "B.Cu")
		(net "SELF_1B_HB")
	)
	(segment
		(start 12.5984 -43.0022)
		(end 12.5984 -46.863)
		(width 0.1397)
		(layer "B.Cu")
		(net "SELF_1B_HB")
	)
	(segment
		(start 12.6238 -52.7558)
		(end 12.6238 -53.2638)
		(width 0.1397)
		(layer "B.Cu")
		(net "SELF_1B_HB")
	)
	(segment
		(start 12.5984 -46.863)
		(end 11.46175 -47.99965)
		(width 0.1397)
		(layer "B.Cu")
		(net "SELF_1B_HB")
	)
	(segment
		(start 13.3858 -42.2148)
		(end 12.5984 -43.0022)
		(width 0.1397)
		(layer "B.Cu")
		(net "SELF_1B_HB")
	)
	(segment
		(start 11.46175 -47.99965)
		(end 11.46175 -51.59375)
		(width 0.1397)
		(layer "B.Cu")
		(net "SELF_1B_HB")
	)
	(segment
		(start 11.46175 -51.59375)
		(end 12.6238 -52.7558)
		(width 0.1397)
		(layer "B.Cu")
		(net "SELF_1B_HB")
	)
	(segment
		(start 45.619924 -51.919886)
		(end 46.98492 -53.284882)
		(width 0.1397)
		(layer "F.Cu")
		(net "SELF_TRAY_PRESENT_LOWER")
	)
	(segment
		(start 46.295564 -63.000636)
		(end 44.941236 -63.000636)
		(width 0.1397)
		(layer "F.Cu")
		(net "SELF_TRAY_PRESENT_LOWER")
	)
	(segment
		(start 46.98492 -58.973974)
		(end 46.985174 -58.974228)
		(width 0.1397)
		(layer "F.Cu")
		(net "SELF_TRAY_PRESENT_LOWER")
	)
	(segment
		(start 44.941236 -63.000636)
		(end 44.2468 -62.3062)
		(width 0.1397)
		(layer "F.Cu")
		(net "SELF_TRAY_PRESENT_LOWER")
	)
	(segment
		(start 46.985174 -60.105544)
		(end 46.98492 -60.105798)
		(width 0.1397)
		(layer "F.Cu")
		(net "SELF_TRAY_PRESENT_LOWER")
	)
	(segment
		(start 13.582396 -56.76265)
		(end 12.6873 -55.867554)
		(width 0.1397)
		(layer "F.Cu")
		(net "SELF_TRAY_PRESENT_LOWER")
	)
	(segment
		(start 21.841968 -58.619136)
		(end 21.761704 -58.6994)
		(width 0.1397)
		(layer "F.Cu")
		(net "SELF_TRAY_PRESENT_LOWER")
	)
	(segment
		(start 17.86255 -56.76265)
		(end 13.582396 -56.76265)
		(width 0.1397)
		(layer "F.Cu")
		(net "SELF_TRAY_PRESENT_LOWER")
	)
	(segment
		(start 12.6873 -55.867554)
		(end 12.6873 -55.2196)
		(width 0.1397)
		(layer "F.Cu")
		(net "SELF_TRAY_PRESENT_LOWER")
	)
	(segment
		(start 31.1658 -60.706)
		(end 27.983942 -60.706)
		(width 0.1397)
		(layer "F.Cu")
		(net "SELF_TRAY_PRESENT_LOWER")
	)
	(segment
		(start 27.178 -59.835542)
		(end 25.961594 -58.619136)
		(width 0.1397)
		(layer "F.Cu")
		(net "SELF_TRAY_PRESENT_LOWER")
	)
	(segment
		(start 18.3134 -56.3118)
		(end 17.86255 -56.76265)
		(width 0.1397)
		(layer "F.Cu")
		(net "SELF_TRAY_PRESENT_LOWER")
	)
	(segment
		(start 46.98492 -53.284882)
		(end 46.98492 -58.973974)
		(width 0.1397)
		(layer "F.Cu")
		(net "SELF_TRAY_PRESENT_LOWER")
	)
	(segment
		(start 31.618936 -61.159136)
		(end 31.1658 -60.706)
		(width 0.1397)
		(layer "F.Cu")
		(net "SELF_TRAY_PRESENT_LOWER")
	)
	(segment
		(start 43.561 -61.159136)
		(end 31.618936 -61.159136)
		(width 0.1397)
		(layer "F.Cu")
		(net "SELF_TRAY_PRESENT_LOWER")
	)
	(segment
		(start 27.178 -59.900058)
		(end 27.178 -59.835542)
		(width 0.1397)
		(layer "F.Cu")
		(net "SELF_TRAY_PRESENT_LOWER")
	)
	(segment
		(start 46.985174 -58.974228)
		(end 46.985174 -60.105544)
		(width 0.1397)
		(layer "F.Cu")
		(net "SELF_TRAY_PRESENT_LOWER")
	)
	(segment
		(start 44.2468 -61.844936)
		(end 43.561 -61.159136)
		(width 0.1397)
		(layer "F.Cu")
		(net "SELF_TRAY_PRESENT_LOWER")
	)
	(segment
		(start 25.961594 -58.619136)
		(end 21.841968 -58.619136)
		(width 0.1397)
		(layer "F.Cu")
		(net "SELF_TRAY_PRESENT_LOWER")
	)
	(segment
		(start 44.2468 -62.3062)
		(end 44.2468 -61.844936)
		(width 0.1397)
		(layer "F.Cu")
		(net "SELF_TRAY_PRESENT_LOWER")
	)
	(segment
		(start 27.983942 -60.706)
		(end 27.178 -59.900058)
		(width 0.1397)
		(layer "F.Cu")
		(net "SELF_TRAY_PRESENT_LOWER")
	)
	(segment
		(start 46.98492 -60.105798)
		(end 46.98492 -62.31128)
		(width 0.1397)
		(layer "F.Cu")
		(net "SELF_TRAY_PRESENT_LOWER")
	)
	(segment
		(start 46.98492 -62.31128)
		(end 46.295564 -63.000636)
		(width 0.1397)
		(layer "F.Cu")
		(net "SELF_TRAY_PRESENT_LOWER")
	)
	(via
		(at 18.3134 -56.3118)
		(size 0.5588)
		(drill 0.3048)
		(layers "F.Cu" "B.Cu")
		(net "SELF_TRAY_PRESENT_LOWER")
	)
	(via
		(at 21.761704 -58.6994)
		(size 0.5588)
		(drill 0.3048)
		(layers "F.Cu" "B.Cu")
		(net "SELF_TRAY_PRESENT_LOWER")
	)
	(segment
		(start 18.546064 -56.079136)
		(end 18.3134 -56.3118)
		(width 0.1397)
		(layer "B.Cu")
		(net "SELF_TRAY_PRESENT_LOWER")
	)
	(segment
		(start 20.881594 -56.079136)
		(end 18.546064 -56.079136)
		(width 0.1397)
		(layer "B.Cu")
		(net "SELF_TRAY_PRESENT_LOWER")
	)
	(segment
		(start 21.4376 -56.635142)
		(end 20.881594 -56.079136)
		(width 0.1397)
		(layer "B.Cu")
		(net "SELF_TRAY_PRESENT_LOWER")
	)
	(segment
		(start 21.761704 -58.6994)
		(end 21.4376 -58.375296)
		(width 0.1397)
		(layer "B.Cu")
		(net "SELF_TRAY_PRESENT_LOWER")
	)
	(segment
		(start 21.4376 -58.375296)
		(end 21.4376 -56.635142)
		(width 0.1397)
		(layer "B.Cu")
		(net "SELF_TRAY_PRESENT_LOWER")
	)
	(segment
		(start 46.5328 -59.0042)
		(end 46.147736 -58.619136)
		(width 0.1397)
		(layer "F.Cu")
		(net "PEER_TRAY PRESENT_LOWER")
	)
	(segment
		(start 19.1262 -53.6702)
		(end 18.4658 -54.3306)
		(width 0.1397)
		(layer "F.Cu")
		(net "PEER_TRAY PRESENT_LOWER")
	)
	(segment
		(start 12.8143 -54.3306)
		(end 12.6873 -54.2036)
		(width 0.1397)
		(layer "F.Cu")
		(net "PEER_TRAY PRESENT_LOWER")
	)
	(segment
		(start 46.5328 -61.16701)
		(end 46.5328 -59.929268)
		(width 0.1397)
		(layer "F.Cu")
		(net "PEER_TRAY PRESENT_LOWER")
	)
	(segment
		(start 31.187136 -58.619136)
		(end 31.0134 -58.4454)
		(width 0.1397)
		(layer "F.Cu")
		(net "PEER_TRAY PRESENT_LOWER")
	)
	(segment
		(start 45.619924 -62.079886)
		(end 46.5328 -61.16701)
		(width 0.1397)
		(layer "F.Cu")
		(net "PEER_TRAY PRESENT_LOWER")
	)
	(segment
		(start 46.540674 -59.158378)
		(end 46.5328 -59.150504)
		(width 0.1397)
		(layer "F.Cu")
		(net "PEER_TRAY PRESENT_LOWER")
	)
	(segment
		(start 46.147736 -58.619136)
		(end 31.187136 -58.619136)
		(width 0.1397)
		(layer "F.Cu")
		(net "PEER_TRAY PRESENT_LOWER")
	)
	(segment
		(start 46.5328 -59.929268)
		(end 46.540674 -59.921394)
		(width 0.1397)
		(layer "F.Cu")
		(net "PEER_TRAY PRESENT_LOWER")
	)
	(segment
		(start 18.4658 -54.3306)
		(end 12.8143 -54.3306)
		(width 0.1397)
		(layer "F.Cu")
		(net "PEER_TRAY PRESENT_LOWER")
	)
	(segment
		(start 46.5328 -59.150504)
		(end 46.5328 -59.0042)
		(width 0.1397)
		(layer "F.Cu")
		(net "PEER_TRAY PRESENT_LOWER")
	)
	(segment
		(start 46.540674 -59.921394)
		(end 46.540674 -59.158378)
		(width 0.1397)
		(layer "F.Cu")
		(net "PEER_TRAY PRESENT_LOWER")
	)
	(via
		(at 19.1262 -53.6702)
		(size 0.5588)
		(drill 0.3048)
		(layers "F.Cu" "B.Cu")
		(net "PEER_TRAY PRESENT_LOWER")
	)
	(via
		(at 31.0134 -58.4454)
		(size 0.5588)
		(drill 0.3048)
		(layers "F.Cu" "B.Cu")
		(net "PEER_TRAY PRESENT_LOWER")
	)
	(segment
		(start 21.4376 -54.095142)
		(end 20.881594 -53.539136)
		(width 0.1397)
		(layer "B.Cu")
		(net "PEER_TRAY PRESENT_LOWER")
	)
	(segment
		(start 20.881594 -53.539136)
		(end 19.257264 -53.539136)
		(width 0.1397)
		(layer "B.Cu")
		(net "PEER_TRAY PRESENT_LOWER")
	)
	(segment
		(start 23.400258 -56.0578)
		(end 22.707092 -56.0578)
		(width 0.1397)
		(layer "B.Cu")
		(net "PEER_TRAY PRESENT_LOWER")
	)
	(segment
		(start 21.4376 -54.788308)
		(end 21.4376 -54.095142)
		(width 0.1397)
		(layer "B.Cu")
		(net "PEER_TRAY PRESENT_LOWER")
	)
	(segment
		(start 31.0134 -58.4454)
		(end 30.988 -58.42)
		(width 0.1397)
		(layer "B.Cu")
		(net "PEER_TRAY PRESENT_LOWER")
	)
	(segment
		(start 23.9776 -57.328308)
		(end 23.9776 -56.635142)
		(width 0.1397)
		(layer "B.Cu")
		(net "PEER_TRAY PRESENT_LOWER")
	)
	(segment
		(start 25.069292 -58.42)
		(end 23.9776 -57.328308)
		(width 0.1397)
		(layer "B.Cu")
		(net "PEER_TRAY PRESENT_LOWER")
	)
	(segment
		(start 30.988 -58.42)
		(end 25.069292 -58.42)
		(width 0.1397)
		(layer "B.Cu")
		(net "PEER_TRAY PRESENT_LOWER")
	)
	(segment
		(start 23.9776 -56.635142)
		(end 23.400258 -56.0578)
		(width 0.1397)
		(layer "B.Cu")
		(net "PEER_TRAY PRESENT_LOWER")
	)
	(segment
		(start 22.707092 -56.0578)
		(end 21.4376 -54.788308)
		(width 0.1397)
		(layer "B.Cu")
		(net "PEER_TRAY PRESENT_LOWER")
	)
	(segment
		(start 19.257264 -53.539136)
		(end 19.1262 -53.6702)
		(width 0.1397)
		(layer "B.Cu")
		(net "PEER_TRAY PRESENT_LOWER")
	)
	(segment
		(start 8.23595 -45.1866)
		(end 8.36295 -45.0596)
		(width 0.1397)
		(layer "F.Cu")
		(net "SEB_PEER_2A_HB")
	)
	(segment
		(start 40.115236 -55.380636)
		(end 42.159174 -55.380636)
		(width 0.1397)
		(layer "F.Cu")
		(net "SEB_PEER_2A_HB")
	)
	(segment
		(start 15.3289 -44.5262)
		(end 15.3289 -43.5102)
		(width 0.1397)
		(layer "F.Cu")
		(net "SEB_PEER_2A_HB")
	)
	(segment
		(start 12.93876 -175.40224)
		(end 13.1445 -175.40224)
		(width 0.1397)
		(layer "F.Cu")
		(net "SEB_PEER_2A_HB")
	)
	(segment
		(start 16.129 -44.5262)
		(end 16.764 -45.1612)
		(width 0.1397)
		(layer "F.Cu")
		(net "SEB_PEER_2A_HB")
	)
	(segment
		(start 15.3289 -44.5262)
		(end 16.129 -44.5262)
		(width 0.1397)
		(layer "F.Cu")
		(net "SEB_PEER_2A_HB")
	)
	(segment
		(start 14.7955 -45.0596)
		(end 15.3289 -44.5262)
		(width 0.1397)
		(layer "F.Cu")
		(net "SEB_PEER_2A_HB")
	)
	(segment
		(start 16.764 -45.1612)
		(end 28.9052 -45.1612)
		(width 0.1397)
		(layer "F.Cu")
		(net "SEB_PEER_2A_HB")
	)
	(segment
		(start 28.9052 -45.1612)
		(end 37.084 -53.34)
		(width 0.1397)
		(layer "F.Cu")
		(net "SEB_PEER_2A_HB")
	)
	(segment
		(start 11.303 -177.165)
		(end 11.303 -177.038)
		(width 0.1397)
		(layer "F.Cu")
		(net "SEB_PEER_2A_HB")
	)
	(segment
		(start 11.303 -177.038)
		(end 12.93876 -175.40224)
		(width 0.1397)
		(layer "F.Cu")
		(net "SEB_PEER_2A_HB")
	)
	(segment
		(start 42.159174 -55.380636)
		(end 43.079924 -54.459886)
		(width 0.1397)
		(layer "F.Cu")
		(net "SEB_PEER_2A_HB")
	)
	(segment
		(start 38.2016 -53.34)
		(end 39.2176 -54.356)
		(width 0.1397)
		(layer "F.Cu")
		(net "SEB_PEER_2A_HB")
	)
	(segment
		(start 37.084 -53.34)
		(end 38.2016 -53.34)
		(width 0.1397)
		(layer "F.Cu")
		(net "SEB_PEER_2A_HB")
	)
	(segment
		(start 39.2176 -54.356)
		(end 39.2176 -54.483)
		(width 0.1397)
		(layer "F.Cu")
		(net "SEB_PEER_2A_HB")
	)
	(segment
		(start 39.2176 -54.483)
		(end 40.115236 -55.380636)
		(width 0.1397)
		(layer "F.Cu")
		(net "SEB_PEER_2A_HB")
	)
	(segment
		(start 8.36295 -45.0596)
		(end 14.7955 -45.0596)
		(width 0.1397)
		(layer "F.Cu")
		(net "SEB_PEER_2A_HB")
	)
	(via
		(at 11.303 -177.165)
		(size 0.5588)
		(drill 0.3048)
		(layers "F.Cu" "B.Cu")
		(net "SEB_PEER_2A_HB")
	)
	(via
		(at 8.23595 -45.1866)
		(size 0.5588)
		(drill 0.3048)
		(layers "F.Cu" "B.Cu")
		(net "SEB_PEER_2A_HB")
	)
	(segment
		(start 3.9878 -60.796932)
		(end 3.9878 -78.931516)
		(width 0.1397)
		(layer "B.Cu")
		(net "SEB_PEER_2A_HB")
	)
	(segment
		(start 2.243074 -167.610282)
		(end 2.50317 -167.870378)
		(width 0.1397)
		(layer "B.Cu")
		(net "SEB_PEER_2A_HB")
	)
	(segment
		(start 10.470896 -175.83785)
		(end 10.470896 -176.472596)
		(width 0.1397)
		(layer "B.Cu")
		(net "SEB_PEER_2A_HB")
	)
	(segment
		(start 8.781796 -56.444642)
		(end 8.279638 -56.9468)
		(width 0.1397)
		(layer "B.Cu")
		(net "SEB_PEER_2A_HB")
	)
	(segment
		(start 3.9878 -78.931516)
		(end 2.243074 -80.676242)
		(width 0.1397)
		(layer "B.Cu")
		(net "SEB_PEER_2A_HB")
	)
	(segment
		(start 11.1633 -177.165)
		(end 11.303 -177.165)
		(width 0.1397)
		(layer "B.Cu")
		(net "SEB_PEER_2A_HB")
	)
	(segment
		(start 2.243074 -80.676242)
		(end 2.243074 -113.43767)
		(width 0.1397)
		(layer "B.Cu")
		(net "SEB_PEER_2A_HB")
	)
	(segment
		(start 8.321802 -52.416202)
		(end 8.781796 -52.876196)
		(width 0.1397)
		(layer "B.Cu")
		(net "SEB_PEER_2A_HB")
	)
	(segment
		(start 2.50317 -167.870378)
		(end 2.503424 -167.870378)
		(width 0.1397)
		(layer "B.Cu")
		(net "SEB_PEER_2A_HB")
	)
	(segment
		(start 8.321802 -52.415948)
		(end 8.321802 -52.416202)
		(width 0.1397)
		(layer "B.Cu")
		(net "SEB_PEER_2A_HB")
	)
	(segment
		(start 2.242566 -119.371872)
		(end 2.243074 -119.37238)
		(width 0.1397)
		(layer "B.Cu")
		(net "SEB_PEER_2A_HB")
	)
	(segment
		(start 8.23595 -52.330096)
		(end 8.321802 -52.415948)
		(width 0.1397)
		(layer "B.Cu")
		(net "SEB_PEER_2A_HB")
	)
	(segment
		(start 10.470896 -176.472596)
		(end 11.1633 -177.165)
		(width 0.1397)
		(layer "B.Cu")
		(net "SEB_PEER_2A_HB")
	)
	(segment
		(start 8.781796 -52.876196)
		(end 8.781796 -56.444642)
		(width 0.1397)
		(layer "B.Cu")
		(net "SEB_PEER_2A_HB")
	)
	(segment
		(start 2.243074 -119.37238)
		(end 2.243074 -167.610282)
		(width 0.1397)
		(layer "B.Cu")
		(net "SEB_PEER_2A_HB")
	)
	(segment
		(start 7.837932 -56.9468)
		(end 3.9878 -60.796932)
		(width 0.1397)
		(layer "B.Cu")
		(net "SEB_PEER_2A_HB")
	)
	(segment
		(start 8.279638 -56.9468)
		(end 7.837932 -56.9468)
		(width 0.1397)
		(layer "B.Cu")
		(net "SEB_PEER_2A_HB")
	)
	(segment
		(start 2.503424 -167.870378)
		(end 10.470896 -175.83785)
		(width 0.1397)
		(layer "B.Cu")
		(net "SEB_PEER_2A_HB")
	)
	(segment
		(start 8.23595 -45.1866)
		(end 8.23595 -52.330096)
		(width 0.1397)
		(layer "B.Cu")
		(net "SEB_PEER_2A_HB")
	)
	(segment
		(start 2.243074 -113.43767)
		(end 2.242566 -113.438178)
		(width 0.1397)
		(layer "B.Cu")
		(net "SEB_PEER_2A_HB")
	)
	(segment
		(start 2.242566 -113.438178)
		(end 2.242566 -119.371872)
		(width 0.1397)
		(layer "B.Cu")
		(net "SEB_PEER_2A_HB")
	)
	(segment
		(start 14.4399 -42.4942)
		(end 12.80795 -42.4942)
		(width 0.1397)
		(layer "F.Cu")
		(net "SEB_PEER_1B_HB")
	)
	(segment
		(start 14.9733 -57.6707)
		(end 10.0203 -57.6707)
		(width 0.1397)
		(layer "F.Cu")
		(net "SEB_PEER_1B_HB")
	)
	(segment
		(start 15.5702 -58.2676)
		(end 14.9733 -57.6707)
		(width 0.1397)
		(layer "F.Cu")
		(net "SEB_PEER_1B_HB")
	)
	(segment
		(start 11.811 -179.197)
		(end 10.80135 -179.197)
		(width 0.1397)
		(layer "F.Cu")
		(net "SEB_PEER_1B_HB")
	)
	(segment
		(start 10.80135 -179.197)
		(end 8.40105 -176.7967)
		(width 0.1397)
		(layer "F.Cu")
		(net "SEB_PEER_1B_HB")
	)
	(segment
		(start 8.40105 -176.7967)
		(end 8.40105 -174.98695)
		(width 0.1397)
		(layer "F.Cu")
		(net "SEB_PEER_1B_HB")
	)
	(segment
		(start 8.40105 -174.98695)
		(end 8.636 -174.752)
		(width 0.1397)
		(layer "F.Cu")
		(net "SEB_PEER_1B_HB")
	)
	(segment
		(start 10.0203 -57.6707)
		(end 9.652 -58.039)
		(width 0.1397)
		(layer "F.Cu")
		(net "SEB_PEER_1B_HB")
	)
	(segment
		(start 14.4399 -41.4782)
		(end 14.4399 -42.4942)
		(width 0.1397)
		(layer "F.Cu")
		(net "SEB_PEER_1B_HB")
	)
	(segment
		(start 12.80795 -42.4942)
		(end 11.0236 -44.27855)
		(width 0.1397)
		(layer "F.Cu")
		(net "SEB_PEER_1B_HB")
	)
	(segment
		(start 8.636 -174.752)
		(end 9.2075 -174.752)
		(width 0.1397)
		(layer "F.Cu")
		(net "SEB_PEER_1B_HB")
	)
	(via
		(at 15.5702 -58.2676)
		(size 0.5588)
		(drill 0.3048)
		(layers "F.Cu" "B.Cu")
		(net "SEB_PEER_1B_HB")
	)
	(via
		(at 11.811 -179.197)
		(size 0.5588)
		(drill 0.3048)
		(layers "F.Cu" "B.Cu")
		(net "SEB_PEER_1B_HB")
	)
	(via
		(at 11.0236 -44.27855)
		(size 0.5588)
		(drill 0.3048)
		(layers "F.Cu" "B.Cu")
		(net "SEB_PEER_1B_HB")
	)
	(via
		(at 9.652 -58.039)
		(size 0.5588)
		(drill 0.3048)
		(layers "F.Cu" "B.Cu")
		(net "SEB_PEER_1B_HB")
	)
	(segment
		(start 11.0236 -44.27855)
		(end 10.96645 -44.27855)
		(width 0.1397)
		(layer "B.Cu")
		(net "SEB_PEER_1B_HB")
	)
	(segment
		(start 4.9022 -69.355716)
		(end 5.6134 -68.644516)
		(width 0.1397)
		(layer "B.Cu")
		(net "SEB_PEER_1B_HB")
	)
	(segment
		(start 4.977384 -142.010384)
		(end 4.977384 -134.976616)
		(width 0.1397)
		(layer "B.Cu")
		(net "SEB_PEER_1B_HB")
	)
	(segment
		(start 24.659336 -50.999136)
		(end 25.580086 -51.919886)
		(width 0.1397)
		(layer "B.Cu")
		(net "SEB_PEER_1B_HB")
	)
	(segment
		(start 3.605784 -82.666332)
		(end 4.9022 -81.369916)
		(width 0.1397)
		(layer "B.Cu")
		(net "SEB_PEER_1B_HB")
	)
	(segment
		(start 3.131566 -113.806478)
		(end 3.605784 -113.33226)
		(width 0.1397)
		(layer "B.Cu")
		(net "SEB_PEER_1B_HB")
	)
	(segment
		(start 10.96645 -44.27855)
		(end 9.20623 -46.03877)
		(width 0.1397)
		(layer "B.Cu")
		(net "SEB_PEER_1B_HB")
	)
	(segment
		(start 15.5702 -54.761892)
		(end 19.777456 -50.554636)
		(width 0.1397)
		(layer "B.Cu")
		(net "SEB_PEER_1B_HB")
	)
	(segment
		(start 11.811 -178.308)
		(end 12.33805 -177.78095)
		(width 0.1397)
		(layer "B.Cu")
		(net "SEB_PEER_1B_HB")
	)
	(segment
		(start 5.6134 -62.357)
		(end 9.652 -58.3184)
		(width 0.1397)
		(layer "B.Cu")
		(net "SEB_PEER_1B_HB")
	)
	(segment
		(start 9.7536 -52.578)
		(end 9.7536 -57.9374)
		(width 0.1397)
		(layer "B.Cu")
		(net "SEB_PEER_1B_HB")
	)
	(segment
		(start 12.33805 -177.78095)
		(end 12.33805 -151.27605)
		(width 0.1397)
		(layer "B.Cu")
		(net "SEB_PEER_1B_HB")
	)
	(segment
		(start 4.9022 -81.369916)
		(end 4.9022 -69.355716)
		(width 0.1397)
		(layer "B.Cu")
		(net "SEB_PEER_1B_HB")
	)
	(segment
		(start 5.951474 -121.82348)
		(end 3.131566 -119.003572)
		(width 0.1397)
		(layer "B.Cu")
		(net "SEB_PEER_1B_HB")
	)
	(segment
		(start 21.535136 -50.999136)
		(end 24.659336 -50.999136)
		(width 0.1397)
		(layer "B.Cu")
		(net "SEB_PEER_1B_HB")
	)
	(segment
		(start 5.6134 -68.644516)
		(end 5.6134 -62.357)
		(width 0.1397)
		(layer "B.Cu")
		(net "SEB_PEER_1B_HB")
	)
	(segment
		(start 5.951474 -134.002526)
		(end 5.951474 -121.82348)
		(width 0.1397)
		(layer "B.Cu")
		(net "SEB_PEER_1B_HB")
	)
	(segment
		(start 3.131566 -119.003572)
		(end 3.131566 -113.806478)
		(width 0.1397)
		(layer "B.Cu")
		(net "SEB_PEER_1B_HB")
	)
	(segment
		(start 21.090636 -50.554636)
		(end 21.535136 -50.999136)
		(width 0.1397)
		(layer "B.Cu")
		(net "SEB_PEER_1B_HB")
	)
	(segment
		(start 15.5702 -58.2676)
		(end 15.5702 -54.761892)
		(width 0.1397)
		(layer "B.Cu")
		(net "SEB_PEER_1B_HB")
	)
	(segment
		(start 9.20623 -46.03877)
		(end 9.20623 -52.03063)
		(width 0.1397)
		(layer "B.Cu")
		(net "SEB_PEER_1B_HB")
	)
	(segment
		(start 9.20623 -52.03063)
		(end 9.7536 -52.578)
		(width 0.1397)
		(layer "B.Cu")
		(net "SEB_PEER_1B_HB")
	)
	(segment
		(start 9.7536 -57.9374)
		(end 9.652 -58.039)
		(width 0.1397)
		(layer "B.Cu")
		(net "SEB_PEER_1B_HB")
	)
	(segment
		(start 4.977384 -134.976616)
		(end 5.951474 -134.002526)
		(width 0.1397)
		(layer "B.Cu")
		(net "SEB_PEER_1B_HB")
	)
	(segment
		(start 11.811 -179.197)
		(end 11.811 -178.308)
		(width 0.1397)
		(layer "B.Cu")
		(net "SEB_PEER_1B_HB")
	)
	(segment
		(start 19.777456 -50.554636)
		(end 21.090636 -50.554636)
		(width 0.1397)
		(layer "B.Cu")
		(net "SEB_PEER_1B_HB")
	)
	(segment
		(start 7.48665 -146.42465)
		(end 7.48665 -144.51965)
		(width 0.1397)
		(layer "B.Cu")
		(net "SEB_PEER_1B_HB")
	)
	(segment
		(start 12.33805 -151.27605)
		(end 7.48665 -146.42465)
		(width 0.1397)
		(layer "B.Cu")
		(net "SEB_PEER_1B_HB")
	)
	(segment
		(start 9.652 -58.3184)
		(end 9.652 -58.039)
		(width 0.1397)
		(layer "B.Cu")
		(net "SEB_PEER_1B_HB")
	)
	(segment
		(start 7.48665 -144.51965)
		(end 4.977384 -142.010384)
		(width 0.1397)
		(layer "B.Cu")
		(net "SEB_PEER_1B_HB")
	)
	(segment
		(start 3.605784 -113.33226)
		(end 3.605784 -82.666332)
		(width 0.1397)
		(layer "B.Cu")
		(net "SEB_PEER_1B_HB")
	)
	(segment
		(start 11.7983 -56.0197)
		(end 13.0048 -57.2262)
		(width 0.1397)
		(layer "F.Cu")
		(net "PEER_TRAY PRESENT_UPPER")
	)
	(segment
		(start 13.0048 -57.2262)
		(end 17.4244 -57.2262)
		(width 0.1397)
		(layer "F.Cu")
		(net "PEER_TRAY PRESENT_UPPER")
	)
	(segment
		(start 27.383486 -62.079886)
		(end 28.120086 -62.079886)
		(width 0.1397)
		(layer "F.Cu")
		(net "PEER_TRAY PRESENT_UPPER")
	)
	(segment
		(start 18.9992 -58.8772)
		(end 18.9992 -59.341258)
		(width 0.1397)
		(layer "F.Cu")
		(net "PEER_TRAY PRESENT_UPPER")
	)
	(segment
		(start 11.7983 -55.2196)
		(end 11.7983 -56.0197)
		(width 0.1397)
		(layer "F.Cu")
		(net "PEER_TRAY PRESENT_UPPER")
	)
	(segment
		(start 26.0858 -60.7822)
		(end 27.383486 -62.079886)
		(width 0.1397)
		(layer "F.Cu")
		(net "PEER_TRAY PRESENT_UPPER")
	)
	(segment
		(start 18.9992 -59.341258)
		(end 20.440142 -60.7822)
		(width 0.1397)
		(layer "F.Cu")
		(net "PEER_TRAY PRESENT_UPPER")
	)
	(segment
		(start 17.4244 -57.2262)
		(end 17.6276 -57.4294)
		(width 0.1397)
		(layer "F.Cu")
		(net "PEER_TRAY PRESENT_UPPER")
	)
	(segment
		(start 20.440142 -60.7822)
		(end 26.0858 -60.7822)
		(width 0.1397)
		(layer "F.Cu")
		(net "PEER_TRAY PRESENT_UPPER")
	)
	(via
		(at 18.9992 -58.8772)
		(size 0.5588)
		(drill 0.3048)
		(layers "F.Cu" "B.Cu")
		(net "PEER_TRAY PRESENT_UPPER")
	)
	(via
		(at 17.6276 -57.4294)
		(size 0.5588)
		(drill 0.3048)
		(layers "F.Cu" "B.Cu")
		(net "PEER_TRAY PRESENT_UPPER")
	)
	(segment
		(start 18.9992 -58.801)
		(end 17.6276 -57.4294)
		(width 0.1397)
		(layer "B.Cu")
		(net "PEER_TRAY PRESENT_UPPER")
	)
	(segment
		(start 18.9992 -58.8772)
		(end 18.9992 -58.801)
		(width 0.1397)
		(layer "B.Cu")
		(net "PEER_TRAY PRESENT_UPPER")
	)
	(segment
		(start 34.948114 -62.079886)
		(end 34.0233 -63.0047)
		(width 0.1397)
		(layer "F.Cu")
		(net "I2C_C_SDA_CONN_R")
	)
	(segment
		(start 21.4249 -63.0047)
		(end 20.500086 -62.079886)
		(width 0.1397)
		(layer "F.Cu")
		(net "I2C_C_SDA_CONN_R")
	)
	(segment
		(start 37.999924 -62.079886)
		(end 34.948114 -62.079886)
		(width 0.1397)
		(layer "F.Cu")
		(net "I2C_C_SDA_CONN_R")
	)
	(segment
		(start 16.002 -67.1195)
		(end 16.002 -66.1162)
		(width 0.1397)
		(layer "F.Cu")
		(net "I2C_C_SDA_CONN_R")
	)
	(segment
		(start 15.8877 -66.0019)
		(end 15.9258 -66.04)
		(width 0.1397)
		(layer "F.Cu")
		(net "I2C_C_SDA_CONN_R")
	)
	(segment
		(start 34.0233 -63.0047)
		(end 21.4249 -63.0047)
		(width 0.1397)
		(layer "F.Cu")
		(net "I2C_C_SDA_CONN_R")
	)
	(segment
		(start 20.500086 -62.811914)
		(end 16.1925 -67.1195)
		(width 0.1397)
		(layer "F.Cu")
		(net "I2C_C_SDA_CONN_R")
	)
	(segment
		(start 14.8082 -66.0019)
		(end 15.8877 -66.0019)
		(width 0.1397)
		(layer "F.Cu")
		(net "I2C_C_SDA_CONN_R")
	)
	(segment
		(start 20.500086 -62.079886)
		(end 20.500086 -62.811914)
		(width 0.1397)
		(layer "F.Cu")
		(net "I2C_C_SDA_CONN_R")
	)
	(segment
		(start 16.002 -66.1162)
		(end 15.9258 -66.04)
		(width 0.1397)
		(layer "F.Cu")
		(net "I2C_C_SDA_CONN_R")
	)
	(segment
		(start 16.1925 -67.1195)
		(end 16.002 -67.1195)
		(width 0.1397)
		(layer "F.Cu")
		(net "I2C_C_SDA_CONN_R")
	)
	(segment
		(start 11.7983 -53.178456)
		(end 13.433806 -51.54295)
		(width 0.1397)
		(layer "F.Cu")
		(net "SELF_TRAY_PRESENT_UPPER")
	)
	(segment
		(start 26.754836 -50.554636)
		(end 28.120086 -51.919886)
		(width 0.1397)
		(layer "F.Cu")
		(net "SELF_TRAY_PRESENT_UPPER")
	)
	(segment
		(start 11.7983 -54.2036)
		(end 11.7983 -53.178456)
		(width 0.1397)
		(layer "F.Cu")
		(net "SELF_TRAY_PRESENT_UPPER")
	)
	(segment
		(start 13.433806 -51.54295)
		(end 16.50365 -51.54295)
		(width 0.1397)
		(layer "F.Cu")
		(net "SELF_TRAY_PRESENT_UPPER")
	)
	(segment
		(start 17.491964 -50.554636)
		(end 26.754836 -50.554636)
		(width 0.1397)
		(layer "F.Cu")
		(net "SELF_TRAY_PRESENT_UPPER")
	)
	(segment
		(start 16.50365 -51.54295)
		(end 17.491964 -50.554636)
		(width 0.1397)
		(layer "F.Cu")
		(net "SELF_TRAY_PRESENT_UPPER")
	)
	(segment
		(start 30.7594 -59.6646)
		(end 31.555436 -60.460636)
		(width 0.1397)
		(layer "F.Cu")
		(net "LOWER_TRAY_ID")
	)
	(segment
		(start 15.5575 -56.134)
		(end 15.5575 -55.118)
		(width 0.1397)
		(layer "F.Cu")
		(net "LOWER_TRAY_ID")
	)
	(segment
		(start 29.8704 -59.6646)
		(end 30.7594 -59.6646)
		(width 0.1397)
		(layer "F.Cu")
		(net "LOWER_TRAY_ID")
	)
	(segment
		(start 31.555436 -60.460636)
		(end 44.699174 -60.460636)
		(width 0.1397)
		(layer "F.Cu")
		(net "LOWER_TRAY_ID")
	)
	(segment
		(start 17.0688 -56.134)
		(end 17.9324 -55.2704)
		(width 0.1397)
		(layer "F.Cu")
		(net "LOWER_TRAY_ID")
	)
	(segment
		(start 15.5575 -56.134)
		(end 17.0688 -56.134)
		(width 0.1397)
		(layer "F.Cu")
		(net "LOWER_TRAY_ID")
	)
	(segment
		(start 44.699174 -60.460636)
		(end 45.619924 -59.539886)
		(width 0.1397)
		(layer "F.Cu")
		(net "LOWER_TRAY_ID")
	)
	(via
		(at 29.8704 -59.6646)
		(size 0.5588)
		(drill 0.3048)
		(layers "F.Cu" "B.Cu")
		(net "LOWER_TRAY_ID")
	)
	(via
		(at 17.9324 -55.2704)
		(size 0.5588)
		(drill 0.3048)
		(layers "F.Cu" "B.Cu")
		(net "LOWER_TRAY_ID")
	)
	(segment
		(start 23.273258 -58.4708)
		(end 23.208742 -58.4708)
		(width 0.1397)
		(layer "B.Cu")
		(net "LOWER_TRAY_ID")
	)
	(segment
		(start 24.638 -59.900058)
		(end 24.638 -59.835542)
		(width 0.1397)
		(layer "B.Cu")
		(net "LOWER_TRAY_ID")
	)
	(segment
		(start 18.0594 -55.3974)
		(end 17.9324 -55.2704)
		(width 0.1397)
		(layer "B.Cu")
		(net "LOWER_TRAY_ID")
	)
	(segment
		(start 23.208742 -58.4708)
		(end 21.8948 -57.156858)
		(width 0.1397)
		(layer "B.Cu")
		(net "LOWER_TRAY_ID")
	)
	(segment
		(start 21.8948 -57.156858)
		(end 21.8948 -56.463692)
		(width 0.1397)
		(layer "B.Cu")
		(net "LOWER_TRAY_ID")
	)
	(segment
		(start 21.8948 -56.463692)
		(end 20.828508 -55.3974)
		(width 0.1397)
		(layer "B.Cu")
		(net "LOWER_TRAY_ID")
	)
	(segment
		(start 24.638 -59.835542)
		(end 23.273258 -58.4708)
		(width 0.1397)
		(layer "B.Cu")
		(net "LOWER_TRAY_ID")
	)
	(segment
		(start 20.828508 -55.3974)
		(end 18.0594 -55.3974)
		(width 0.1397)
		(layer "B.Cu")
		(net "LOWER_TRAY_ID")
	)
	(segment
		(start 29.8704 -59.6646)
		(end 29.074364 -60.460636)
		(width 0.1397)
		(layer "B.Cu")
		(net "LOWER_TRAY_ID")
	)
	(segment
		(start 25.198578 -60.460636)
		(end 24.638 -59.900058)
		(width 0.1397)
		(layer "B.Cu")
		(net "LOWER_TRAY_ID")
	)
	(segment
		(start 29.074364 -60.460636)
		(end 25.198578 -60.460636)
		(width 0.1397)
		(layer "B.Cu")
		(net "LOWER_TRAY_ID")
	)
	(segment
		(start 27.738578 -57.920636)
		(end 37.079174 -57.920636)
		(width 0.1397)
		(layer "F.Cu")
		(net "I2C_C_SCL_CONN_R")
	)
	(segment
		(start 18.63725 -59.81065)
		(end 18.63725 -63.9191)
		(width 0.1397)
		(layer "F.Cu")
		(net "I2C_C_SCL_CONN_R")
	)
	(segment
		(start 18.2245 -64.33185)
		(end 16.92275 -64.33185)
		(width 0.1397)
		(layer "F.Cu")
		(net "I2C_C_SCL_CONN_R")
	)
	(segment
		(start 13.7922 -64.7446)
		(end 14.3256 -64.2112)
		(width 0.1397)
		(layer "F.Cu")
		(net "I2C_C_SCL_CONN_R")
	)
	(segment
		(start 18.63725 -63.9191)
		(end 18.2245 -64.33185)
		(width 0.1397)
		(layer "F.Cu")
		(net "I2C_C_SCL_CONN_R")
	)
	(segment
		(start 15.9004 -63.3095)
		(end 15.2273 -63.3095)
		(width 0.1397)
		(layer "F.Cu")
		(net "I2C_C_SCL_CONN_R")
	)
	(segment
		(start 13.7922 -66.0019)
		(end 13.7922 -64.7446)
		(width 0.1397)
		(layer "F.Cu")
		(net "I2C_C_SCL_CONN_R")
	)
	(segment
		(start 19.979386 -56.999886)
		(end 18.4785 -58.500772)
		(width 0.1397)
		(layer "F.Cu")
		(net "I2C_C_SCL_CONN_R")
	)
	(segment
		(start 20.500086 -56.999886)
		(end 19.979386 -56.999886)
		(width 0.1397)
		(layer "F.Cu")
		(net "I2C_C_SCL_CONN_R")
	)
	(segment
		(start 25.961594 -56.079136)
		(end 26.5176 -56.635142)
		(width 0.1397)
		(layer "F.Cu")
		(net "I2C_C_SCL_CONN_R")
	)
	(segment
		(start 20.500086 -56.999886)
		(end 21.420836 -56.079136)
		(width 0.1397)
		(layer "F.Cu")
		(net "I2C_C_SCL_CONN_R")
	)
	(segment
		(start 21.420836 -56.079136)
		(end 25.961594 -56.079136)
		(width 0.1397)
		(layer "F.Cu")
		(net "I2C_C_SCL_CONN_R")
	)
	(segment
		(start 15.2273 -63.3095)
		(end 14.3256 -64.2112)
		(width 0.1397)
		(layer "F.Cu")
		(net "I2C_C_SCL_CONN_R")
	)
	(segment
		(start 26.5176 -56.699658)
		(end 27.738578 -57.920636)
		(width 0.1397)
		(layer "F.Cu")
		(net "I2C_C_SCL_CONN_R")
	)
	(segment
		(start 37.079174 -57.920636)
		(end 37.999924 -56.999886)
		(width 0.1397)
		(layer "F.Cu")
		(net "I2C_C_SCL_CONN_R")
	)
	(segment
		(start 18.4785 -58.500772)
		(end 18.4785 -59.6519)
		(width 0.1397)
		(layer "F.Cu")
		(net "I2C_C_SCL_CONN_R")
	)
	(segment
		(start 26.5176 -56.635142)
		(end 26.5176 -56.699658)
		(width 0.1397)
		(layer "F.Cu")
		(net "I2C_C_SCL_CONN_R")
	)
	(segment
		(start 16.92275 -64.33185)
		(end 15.9004 -63.3095)
		(width 0.1397)
		(layer "F.Cu")
		(net "I2C_C_SCL_CONN_R")
	)
	(segment
		(start 18.4785 -59.6519)
		(end 18.63725 -59.81065)
		(width 0.1397)
		(layer "F.Cu")
		(net "I2C_C_SCL_CONN_R")
	)
	(segment
		(start 14.4526 -60.9727)
		(end 15.494 -60.9727)
		(width 0.1397)
		(layer "F.Cu")
		(net "UPPER_TRAY_ID")
	)
	(segment
		(start 15.9639 -60.9727)
		(end 15.494 -60.9727)
		(width 0.1397)
		(layer "F.Cu")
		(net "UPPER_TRAY_ID")
	)
	(segment
		(start 26.754836 -58.174636)
		(end 28.120086 -59.539886)
		(width 0.1397)
		(layer "F.Cu")
		(net "UPPER_TRAY_ID")
	)
	(segment
		(start 17.7546 -60.0964)
		(end 17.145 -60.706)
		(width 0.1397)
		(layer "F.Cu")
		(net "UPPER_TRAY_ID")
	)
	(segment
		(start 19.7866 -58.174636)
		(end 26.754836 -58.174636)
		(width 0.1397)
		(layer "F.Cu")
		(net "UPPER_TRAY_ID")
	)
	(segment
		(start 16.2306 -60.706)
		(end 15.9639 -60.9727)
		(width 0.1397)
		(layer "F.Cu")
		(net "UPPER_TRAY_ID")
	)
	(segment
		(start 17.145 -60.706)
		(end 16.2306 -60.706)
		(width 0.1397)
		(layer "F.Cu")
		(net "UPPER_TRAY_ID")
	)
	(via
		(at 19.7866 -58.174636)
		(size 0.5588)
		(drill 0.3048)
		(layers "F.Cu" "B.Cu")
		(net "UPPER_TRAY_ID")
	)
	(via
		(at 17.7546 -60.0964)
		(size 0.5588)
		(drill 0.3048)
		(layers "F.Cu" "B.Cu")
		(net "UPPER_TRAY_ID")
	)
	(segment
		(start 17.7546 -60.0964)
		(end 17.907 -59.944)
		(width 0.1397)
		(layer "B.Cu")
		(net "UPPER_TRAY_ID")
	)
	(segment
		(start 17.907 -59.944)
		(end 18.606008 -59.944)
		(width 0.1397)
		(layer "B.Cu")
		(net "UPPER_TRAY_ID")
	)
	(segment
		(start 19.7866 -58.763408)
		(end 19.7866 -58.174636)
		(width 0.1397)
		(layer "B.Cu")
		(net "UPPER_TRAY_ID")
	)
	(segment
		(start 18.606008 -59.944)
		(end 19.7866 -58.763408)
		(width 0.1397)
		(layer "B.Cu")
		(net "UPPER_TRAY_ID")
	)
	(segment
		(start 17.3228 -53.6829)
		(end 18.1356 -52.8701)
		(width 0.1397)
		(layer "F.Cu")
		(net "FCB_HW_REVISION")
	)
	(segment
		(start 40.158162 -57.920636)
		(end 39.2938 -57.056274)
		(width 0.1397)
		(layer "F.Cu")
		(net "FCB_HW_REVISION")
	)
	(segment
		(start 38.426136 -56.079136)
		(end 29.040836 -56.079136)
		(width 0.1397)
		(layer "F.Cu")
		(net "FCB_HW_REVISION")
	)
	(segment
		(start 39.2938 -57.056274)
		(end 39.2938 -56.9468)
		(width 0.1397)
		(layer "F.Cu")
		(net "FCB_HW_REVISION")
	)
	(segment
		(start 29.040836 -56.079136)
		(end 28.120086 -56.999886)
		(width 0.1397)
		(layer "F.Cu")
		(net "FCB_HW_REVISION")
	)
	(segment
		(start 15.6464 -53.6829)
		(end 17.3228 -53.6829)
		(width 0.1397)
		(layer "F.Cu")
		(net "FCB_HW_REVISION")
	)
	(segment
		(start 45.619924 -56.999886)
		(end 44.699174 -57.920636)
		(width 0.1397)
		(layer "F.Cu")
		(net "FCB_HW_REVISION")
	)
	(segment
		(start 39.2938 -56.9468)
		(end 38.426136 -56.079136)
		(width 0.1397)
		(layer "F.Cu")
		(net "FCB_HW_REVISION")
	)
	(segment
		(start 44.699174 -57.920636)
		(end 40.158162 -57.920636)
		(width 0.1397)
		(layer "F.Cu")
		(net "FCB_HW_REVISION")
	)
	(segment
		(start 14.5796 -53.6829)
		(end 15.6464 -53.6829)
		(width 0.1397)
		(layer "F.Cu")
		(net "FCB_HW_REVISION")
	)
	(via
		(at 18.1356 -52.8701)
		(size 0.5588)
		(drill 0.3048)
		(layers "F.Cu" "B.Cu")
		(net "FCB_HW_REVISION")
	)
	(segment
		(start 18.1356 -52.8701)
		(end 20.006564 -50.999136)
		(width 0.1397)
		(layer "B.Cu")
		(net "FCB_HW_REVISION")
	)
	(segment
		(start 20.881594 -50.999136)
		(end 22.098 -52.215542)
		(width 0.1397)
		(layer "B.Cu")
		(net "FCB_HW_REVISION")
	)
	(segment
		(start 20.006564 -50.999136)
		(end 20.881594 -50.999136)
		(width 0.1397)
		(layer "B.Cu")
		(net "FCB_HW_REVISION")
	)
	(segment
		(start 22.098 -54.820058)
		(end 22.878542 -55.6006)
		(width 0.1397)
		(layer "B.Cu")
		(net "FCB_HW_REVISION")
	)
	(segment
		(start 24.4348 -57.156858)
		(end 25.198578 -57.920636)
		(width 0.1397)
		(layer "B.Cu")
		(net "FCB_HW_REVISION")
	)
	(segment
		(start 27.199336 -57.920636)
		(end 28.120086 -56.999886)
		(width 0.1397)
		(layer "B.Cu")
		(net "FCB_HW_REVISION")
	)
	(segment
		(start 25.198578 -57.920636)
		(end 27.199336 -57.920636)
		(width 0.1397)
		(layer "B.Cu")
		(net "FCB_HW_REVISION")
	)
	(segment
		(start 22.098 -52.215542)
		(end 22.098 -54.820058)
		(width 0.1397)
		(layer "B.Cu")
		(net "FCB_HW_REVISION")
	)
	(segment
		(start 24.4348 -56.463692)
		(end 24.4348 -57.156858)
		(width 0.1397)
		(layer "B.Cu")
		(net "FCB_HW_REVISION")
	)
	(segment
		(start 23.571708 -55.6006)
		(end 24.4348 -56.463692)
		(width 0.1397)
		(layer "B.Cu")
		(net "FCB_HW_REVISION")
	)
	(segment
		(start 22.878542 -55.6006)
		(end 23.571708 -55.6006)
		(width 0.1397)
		(layer "B.Cu")
		(net "FCB_HW_REVISION")
	)
	(segment
		(start 16.986758 -58.74385)
		(end 20.349972 -55.380636)
		(width 0.1397)
		(layer "F.Cu")
		(net "SEB_PEER_1A_HB")
	)
	(segment
		(start 10.86485 -58.24855)
		(end 14.877542 -58.24855)
		(width 0.1397)
		(layer "F.Cu")
		(net "SEB_PEER_1A_HB")
	)
	(segment
		(start 20.349972 -55.380636)
		(end 24.659336 -55.380636)
		(width 0.1397)
		(layer "F.Cu")
		(net "SEB_PEER_1A_HB")
	)
	(segment
		(start 14.877542 -58.24855)
		(end 15.372842 -58.74385)
		(width 0.1397)
		(layer "F.Cu")
		(net "SEB_PEER_1A_HB")
	)
	(segment
		(start 11.6332 -46.5582)
		(end 11.0998 -46.0248)
		(width 0.1397)
		(layer "F.Cu")
		(net "SEB_PEER_1A_HB")
	)
	(segment
		(start 15.372842 -58.74385)
		(end 16.986758 -58.74385)
		(width 0.1397)
		(layer "F.Cu")
		(net "SEB_PEER_1A_HB")
	)
	(segment
		(start 24.659336 -55.380636)
		(end 25.580086 -54.459886)
		(width 0.1397)
		(layer "F.Cu")
		(net "SEB_PEER_1A_HB")
	)
	(segment
		(start 10.922 -178.689)
		(end 9.2075 -176.9745)
		(width 0.1397)
		(layer "F.Cu")
		(net "SEB_PEER_1A_HB")
	)
	(segment
		(start 14.4399 -46.5582)
		(end 11.6332 -46.5582)
		(width 0.1397)
		(layer "F.Cu")
		(net "SEB_PEER_1A_HB")
	)
	(segment
		(start 14.4399 -46.5582)
		(end 14.4399 -45.5422)
		(width 0.1397)
		(layer "F.Cu")
		(net "SEB_PEER_1A_HB")
	)
	(segment
		(start 10.4394 -58.674)
		(end 10.86485 -58.24855)
		(width 0.1397)
		(layer "F.Cu")
		(net "SEB_PEER_1A_HB")
	)
	(segment
		(start 12.573 -178.689)
		(end 10.922 -178.689)
		(width 0.1397)
		(layer "F.Cu")
		(net "SEB_PEER_1A_HB")
	)
	(segment
		(start 9.2075 -176.9745)
		(end 9.2075 -175.40224)
		(width 0.1397)
		(layer "F.Cu")
		(net "SEB_PEER_1A_HB")
	)
	(via
		(at 11.0998 -46.0248)
		(size 0.5588)
		(drill 0.3048)
		(layers "F.Cu" "B.Cu")
		(net "SEB_PEER_1A_HB")
	)
	(via
		(at 12.573 -178.689)
		(size 0.5588)
		(drill 0.3048)
		(layers "F.Cu" "B.Cu")
		(net "SEB_PEER_1A_HB")
	)
	(via
		(at 10.4394 -58.674)
		(size 0.5588)
		(drill 0.3048)
		(layers "F.Cu" "B.Cu")
		(net "SEB_PEER_1A_HB")
	)
	(segment
		(start 12.78255 -178.47945)
		(end 12.573 -178.689)
		(width 0.1397)
		(layer "B.Cu")
		(net "SEB_PEER_1A_HB")
	)
	(segment
		(start 5.421884 -141.819884)
		(end 8.001 -144.399)
		(width 0.1397)
		(layer "B.Cu")
		(net "SEB_PEER_1A_HB")
	)
	(segment
		(start 10.01395 -47.11065)
		(end 11.0998 -46.0248)
		(width 0.1397)
		(layer "B.Cu")
		(net "SEB_PEER_1A_HB")
	)
	(segment
		(start 6.0706 -68.834)
		(end 5.3594 -69.5452)
		(width 0.1397)
		(layer "B.Cu")
		(net "SEB_PEER_1A_HB")
	)
	(segment
		(start 5.3594 -69.5452)
		(end 5.3594 -81.5594)
		(width 0.1397)
		(layer "B.Cu")
		(net "SEB_PEER_1A_HB")
	)
	(segment
		(start 3.576066 -113.990628)
		(end 3.576066 -118.819422)
		(width 0.1397)
		(layer "B.Cu")
		(net "SEB_PEER_1A_HB")
	)
	(segment
		(start 8.001 -146.177)
		(end 12.78255 -150.95855)
		(width 0.1397)
		(layer "B.Cu")
		(net "SEB_PEER_1A_HB")
	)
	(segment
		(start 10.4394 -58.674)
		(end 6.0706 -63.0428)
		(width 0.1397)
		(layer "B.Cu")
		(net "SEB_PEER_1A_HB")
	)
	(segment
		(start 8.001 -144.399)
		(end 8.001 -146.177)
		(width 0.1397)
		(layer "B.Cu")
		(net "SEB_PEER_1A_HB")
	)
	(segment
		(start 10.4394 -58.674)
		(end 10.4394 -52.6288)
		(width 0.1397)
		(layer "B.Cu")
		(net "SEB_PEER_1A_HB")
	)
	(segment
		(start 10.4394 -52.6288)
		(end 10.01395 -52.20335)
		(width 0.1397)
		(layer "B.Cu")
		(net "SEB_PEER_1A_HB")
	)
	(segment
		(start 12.78255 -150.95855)
		(end 12.78255 -178.47945)
		(width 0.1397)
		(layer "B.Cu")
		(net "SEB_PEER_1A_HB")
	)
	(segment
		(start 3.576066 -118.819422)
		(end 6.395974 -121.63933)
		(width 0.1397)
		(layer "B.Cu")
		(net "SEB_PEER_1A_HB")
	)
	(segment
		(start 10.01395 -52.20335)
		(end 10.01395 -47.11065)
		(width 0.1397)
		(layer "B.Cu")
		(net "SEB_PEER_1A_HB")
	)
	(segment
		(start 4.050284 -113.51641)
		(end 3.576066 -113.990628)
		(width 0.1397)
		(layer "B.Cu")
		(net "SEB_PEER_1A_HB")
	)
	(segment
		(start 5.421884 -135.167116)
		(end 5.421884 -141.819884)
		(width 0.1397)
		(layer "B.Cu")
		(net "SEB_PEER_1A_HB")
	)
	(segment
		(start 6.0706 -63.0428)
		(end 6.0706 -68.834)
		(width 0.1397)
		(layer "B.Cu")
		(net "SEB_PEER_1A_HB")
	)
	(segment
		(start 5.3594 -81.5594)
		(end 4.050284 -82.868516)
		(width 0.1397)
		(layer "B.Cu")
		(net "SEB_PEER_1A_HB")
	)
	(segment
		(start 6.395974 -134.193026)
		(end 5.421884 -135.167116)
		(width 0.1397)
		(layer "B.Cu")
		(net "SEB_PEER_1A_HB")
	)
	(segment
		(start 4.050284 -82.868516)
		(end 4.050284 -113.51641)
		(width 0.1397)
		(layer "B.Cu")
		(net "SEB_PEER_1A_HB")
	)
	(segment
		(start 6.395974 -121.63933)
		(end 6.395974 -134.193026)
		(width 0.1397)
		(layer "B.Cu")
		(net "SEB_PEER_1A_HB")
	)
	(segment
		(start 12.6238 -41.021)
		(end 14.1986 -39.4462)
		(width 0.1397)
		(layer "F.Cu")
		(net "SEB_PEER_2B_HB")
	)
	(segment
		(start 9.9822 -44.577)
		(end 9.9822 -44.2976)
		(width 0.1397)
		(layer "F.Cu")
		(net "SEB_PEER_2B_HB")
	)
	(segment
		(start 14.4399 -39.5732)
		(end 15.3289 -40.4622)
		(width 0.1397)
		(layer "F.Cu")
		(net "SEB_PEER_2B_HB")
	)
	(segment
		(start 28.1432 -42.2402)
		(end 36.449 -50.546)
		(width 0.1397)
		(layer "F.Cu")
		(net "SEB_PEER_2B_HB")
	)
	(segment
		(start 13.1445 -174.752)
		(end 12.617196 -174.752)
		(width 0.1397)
		(layer "F.Cu")
		(net "SEB_PEER_2B_HB")
	)
	(segment
		(start 41.706038 -50.546)
		(end 43.079924 -51.919886)
		(width 0.1397)
		(layer "F.Cu")
		(net "SEB_PEER_2B_HB")
	)
	(segment
		(start 16.3576 -40.4622)
		(end 18.1356 -42.2402)
		(width 0.1397)
		(layer "F.Cu")
		(net "SEB_PEER_2B_HB")
	)
	(segment
		(start 12.6238 -41.656)
		(end 12.6238 -41.021)
		(width 0.1397)
		(layer "F.Cu")
		(net "SEB_PEER_2B_HB")
	)
	(segment
		(start 14.1986 -39.4462)
		(end 14.4399 -39.4462)
		(width 0.1397)
		(layer "F.Cu")
		(net "SEB_PEER_2B_HB")
	)
	(segment
		(start 9.9822 -44.2976)
		(end 12.6238 -41.656)
		(width 0.1397)
		(layer "F.Cu")
		(net "SEB_PEER_2B_HB")
	)
	(segment
		(start 12.617196 -174.752)
		(end 11.020552 -176.348644)
		(width 0.1397)
		(layer "F.Cu")
		(net "SEB_PEER_2B_HB")
	)
	(segment
		(start 18.1356 -42.2402)
		(end 28.1432 -42.2402)
		(width 0.1397)
		(layer "F.Cu")
		(net "SEB_PEER_2B_HB")
	)
	(segment
		(start 36.449 -50.546)
		(end 41.706038 -50.546)
		(width 0.1397)
		(layer "F.Cu")
		(net "SEB_PEER_2B_HB")
	)
	(segment
		(start 14.4399 -39.4462)
		(end 14.4399 -39.5732)
		(width 0.1397)
		(layer "F.Cu")
		(net "SEB_PEER_2B_HB")
	)
	(segment
		(start 15.3289 -40.4622)
		(end 16.3576 -40.4622)
		(width 0.1397)
		(layer "F.Cu")
		(net "SEB_PEER_2B_HB")
	)
	(via
		(at 11.020552 -176.348644)
		(size 0.5588)
		(drill 0.3048)
		(layers "F.Cu" "B.Cu")
		(net "SEB_PEER_2B_HB")
	)
	(via
		(at 9.9822 -44.577)
		(size 0.5588)
		(drill 0.3048)
		(layers "F.Cu" "B.Cu")
		(net "SEB_PEER_2B_HB")
	)
	(segment
		(start 2.687574 -80.878426)
		(end 4.445 -79.121)
		(width 0.1397)
		(layer "B.Cu")
		(net "SEB_PEER_2B_HB")
	)
	(segment
		(start 2.687066 -119.187722)
		(end 2.687066 -113.622328)
		(width 0.1397)
		(layer "B.Cu")
		(net "SEB_PEER_2B_HB")
	)
	(segment
		(start 9.226296 -56.628792)
		(end 9.226296 -52.685696)
		(width 0.1397)
		(layer "B.Cu")
		(net "SEB_PEER_2B_HB")
	)
	(segment
		(start 8.75665 -52.21605)
		(end 8.75665 -45.80255)
		(width 0.1397)
		(layer "B.Cu")
		(net "SEB_PEER_2B_HB")
	)
	(segment
		(start 11.020552 -175.758856)
		(end 2.687574 -167.425878)
		(width 0.1397)
		(layer "B.Cu")
		(net "SEB_PEER_2B_HB")
	)
	(segment
		(start 4.445 -79.121)
		(end 4.445 -60.968382)
		(width 0.1397)
		(layer "B.Cu")
		(net "SEB_PEER_2B_HB")
	)
	(segment
		(start 4.445 -60.968382)
		(end 8.009382 -57.404)
		(width 0.1397)
		(layer "B.Cu")
		(net "SEB_PEER_2B_HB")
	)
	(segment
		(start 8.451088 -57.404)
		(end 9.226296 -56.628792)
		(width 0.1397)
		(layer "B.Cu")
		(net "SEB_PEER_2B_HB")
	)
	(segment
		(start 9.226296 -52.685696)
		(end 8.75665 -52.21605)
		(width 0.1397)
		(layer "B.Cu")
		(net "SEB_PEER_2B_HB")
	)
	(segment
		(start 11.020552 -176.348644)
		(end 11.020552 -175.758856)
		(width 0.1397)
		(layer "B.Cu")
		(net "SEB_PEER_2B_HB")
	)
	(segment
		(start 8.75665 -45.80255)
		(end 9.9822 -44.577)
		(width 0.1397)
		(layer "B.Cu")
		(net "SEB_PEER_2B_HB")
	)
	(segment
		(start 2.687574 -167.425878)
		(end 2.687574 -119.18823)
		(width 0.1397)
		(layer "B.Cu")
		(net "SEB_PEER_2B_HB")
	)
	(segment
		(start 2.687066 -113.622328)
		(end 2.687574 -113.62182)
		(width 0.1397)
		(layer "B.Cu")
		(net "SEB_PEER_2B_HB")
	)
	(segment
		(start 8.009382 -57.404)
		(end 8.451088 -57.404)
		(width 0.1397)
		(layer "B.Cu")
		(net "SEB_PEER_2B_HB")
	)
	(segment
		(start 2.687574 -119.18823)
		(end 2.687066 -119.187722)
		(width 0.1397)
		(layer "B.Cu")
		(net "SEB_PEER_2B_HB")
	)
	(segment
		(start 2.687574 -113.62182)
		(end 2.687574 -80.878426)
		(width 0.1397)
		(layer "B.Cu")
		(net "SEB_PEER_2B_HB")
	)
	(segment
		(start 39.3065 -143.3957)
		(end 39.3065 -143.5862)
		(width 0.1397)
		(layer "F.Cu")
		(net "P12VL_2490_EN_2")
	)
	(segment
		(start 39.3065 -143.5862)
		(end 38.989 -143.9037)
		(width 0.1397)
		(layer "F.Cu")
		(net "P12VL_2490_EN_2")
	)
	(segment
		(start 38.89629 -142.0495)
		(end 38.89629 -143.81099)
		(width 0.1397)
		(layer "F.Cu")
		(net "P12VL_2490_EN_2")
	)
	(segment
		(start 40.7162 -141.9606)
		(end 40.7162 -141.986)
		(width 0.1397)
		(layer "F.Cu")
		(net "P12VL_2490_EN_2")
	)
	(segment
		(start 40.7162 -141.986)
		(end 39.3065 -143.3957)
		(width 0.1397)
		(layer "F.Cu")
		(net "P12VL_2490_EN_2")
	)
	(segment
		(start 43.7134 -139.4714)
		(end 43.2054 -139.4714)
		(width 0.1397)
		(layer "F.Cu")
		(net "P12VL_2490_EN_2")
	)
	(segment
		(start 42.1386 -140.5382)
		(end 40.7162 -141.9606)
		(width 0.1397)
		(layer "F.Cu")
		(net "P12VL_2490_EN_2")
	)
	(segment
		(start 38.89629 -143.81099)
		(end 38.989 -143.9037)
		(width 0.1397)
		(layer "F.Cu")
		(net "P12VL_2490_EN_2")
	)
	(segment
		(start 44.647104 -139.4714)
		(end 43.7134 -139.4714)
		(width 0.1397)
		(layer "F.Cu")
		(net "P12VL_2490_EN_2")
	)
	(segment
		(start 43.2054 -139.4714)
		(end 42.1386 -140.5382)
		(width 0.1397)
		(layer "F.Cu")
		(net "P12VL_2490_EN_2")
	)
	(segment
		(start 46.377352 -137.741152)
		(end 44.647104 -139.4714)
		(width 0.1397)
		(layer "F.Cu")
		(net "P12VL_2490_EN_2")
	)
	(via
		(at 46.377352 -137.741152)
		(size 0.5588)
		(drill 0.3048)
		(layers "F.Cu" "B.Cu")
		(net "P12VL_2490_EN_2")
	)
	(segment
		(start 51.60645 -122.402854)
		(end 49.86655 -124.142754)
		(width 0.1397)
		(layer "B.Cu")
		(net "P12VL_2490_EN_2")
	)
	(segment
		(start 44.372784 -60.833)
		(end 46.2788 -60.833)
		(width 0.1397)
		(layer "B.Cu")
		(net "P12VL_2490_EN_2")
	)
	(segment
		(start 43.079924 -59.54014)
		(end 44.372784 -60.833)
		(width 0.1397)
		(layer "B.Cu")
		(net "P12VL_2490_EN_2")
	)
	(segment
		(start 46.2788 -60.833)
		(end 50.362104 -64.916304)
		(width 0.1397)
		(layer "B.Cu")
		(net "P12VL_2490_EN_2")
	)
	(segment
		(start 43.079924 -59.539886)
		(end 43.079924 -59.54014)
		(width 0.1397)
		(layer "B.Cu")
		(net "P12VL_2490_EN_2")
	)
	(segment
		(start 49.86655 -124.142754)
		(end 49.86655 -134.251954)
		(width 0.1397)
		(layer "B.Cu")
		(net "P12VL_2490_EN_2")
	)
	(segment
		(start 49.86655 -134.251954)
		(end 46.377352 -137.741152)
		(width 0.1397)
		(layer "B.Cu")
		(net "P12VL_2490_EN_2")
	)
	(segment
		(start 50.362104 -64.916304)
		(end 50.362104 -103.721662)
		(width 0.1397)
		(layer "B.Cu")
		(net "P12VL_2490_EN_2")
	)
	(segment
		(start 51.60645 -104.966008)
		(end 51.60645 -122.402854)
		(width 0.1397)
		(layer "B.Cu")
		(net "P12VL_2490_EN_2")
	)
	(segment
		(start 50.362104 -103.721662)
		(end 51.60645 -104.966008)
		(width 0.1397)
		(layer "B.Cu")
		(net "P12VL_2490_EN_2")
	)
	(segment
		(start 39.9034 -145.8595)
		(end 39.9034 -143.6116)
		(width 0.1397)
		(layer "F.Cu")
		(net "P12VL_2490_EN_1")
	)
	(segment
		(start 39.9034 -143.6116)
		(end 40.64 -142.875)
		(width 0.1397)
		(layer "F.Cu")
		(net "P12VL_2490_EN_1")
	)
	(segment
		(start 40.132 -146.0881)
		(end 39.9034 -145.8595)
		(width 0.1397)
		(layer "F.Cu")
		(net "P12VL_2490_EN_1")
	)
	(via
		(at 40.64 -142.875)
		(size 0.5588)
		(drill 0.3048)
		(layers "F.Cu" "B.Cu")
		(net "P12VL_2490_EN_1")
	)
	(via
		(at 46.736762 -136.270238)
		(size 0.7112)
		(drill 0.3556)
		(layers "F.Cu" "B.Cu")
		(net "P12VL_2490_EN_1")
	)
	(segment
		(start 40.64 -142.367)
		(end 46.736762 -136.270238)
		(width 0.1397)
		(layer "B.Cu")
		(net "P12VL_2490_EN_1")
	)
	(segment
		(start 47.4853 -135.5217)
		(end 46.736762 -136.270238)
		(width 0.1397)
		(layer "B.Cu")
		(net "P12VL_2490_EN_1")
	)
	(segment
		(start 49.91735 -67.4624)
		(end 49.91735 -106.71175)
		(width 0.1397)
		(layer "B.Cu")
		(net "P12VL_2490_EN_1")
	)
	(segment
		(start 50.37455 -111.354108)
		(end 50.927 -111.906558)
		(width 0.1397)
		(layer "B.Cu")
		(net "P12VL_2490_EN_1")
	)
	(segment
		(start 43.079924 -62.08014)
		(end 44.220384 -63.2206)
		(width 0.1397)
		(layer "B.Cu")
		(net "P12VL_2490_EN_1")
	)
	(segment
		(start 43.079924 -62.079886)
		(end 43.079924 -62.08014)
		(width 0.1397)
		(layer "B.Cu")
		(net "P12VL_2490_EN_1")
	)
	(segment
		(start 40.64 -142.875)
		(end 40.64 -142.367)
		(width 0.1397)
		(layer "B.Cu")
		(net "P12VL_2490_EN_1")
	)
	(segment
		(start 44.220384 -63.2206)
		(end 45.67555 -63.2206)
		(width 0.1397)
		(layer "B.Cu")
		(net "P12VL_2490_EN_1")
	)
	(segment
		(start 50.37455 -107.16895)
		(end 50.37455 -111.354108)
		(width 0.1397)
		(layer "B.Cu")
		(net "P12VL_2490_EN_1")
	)
	(segment
		(start 45.67555 -63.2206)
		(end 49.91735 -67.4624)
		(width 0.1397)
		(layer "B.Cu")
		(net "P12VL_2490_EN_1")
	)
	(segment
		(start 50.927 -111.906558)
		(end 50.927 -121.3866)
		(width 0.1397)
		(layer "B.Cu")
		(net "P12VL_2490_EN_1")
	)
	(segment
		(start 49.91735 -106.71175)
		(end 50.37455 -107.16895)
		(width 0.1397)
		(layer "B.Cu")
		(net "P12VL_2490_EN_1")
	)
	(segment
		(start 48.21555 -132.250942)
		(end 47.4853 -132.981192)
		(width 0.1397)
		(layer "B.Cu")
		(net "P12VL_2490_EN_1")
	)
	(segment
		(start 47.4853 -132.981192)
		(end 47.4853 -135.5217)
		(width 0.1397)
		(layer "B.Cu")
		(net "P12VL_2490_EN_1")
	)
	(segment
		(start 48.21555 -124.09805)
		(end 48.21555 -132.250942)
		(width 0.1397)
		(layer "B.Cu")
		(net "P12VL_2490_EN_1")
	)
	(segment
		(start 50.927 -121.3866)
		(end 48.21555 -124.09805)
		(width 0.1397)
		(layer "B.Cu")
		(net "P12VL_2490_EN_1")
	)
	(segment
		(start 18.3388 -398.4498)
		(end 19.1516 -399.2626)
		(width 0.508)
		(layer "F.Cu")
		(net "ADM1276_GATE_DRV0")
	)
	(segment
		(start 35.0139 -378.7394)
		(end 35.0266 -378.7521)
		(width 0.508)
		(layer "F.Cu")
		(net "ADM1276_GATE_DRV0")
	)
	(segment
		(start 19.1516 -399.2626)
		(end 19.1516 -400.2024)
		(width 0.508)
		(layer "F.Cu")
		(net "ADM1276_GATE_DRV0")
	)
	(segment
		(start 33.6042 -378.7394)
		(end 35.0139 -378.7394)
		(width 0.508)
		(layer "F.Cu")
		(net "ADM1276_GATE_DRV0")
	)
	(segment
		(start 17.1958 -398.4498)
		(end 18.3388 -398.4498)
		(width 0.508)
		(layer "F.Cu")
		(net "ADM1276_GATE_DRV0")
	)
	(via
		(at 17.1958 -398.4498)
		(size 0.5588)
		(drill 0.3048)
		(layers "F.Cu" "B.Cu")
		(net "ADM1276_GATE_DRV0")
	)
	(via
		(at 33.6042 -378.7394)
		(size 0.5588)
		(drill 0.3048)
		(layers "F.Cu" "B.Cu")
		(net "ADM1276_GATE_DRV0")
	)
	(via
		(at 20.8026 -383.5908)
		(size 0.7112)
		(drill 0.3556)
		(layers "F.Cu" "B.Cu")
		(net "ADM1276_GATE_DRV0")
	)
	(segment
		(start 24.257 -380.1364)
		(end 32.2072 -380.1364)
		(width 0.508)
		(layer "B.Cu")
		(net "ADM1276_GATE_DRV0")
	)
	(segment
		(start 20.8026 -383.5908)
		(end 24.257 -380.1364)
		(width 0.508)
		(layer "B.Cu")
		(net "ADM1276_GATE_DRV0")
	)
	(segment
		(start 17.1958 -387.1976)
		(end 20.8026 -383.5908)
		(width 0.508)
		(layer "B.Cu")
		(net "ADM1276_GATE_DRV0")
	)
	(segment
		(start 32.2072 -380.1364)
		(end 33.6042 -378.7394)
		(width 0.508)
		(layer "B.Cu")
		(net "ADM1276_GATE_DRV0")
	)
	(segment
		(start 17.1958 -398.4498)
		(end 17.1958 -387.1976)
		(width 0.508)
		(layer "B.Cu")
		(net "ADM1276_GATE_DRV0")
	)
	(segment
		(start 46.736 -111.633)
		(end 48.4505 -111.633)
		(width 0.508)
		(layer "F.Cu")
		(net "P12VL_2490_GATE_DRV_2")
	)
	(segment
		(start 48.4505 -110.901988)
		(end 48.4505 -111.633)
		(width 0.508)
		(layer "F.Cu")
		(net "P12VL_2490_GATE_DRV_2")
	)
	(segment
		(start 48.241712 -110.6932)
		(end 48.4505 -110.901988)
		(width 0.508)
		(layer "F.Cu")
		(net "P12VL_2490_GATE_DRV_2")
	)
	(via
		(at 48.241712 -110.6932)
		(size 0.7112)
		(drill 0.3556)
		(layers "F.Cu" "B.Cu")
		(net "P12VL_2490_GATE_DRV_2")
	)
	(segment
		(start 18.6182 -110.4392)
		(end 17.9705 -109.7915)
		(width 0.508)
		(layer "F.Cu")
		(net "P12VU_2490_GATE_DRV_2")
	)
	(segment
		(start 21.336 -110.998)
		(end 20.7772 -110.4392)
		(width 0.508)
		(layer "F.Cu")
		(net "P12VU_2490_GATE_DRV_2")
	)
	(segment
		(start 17.9705 -109.7915)
		(end 17.9705 -109.5502)
		(width 0.508)
		(layer "F.Cu")
		(net "P12VU_2490_GATE_DRV_2")
	)
	(segment
		(start 21.336 -111.76)
		(end 21.336 -110.998)
		(width 0.508)
		(layer "F.Cu")
		(net "P12VU_2490_GATE_DRV_2")
	)
	(segment
		(start 20.7772 -110.4392)
		(end 18.6182 -110.4392)
		(width 0.508)
		(layer "F.Cu")
		(net "P12VU_2490_GATE_DRV_2")
	)
	(segment
		(start 17.9705 -108.5469)
		(end 18.0086 -108.5088)
		(width 0.508)
		(layer "F.Cu")
		(net "P12VU_2490_GATE_DRV_2")
	)
	(segment
		(start 17.9705 -109.5502)
		(end 17.9705 -108.5469)
		(width 0.508)
		(layer "F.Cu")
		(net "P12VU_2490_GATE_DRV_2")
	)
	(via
		(at 18.0086 -108.5088)
		(size 0.7112)
		(drill 0.3556)
		(layers "F.Cu" "B.Cu")
		(net "P12VU_2490_GATE_DRV_2")
	)
	(segment
		(start 43.1292 -179.2224)
		(end 45.2374 -179.2224)
		(width 0.1397)
		(layer "F.Cu")
		(net "D_LATCH_Q#")
	)
	(segment
		(start 42.82948 -180.366416)
		(end 42.82948 -179.52212)
		(width 0.1397)
		(layer "F.Cu")
		(net "D_LATCH_Q#")
	)
	(segment
		(start 45.2374 -179.2224)
		(end 45.466 -179.451)
		(width 0.1397)
		(layer "F.Cu")
		(net "D_LATCH_Q#")
	)
	(segment
		(start 42.82948 -179.52212)
		(end 43.1292 -179.2224)
		(width 0.1397)
		(layer "F.Cu")
		(net "D_LATCH_Q#")
	)
	(segment
		(start 9.017 -434.848508)
		(end 9.017 -440.292998)
		(width 0.1397)
		(layer "F.Cu")
		(net "LED_DR_LED0_BLUE")
	)
	(segment
		(start 6.044946 -433.7685)
		(end 7.936992 -433.7685)
		(width 0.1397)
		(layer "F.Cu")
		(net "LED_DR_LED0_BLUE")
	)
	(segment
		(start 6.8072 -431.5968)
		(end 6.8072 -430.7713)
		(width 0.1397)
		(layer "F.Cu")
		(net "LED_DR_LED0_BLUE")
	)
	(segment
		(start 9.017 -440.292998)
		(end 7.949946 -441.360052)
		(width 0.1397)
		(layer "F.Cu")
		(net "LED_DR_LED0_BLUE")
	)
	(segment
		(start 8.369046 -434.200554)
		(end 9.017 -434.848508)
		(width 0.1397)
		(layer "F.Cu")
		(net "LED_DR_LED0_BLUE")
	)
	(segment
		(start 5.947918 -433.671472)
		(end 6.044946 -433.7685)
		(width 0.1397)
		(layer "F.Cu")
		(net "LED_DR_LED0_BLUE")
	)
	(segment
		(start 7.936992 -433.7685)
		(end 8.369046 -434.200554)
		(width 0.1397)
		(layer "F.Cu")
		(net "LED_DR_LED0_BLUE")
	)
	(segment
		(start 5.947918 -433.671472)
		(end 5.947918 -432.456082)
		(width 0.1397)
		(layer "F.Cu")
		(net "LED_DR_LED0_BLUE")
	)
	(segment
		(start 6.8072 -430.7713)
		(end 6.0071 -429.9712)
		(width 0.1397)
		(layer "F.Cu")
		(net "LED_DR_LED0_BLUE")
	)
	(segment
		(start 5.947918 -432.456082)
		(end 6.8072 -431.5968)
		(width 0.1397)
		(layer "F.Cu")
		(net "LED_DR_LED0_BLUE")
	)
	(via
		(at 8.369046 -434.200554)
		(size 0.7112)
		(drill 0.3556)
		(layers "F.Cu" "B.Cu")
		(net "LED_DR_LED0_BLUE")
	)
	(segment
		(start 38.6334 -253.0856)
		(end 39.116 -252.603)
		(width 0.1397)
		(layer "F.Cu")
		(net "LED_DR_LED6_RESERVE")
	)
	(segment
		(start 38.13556 -249.3518)
		(end 38.13556 -251.62256)
		(width 0.1397)
		(layer "F.Cu")
		(net "LED_DR_LED6_RESERVE")
	)
	(segment
		(start 38.13556 -251.62256)
		(end 39.116 -252.603)
		(width 0.1397)
		(layer "F.Cu")
		(net "LED_DR_LED6_RESERVE")
	)
	(segment
		(start 38.6334 -253.9365)
		(end 38.6334 -253.0856)
		(width 0.1397)
		(layer "F.Cu")
		(net "LED_DR_LED6_RESERVE")
	)
	(segment
		(start 35.5346 -249.3518)
		(end 35.5346 -251.2568)
		(width 0.1397)
		(layer "F.Cu")
		(net "I2C_C_SDA_LEDDRV")
	)
	(segment
		(start 34.66465 -253.56185)
		(end 34.29 -253.9365)
		(width 0.1397)
		(layer "F.Cu")
		(net "I2C_C_SDA_LEDDRV")
	)
	(segment
		(start 33.2486 -254.762)
		(end 33.2486 -254.8636)
		(width 0.1397)
		(layer "F.Cu")
		(net "I2C_C_SDA_LEDDRV")
	)
	(segment
		(start 34.0741 -253.9365)
		(end 33.2486 -254.762)
		(width 0.1397)
		(layer "F.Cu")
		(net "I2C_C_SDA_LEDDRV")
	)
	(segment
		(start 34.29 -253.9365)
		(end 34.0741 -253.9365)
		(width 0.1397)
		(layer "F.Cu")
		(net "I2C_C_SDA_LEDDRV")
	)
	(segment
		(start 35.5346 -251.2568)
		(end 34.66465 -252.12675)
		(width 0.1397)
		(layer "F.Cu")
		(net "I2C_C_SDA_LEDDRV")
	)
	(segment
		(start 34.66465 -252.12675)
		(end 34.66465 -253.56185)
		(width 0.1397)
		(layer "F.Cu")
		(net "I2C_C_SDA_LEDDRV")
	)
	(via
		(at 33.2486 -254.8636)
		(size 0.7112)
		(drill 0.3556)
		(layers "F.Cu" "B.Cu")
		(net "I2C_C_SDA_LEDDRV")
	)
	(segment
		(start 42.17924 -179.02936)
		(end 42.5704 -178.6382)
		(width 0.1397)
		(layer "F.Cu")
		(net "D_LATCH_Q")
	)
	(segment
		(start 42.17924 -180.366416)
		(end 42.17924 -179.02936)
		(width 0.1397)
		(layer "F.Cu")
		(net "D_LATCH_Q")
	)
	(segment
		(start 42.5958 -177.7111)
		(end 42.5958 -178.6128)
		(width 0.1397)
		(layer "F.Cu")
		(net "D_LATCH_Q")
	)
	(segment
		(start 43.6245 -178.0794)
		(end 42.9641 -178.0794)
		(width 0.1397)
		(layer "F.Cu")
		(net "D_LATCH_Q")
	)
	(segment
		(start 42.5958 -178.6128)
		(end 42.5704 -178.6382)
		(width 0.1397)
		(layer "F.Cu")
		(net "D_LATCH_Q")
	)
	(segment
		(start 42.9641 -178.0794)
		(end 42.5958 -177.7111)
		(width 0.1397)
		(layer "F.Cu")
		(net "D_LATCH_Q")
	)
	(via
		(at 42.5704 -178.6382)
		(size 0.7112)
		(drill 0.3556)
		(layers "F.Cu" "B.Cu")
		(net "D_LATCH_Q")
	)
	(segment
		(start 36.703 -171.45)
		(end 36.957 -171.45)
		(width 0.1397)
		(layer "F.Cu")
		(net "TEMP_ALM#_IN")
	)
	(segment
		(start 35.97275 -173.2915)
		(end 35.97275 -172.18025)
		(width 0.1397)
		(layer "F.Cu")
		(net "TEMP_ALM#_IN")
	)
	(segment
		(start 37.084 -171.323)
		(end 38.735 -171.323)
		(width 0.1397)
		(layer "F.Cu")
		(net "TEMP_ALM#_IN")
	)
	(segment
		(start 38.862 -173.2915)
		(end 39.243 -173.6725)
		(width 0.1397)
		(layer "F.Cu")
		(net "TEMP_ALM#_IN")
	)
	(segment
		(start 36.957 -171.45)
		(end 37.084 -171.323)
		(width 0.1397)
		(layer "F.Cu")
		(net "TEMP_ALM#_IN")
	)
	(segment
		(start 35.97275 -172.18025)
		(end 36.703 -171.45)
		(width 0.1397)
		(layer "F.Cu")
		(net "TEMP_ALM#_IN")
	)
	(segment
		(start 38.735 -171.323)
		(end 38.862 -171.45)
		(width 0.1397)
		(layer "F.Cu")
		(net "TEMP_ALM#_IN")
	)
	(segment
		(start 38.862 -171.45)
		(end 38.862 -173.2915)
		(width 0.1397)
		(layer "F.Cu")
		(net "TEMP_ALM#_IN")
	)
	(via
		(at 36.957 -171.45)
		(size 0.7112)
		(drill 0.3556)
		(layers "F.Cu" "B.Cu")
		(net "TEMP_ALM#_IN")
	)
	(segment
		(start 39.243 -178.816)
		(end 39.243 -178.4985)
		(width 0.1397)
		(layer "F.Cu")
		(net "TEMP_ALM#_IN_D")
	)
	(segment
		(start 40.87876 -179.43576)
		(end 40.87876 -180.366416)
		(width 0.1397)
		(layer "F.Cu")
		(net "TEMP_ALM#_IN_D")
	)
	(segment
		(start 37.4269 -175.1965)
		(end 36.957 -175.1965)
		(width 0.1397)
		(layer "F.Cu")
		(net "TEMP_ALM#_IN_D")
	)
	(segment
		(start 37.720016 -175.489616)
		(end 37.4269 -175.1965)
		(width 0.1397)
		(layer "F.Cu")
		(net "TEMP_ALM#_IN_D")
	)
	(segment
		(start 39.9415 -179.197)
		(end 40.64 -179.197)
		(width 0.1397)
		(layer "F.Cu")
		(net "TEMP_ALM#_IN_D")
	)
	(segment
		(start 38.075616 -175.489616)
		(end 37.720016 -175.489616)
		(width 0.1397)
		(layer "F.Cu")
		(net "TEMP_ALM#_IN_D")
	)
	(segment
		(start 36.6395 -176.657)
		(end 36.6395 -175.514)
		(width 0.1397)
		(layer "F.Cu")
		(net "TEMP_ALM#_IN_D")
	)
	(segment
		(start 39.243 -178.4985)
		(end 39.9415 -179.197)
		(width 0.1397)
		(layer "F.Cu")
		(net "TEMP_ALM#_IN_D")
	)
	(segment
		(start 38.2778 -175.6918)
		(end 38.075616 -175.489616)
		(width 0.1397)
		(layer "F.Cu")
		(net "TEMP_ALM#_IN_D")
	)
	(segment
		(start 38.910768 -179.29606)
		(end 38.910768 -179.148232)
		(width 0.1397)
		(layer "F.Cu")
		(net "TEMP_ALM#_IN_D")
	)
	(segment
		(start 38.910768 -179.148232)
		(end 39.243 -178.816)
		(width 0.1397)
		(layer "F.Cu")
		(net "TEMP_ALM#_IN_D")
	)
	(segment
		(start 40.64 -179.197)
		(end 40.87876 -179.43576)
		(width 0.1397)
		(layer "F.Cu")
		(net "TEMP_ALM#_IN_D")
	)
	(segment
		(start 36.6395 -175.514)
		(end 36.957 -175.1965)
		(width 0.1397)
		(layer "F.Cu")
		(net "TEMP_ALM#_IN_D")
	)
	(via
		(at 38.608 -176.704752)
		(size 0.7112)
		(drill 0.3556)
		(layers "F.Cu" "B.Cu")
		(net "TEMP_ALM#_IN_D")
	)
	(via
		(at 38.2778 -175.6918)
		(size 0.5588)
		(drill 0.3048)
		(layers "F.Cu" "B.Cu")
		(net "TEMP_ALM#_IN_D")
	)
	(via
		(at 38.910768 -179.29606)
		(size 0.5588)
		(drill 0.3048)
		(layers "F.Cu" "B.Cu")
		(net "TEMP_ALM#_IN_D")
	)
	(segment
		(start 38.910768 -177.00752)
		(end 38.608 -176.704752)
		(width 0.1397)
		(layer "B.Cu")
		(net "TEMP_ALM#_IN_D")
	)
	(segment
		(start 38.910768 -179.29606)
		(end 38.910768 -177.00752)
		(width 0.1397)
		(layer "B.Cu")
		(net "TEMP_ALM#_IN_D")
	)
	(segment
		(start 38.2778 -175.6918)
		(end 38.2778 -176.3268)
		(width 0.1397)
		(layer "B.Cu")
		(net "TEMP_ALM#_IN_D")
	)
	(segment
		(start 38.608 -176.657)
		(end 38.608 -176.704752)
		(width 0.1397)
		(layer "B.Cu")
		(net "TEMP_ALM#_IN_D")
	)
	(segment
		(start 38.2778 -176.3268)
		(end 38.608 -176.657)
		(width 0.1397)
		(layer "B.Cu")
		(net "TEMP_ALM#_IN_D")
	)
	(segment
		(start 26.289 -244.856)
		(end 24.638 -243.205)
		(width 0.254)
		(layer "F.Cu")
		(net "P3V3_LX_COPPER")
	)
	(segment
		(start 24.638 -243.205)
		(end 24.003 -243.205)
		(width 0.254)
		(layer "F.Cu")
		(net "P3V3_LX_COPPER")
	)
	(segment
		(start 24.003 -243.205)
		(end 23.876 -243.078)
		(width 0.254)
		(layer "F.Cu")
		(net "P3V3_LX_COPPER")
	)
	(segment
		(start 26.289 -245.491)
		(end 26.289 -244.856)
		(width 0.254)
		(layer "F.Cu")
		(net "P3V3_LX_COPPER")
	)
	(segment
		(start 26.289 -247.396)
		(end 26.289 -245.491)
		(width 0.254)
		(layer "F.Cu")
		(net "P3V3_LX_COPPER")
	)
	(via
		(at 24.003 -241.427)
		(size 0.7112)
		(drill 0.3556)
		(layers "F.Cu" "B.Cu")
		(net "P3V3_LX_COPPER")
	)
	(via
		(at 26.289 -245.491)
		(size 0.7112)
		(drill 0.3556)
		(layers "F.Cu" "B.Cu")
		(net "P3V3_LX_COPPER")
	)
	(segment
		(start 17.9832 -247.8024)
		(end 16.2052 -247.8024)
		(width 0.508)
		(layer "F.Cu")
		(net "P3V3_IN")
	)
	(segment
		(start 14.4145 -247.4214)
		(end 13.081 -247.4214)
		(width 1.016)
		(layer "F.Cu")
		(net "P3V3_IN")
	)
	(segment
		(start 14.5034 -247.5103)
		(end 14.4145 -247.4214)
		(width 1.016)
		(layer "F.Cu")
		(net "P3V3_IN")
	)
	(segment
		(start 18.161 -247.9802)
		(end 19.6596 -247.9802)
		(width 0.508)
		(layer "F.Cu")
		(net "P3V3_IN")
	)
	(segment
		(start 17.9832 -247.8024)
		(end 18.161 -247.9802)
		(width 0.508)
		(layer "F.Cu")
		(net "P3V3_IN")
	)
	(via
		(at 13.081 -247.4214)
		(size 0.7112)
		(drill 0.3556)
		(layers "F.Cu" "B.Cu")
		(net "P3V3_IN")
	)
	(segment
		(start 43.97629 -413.135318)
		(end 44.01058 -413.135318)
		(width 0.254)
		(layer "F.Cu")
		(net "SENSE-_R4")
	)
	(segment
		(start 43.942 -413.101028)
		(end 43.97629 -413.135318)
		(width 0.254)
		(layer "F.Cu")
		(net "SENSE-_R4")
	)
	(segment
		(start 34.60877 -383.09423)
		(end 34.798 -382.905)
		(width 0.254)
		(layer "F.Cu")
		(net "SENSE-_R4")
	)
	(segment
		(start 41.974008 -409.777438)
		(end 41.974008 -409.968446)
		(width 0.254)
		(layer "F.Cu")
		(net "SENSE-_R4")
	)
	(segment
		(start 41.974008 -409.968446)
		(end 43.942 -411.936438)
		(width 0.254)
		(layer "F.Cu")
		(net "SENSE-_R4")
	)
	(segment
		(start 34.798 -382.905)
		(end 34.798 -381.4445)
		(width 0.254)
		(layer "F.Cu")
		(net "SENSE-_R4")
	)
	(segment
		(start 34.292032 -383.09423)
		(end 34.60877 -383.09423)
		(width 0.254)
		(layer "F.Cu")
		(net "SENSE-_R4")
	)
	(segment
		(start 43.942 -411.936438)
		(end 43.942 -413.101028)
		(width 0.254)
		(layer "F.Cu")
		(net "SENSE-_R4")
	)
	(via
		(at 34.292032 -383.09423)
		(size 0.5588)
		(drill 0.3048)
		(layers "F.Cu" "B.Cu")
		(net "SENSE-_R4")
	)
	(via
		(at 44.01058 -413.135318)
		(size 0.5588)
		(drill 0.3048)
		(layers "F.Cu" "B.Cu")
		(net "SENSE-_R4")
	)
	(via
		(at 35.179 -382.143)
		(size 0.7112)
		(drill 0.3556)
		(layers "F.Cu" "B.Cu")
		(net "SENSE-_R4")
	)
	(segment
		(start 35.179 -382.143)
		(end 34.292032 -383.029968)
		(width 0.254)
		(layer "B.Cu")
		(net "SENSE-_R4")
	)
	(segment
		(start 34.292032 -383.029968)
		(end 34.292032 -383.09423)
		(width 0.254)
		(layer "B.Cu")
		(net "SENSE-_R4")
	)
	(segment
		(start 23.218648 -410.1592)
		(end 29.280358 -410.1592)
		(width 0.254)
		(layer "B.Cu")
		(net "SENSE-_R4")
	)
	(segment
		(start 30.397958 -411.2768)
		(end 36.195 -411.2768)
		(width 0.254)
		(layer "B.Cu")
		(net "SENSE-_R4")
	)
	(segment
		(start 22.86 -393.7)
		(end 22.86 -409.800552)
		(width 0.254)
		(layer "B.Cu")
		(net "SENSE-_R4")
	)
	(segment
		(start 29.280358 -410.1592)
		(end 30.397958 -411.2768)
		(width 0.254)
		(layer "B.Cu")
		(net "SENSE-_R4")
	)
	(segment
		(start 22.86 -409.800552)
		(end 23.218648 -410.1592)
		(width 0.254)
		(layer "B.Cu")
		(net "SENSE-_R4")
	)
	(segment
		(start 32.500062 -384.8862)
		(end 31.6738 -384.8862)
		(width 0.254)
		(layer "B.Cu")
		(net "SENSE-_R4")
	)
	(segment
		(start 36.195 -411.2768)
		(end 37.4142 -412.496)
		(width 0.254)
		(layer "B.Cu")
		(net "SENSE-_R4")
	)
	(segment
		(start 31.6738 -384.8862)
		(end 22.86 -393.7)
		(width 0.254)
		(layer "B.Cu")
		(net "SENSE-_R4")
	)
	(segment
		(start 43.371262 -412.496)
		(end 44.01058 -413.135318)
		(width 0.254)
		(layer "B.Cu")
		(net "SENSE-_R4")
	)
	(segment
		(start 37.4142 -412.496)
		(end 43.371262 -412.496)
		(width 0.254)
		(layer "B.Cu")
		(net "SENSE-_R4")
	)
	(segment
		(start 34.292032 -383.09423)
		(end 32.500062 -384.8862)
		(width 0.254)
		(layer "B.Cu")
		(net "SENSE-_R4")
	)
	(segment
		(start 20.701 -410.464)
		(end 21.0947 -410.464)
		(width 0.254)
		(layer "F.Cu")
		(net "SENSE-_R1")
	)
	(segment
		(start 31.75 -381.4445)
		(end 31.75 -382.651)
		(width 0.254)
		(layer "F.Cu")
		(net "SENSE-_R1")
	)
	(segment
		(start 20.014438 -409.777438)
		(end 20.701 -410.464)
		(width 0.254)
		(layer "F.Cu")
		(net "SENSE-_R1")
	)
	(segment
		(start 20.003008 -409.777438)
		(end 20.014438 -409.777438)
		(width 0.254)
		(layer "F.Cu")
		(net "SENSE-_R1")
	)
	(via
		(at 31.75 -382.651)
		(size 0.5588)
		(drill 0.3048)
		(layers "F.Cu" "B.Cu")
		(net "SENSE-_R1")
	)
	(via
		(at 21.0947 -410.464)
		(size 0.5588)
		(drill 0.3048)
		(layers "F.Cu" "B.Cu")
		(net "SENSE-_R1")
	)
	(via
		(at 31.75 -381.127)
		(size 0.7112)
		(drill 0.3556)
		(layers "F.Cu" "B.Cu")
		(net "SENSE-_R1")
	)
	(segment
		(start 21.0947 -392.966956)
		(end 30.851856 -383.2098)
		(width 0.254)
		(layer "B.Cu")
		(net "SENSE-_R1")
	)
	(segment
		(start 21.0947 -410.464)
		(end 21.0947 -392.966956)
		(width 0.254)
		(layer "B.Cu")
		(net "SENSE-_R1")
	)
	(segment
		(start 31.75 -382.651)
		(end 31.75 -381.127)
		(width 0.254)
		(layer "B.Cu")
		(net "SENSE-_R1")
	)
	(segment
		(start 30.851856 -383.2098)
		(end 31.1912 -383.2098)
		(width 0.254)
		(layer "B.Cu")
		(net "SENSE-_R1")
	)
	(segment
		(start 31.1912 -383.2098)
		(end 31.75 -382.651)
		(width 0.254)
		(layer "B.Cu")
		(net "SENSE-_R1")
	)
	(segment
		(start 28.7528 -410.9212)
		(end 28.7528 -411.3022)
		(width 0.254)
		(layer "F.Cu")
		(net "SENSE-_R2")
	)
	(segment
		(start 27.750008 -409.777438)
		(end 27.750008 -409.918408)
		(width 0.254)
		(layer "F.Cu")
		(net "SENSE-_R2")
	)
	(segment
		(start 32.766 -381.4445)
		(end 32.766 -382.650492)
		(width 0.254)
		(layer "F.Cu")
		(net "SENSE-_R2")
	)
	(segment
		(start 27.750008 -409.918408)
		(end 28.7528 -410.9212)
		(width 0.254)
		(layer "F.Cu")
		(net "SENSE-_R2")
	)
	(segment
		(start 32.766 -382.650492)
		(end 32.765746 -382.650746)
		(width 0.254)
		(layer "F.Cu")
		(net "SENSE-_R2")
	)
	(via
		(at 32.765746 -382.650746)
		(size 0.5588)
		(drill 0.3048)
		(layers "F.Cu" "B.Cu")
		(net "SENSE-_R2")
	)
	(via
		(at 33.02 -381.254)
		(size 0.7112)
		(drill 0.3556)
		(layers "F.Cu" "B.Cu")
		(net "SENSE-_R2")
	)
	(via
		(at 28.7528 -411.3022)
		(size 0.5588)
		(drill 0.3048)
		(layers "F.Cu" "B.Cu")
		(net "SENSE-_R2")
	)
	(segment
		(start 32.765746 -381.762254)
		(end 32.765746 -382.650746)
		(width 0.254)
		(layer "B.Cu")
		(net "SENSE-_R2")
	)
	(segment
		(start 22.733 -411.353)
		(end 21.653754 -410.273754)
		(width 0.254)
		(layer "B.Cu")
		(net "SENSE-_R2")
	)
	(segment
		(start 28.7528 -411.3022)
		(end 28.702 -411.353)
		(width 0.254)
		(layer "B.Cu")
		(net "SENSE-_R2")
	)
	(segment
		(start 31.647892 -383.7686)
		(end 32.765746 -382.650746)
		(width 0.254)
		(layer "B.Cu")
		(net "SENSE-_R2")
	)
	(segment
		(start 28.702 -411.353)
		(end 22.733 -411.353)
		(width 0.254)
		(layer "B.Cu")
		(net "SENSE-_R2")
	)
	(segment
		(start 21.653754 -410.273754)
		(end 21.653754 -393.19835)
		(width 0.254)
		(layer "B.Cu")
		(net "SENSE-_R2")
	)
	(segment
		(start 21.653754 -393.19835)
		(end 31.083504 -383.7686)
		(width 0.254)
		(layer "B.Cu")
		(net "SENSE-_R2")
	)
	(segment
		(start 31.083504 -383.7686)
		(end 31.647892 -383.7686)
		(width 0.254)
		(layer "B.Cu")
		(net "SENSE-_R2")
	)
	(segment
		(start 33.02 -381.508)
		(end 32.765746 -381.762254)
		(width 0.254)
		(layer "B.Cu")
		(net "SENSE-_R2")
	)
	(segment
		(start 33.02 -381.254)
		(end 33.02 -381.508)
		(width 0.254)
		(layer "B.Cu")
		(net "SENSE-_R2")
	)
	(segment
		(start 33.782 -381.4445)
		(end 33.782 -382.397)
		(width 0.254)
		(layer "F.Cu")
		(net "SENSE-_R3")
	)
	(segment
		(start 35.8902 -411.8356)
		(end 35.941 -411.8864)
		(width 0.254)
		(layer "F.Cu")
		(net "SENSE-_R3")
	)
	(segment
		(start 34.989008 -409.893008)
		(end 35.8902 -410.7942)
		(width 0.254)
		(layer "F.Cu")
		(net "SENSE-_R3")
	)
	(segment
		(start 34.989008 -409.777438)
		(end 34.989008 -409.893008)
		(width 0.254)
		(layer "F.Cu")
		(net "SENSE-_R3")
	)
	(segment
		(start 35.8902 -410.7942)
		(end 35.8902 -411.8356)
		(width 0.254)
		(layer "F.Cu")
		(net "SENSE-_R3")
	)
	(via
		(at 33.782 -382.397)
		(size 0.5588)
		(drill 0.3048)
		(layers "F.Cu" "B.Cu")
		(net "SENSE-_R3")
	)
	(via
		(at 34.29 -381.127)
		(size 0.7112)
		(drill 0.3556)
		(layers "F.Cu" "B.Cu")
		(net "SENSE-_R3")
	)
	(via
		(at 35.941 -411.8864)
		(size 0.5588)
		(drill 0.3048)
		(layers "F.Cu" "B.Cu")
		(net "SENSE-_R3")
	)
	(segment
		(start 30.1752 -411.8864)
		(end 29.0068 -410.718)
		(width 0.254)
		(layer "B.Cu")
		(net "SENSE-_R3")
	)
	(segment
		(start 33.782 -382.524)
		(end 33.782 -382.397)
		(width 0.254)
		(layer "B.Cu")
		(net "SENSE-_R3")
	)
	(segment
		(start 35.941 -411.8864)
		(end 30.1752 -411.8864)
		(width 0.254)
		(layer "B.Cu")
		(net "SENSE-_R3")
	)
	(segment
		(start 22.212554 -409.943554)
		(end 22.212554 -393.429998)
		(width 0.254)
		(layer "B.Cu")
		(net "SENSE-_R3")
	)
	(segment
		(start 34.29 -381.127)
		(end 34.29 -381.635)
		(width 0.254)
		(layer "B.Cu")
		(net "SENSE-_R3")
	)
	(segment
		(start 34.29 -381.635)
		(end 33.782 -382.143)
		(width 0.254)
		(layer "B.Cu")
		(net "SENSE-_R3")
	)
	(segment
		(start 31.9786 -384.3274)
		(end 33.782 -382.524)
		(width 0.254)
		(layer "B.Cu")
		(net "SENSE-_R3")
	)
	(segment
		(start 22.212554 -393.429998)
		(end 31.315152 -384.3274)
		(width 0.254)
		(layer "B.Cu")
		(net "SENSE-_R3")
	)
	(segment
		(start 29.0068 -410.718)
		(end 22.987 -410.718)
		(width 0.254)
		(layer "B.Cu")
		(net "SENSE-_R3")
	)
	(segment
		(start 31.315152 -384.3274)
		(end 31.9786 -384.3274)
		(width 0.254)
		(layer "B.Cu")
		(net "SENSE-_R3")
	)
	(segment
		(start 22.987 -410.718)
		(end 22.212554 -409.943554)
		(width 0.254)
		(layer "B.Cu")
		(net "SENSE-_R3")
	)
	(segment
		(start 33.782 -382.143)
		(end 33.782 -382.397)
		(width 0.254)
		(layer "B.Cu")
		(net "SENSE-_R3")
	)
	(segment
		(start 43.148504 -412.210504)
		(end 43.148504 -413.080962)
		(width 0.254)
		(layer "F.Cu")
		(net "SENSE+_R4")
	)
	(segment
		(start 27.686 -381.4445)
		(end 27.686 -382.651)
		(width 0.254)
		(layer "F.Cu")
		(net "SENSE+_R4")
	)
	(segment
		(start 41.974008 -411.404562)
		(end 42.342562 -411.404562)
		(width 0.254)
		(layer "F.Cu")
		(net "SENSE+_R4")
	)
	(segment
		(start 42.342562 -411.404562)
		(end 43.148504 -412.210504)
		(width 0.254)
		(layer "F.Cu")
		(net "SENSE+_R4")
	)
	(via
		(at 27.686 -382.651)
		(size 0.5588)
		(drill 0.3048)
		(layers "F.Cu" "B.Cu")
		(net "SENSE+_R4")
	)
	(via
		(at 26.543 -382.524)
		(size 0.7112)
		(drill 0.3556)
		(layers "F.Cu" "B.Cu")
		(net "SENSE+_R4")
	)
	(via
		(at 43.148504 -413.080962)
		(size 0.5588)
		(drill 0.3048)
		(layers "F.Cu" "B.Cu")
		(net "SENSE+_R4")
	)
	(segment
		(start 18.8214 -392.0236)
		(end 27.686 -383.159)
		(width 0.254)
		(layer "B.Cu")
		(net "SENSE+_R4")
	)
	(segment
		(start 18.8214 -409.926536)
		(end 18.821146 -409.926282)
		(width 0.254)
		(layer "B.Cu")
		(net "SENSE+_R4")
	)
	(segment
		(start 18.8214 -411.515306)
		(end 18.8214 -409.926536)
		(width 0.254)
		(layer "B.Cu")
		(net "SENSE+_R4")
	)
	(segment
		(start 43.148504 -413.080962)
		(end 42.844466 -413.385)
		(width 0.254)
		(layer "B.Cu")
		(net "SENSE+_R4")
	)
	(segment
		(start 42.844466 -413.385)
		(end 20.691094 -413.385)
		(width 0.254)
		(layer "B.Cu")
		(net "SENSE+_R4")
	)
	(segment
		(start 20.691094 -413.385)
		(end 18.8214 -411.515306)
		(width 0.254)
		(layer "B.Cu")
		(net "SENSE+_R4")
	)
	(segment
		(start 27.686 -383.159)
		(end 27.686 -382.651)
		(width 0.254)
		(layer "B.Cu")
		(net "SENSE+_R4")
	)
	(segment
		(start 27.686 -382.651)
		(end 27.559 -382.524)
		(width 0.254)
		(layer "B.Cu")
		(net "SENSE+_R4")
	)
	(segment
		(start 18.8214 -406.683464)
		(end 18.8214 -392.0236)
		(width 0.254)
		(layer "B.Cu")
		(net "SENSE+_R4")
	)
	(segment
		(start 18.821146 -409.926282)
		(end 18.821146 -406.683718)
		(width 0.254)
		(layer "B.Cu")
		(net "SENSE+_R4")
	)
	(segment
		(start 18.821146 -406.683718)
		(end 18.8214 -406.683464)
		(width 0.254)
		(layer "B.Cu")
		(net "SENSE+_R4")
	)
	(segment
		(start 27.559 -382.524)
		(end 26.543 -382.524)
		(width 0.254)
		(layer "B.Cu")
		(net "SENSE+_R4")
	)
	(segment
		(start 29.718 -381.4445)
		(end 29.718 -382.651)
		(width 0.254)
		(layer "F.Cu")
		(net "SENSE+_R2")
	)
	(segment
		(start 27.750008 -411.544008)
		(end 28.3972 -412.1912)
		(width 0.254)
		(layer "F.Cu")
		(net "SENSE+_R2")
	)
	(segment
		(start 28.3972 -412.1912)
		(end 28.7528 -412.1912)
		(width 0.254)
		(layer "F.Cu")
		(net "SENSE+_R2")
	)
	(segment
		(start 27.750008 -411.404562)
		(end 27.750008 -411.544008)
		(width 0.254)
		(layer "F.Cu")
		(net "SENSE+_R2")
	)
	(via
		(at 29.718 -382.651)
		(size 0.5588)
		(drill 0.3048)
		(layers "F.Cu" "B.Cu")
		(net "SENSE+_R2")
	)
	(via
		(at 28.7528 -412.1912)
		(size 0.5588)
		(drill 0.3048)
		(layers "F.Cu" "B.Cu")
		(net "SENSE+_R2")
	)
	(via
		(at 29.083 -381.4572)
		(size 0.7112)
		(drill 0.3556)
		(layers "F.Cu" "B.Cu")
		(net "SENSE+_R2")
	)
	(segment
		(start 29.718 -382.707896)
		(end 29.718 -382.651)
		(width 0.254)
		(layer "B.Cu")
		(net "SENSE+_R2")
	)
	(segment
		(start 19.939 -411.05201)
		(end 19.939 -409.46324)
		(width 0.254)
		(layer "B.Cu")
		(net "SENSE+_R2")
	)
	(segment
		(start 29.718 -382.0922)
		(end 29.083 -381.4572)
		(width 0.254)
		(layer "B.Cu")
		(net "SENSE+_R2")
	)
	(segment
		(start 28.7528 -412.1912)
		(end 21.082 -412.1912)
		(width 0.254)
		(layer "B.Cu")
		(net "SENSE+_R2")
	)
	(segment
		(start 19.939 -392.486896)
		(end 29.718 -382.707896)
		(width 0.254)
		(layer "B.Cu")
		(net "SENSE+_R2")
	)
	(segment
		(start 19.938746 -409.462986)
		(end 19.938746 -407.147014)
		(width 0.254)
		(layer "B.Cu")
		(net "SENSE+_R2")
	)
	(segment
		(start 19.939 -409.46324)
		(end 19.938746 -409.462986)
		(width 0.254)
		(layer "B.Cu")
		(net "SENSE+_R2")
	)
	(segment
		(start 21.082 -412.1912)
		(end 20.854416 -411.963616)
		(width 0.254)
		(layer "B.Cu")
		(net "SENSE+_R2")
	)
	(segment
		(start 29.718 -382.651)
		(end 29.718 -382.0922)
		(width 0.254)
		(layer "B.Cu")
		(net "SENSE+_R2")
	)
	(segment
		(start 19.938746 -407.147014)
		(end 19.939 -407.14676)
		(width 0.254)
		(layer "B.Cu")
		(net "SENSE+_R2")
	)
	(segment
		(start 20.854416 -411.963616)
		(end 20.850606 -411.963616)
		(width 0.254)
		(layer "B.Cu")
		(net "SENSE+_R2")
	)
	(segment
		(start 19.939 -407.14676)
		(end 19.939 -392.486896)
		(width 0.254)
		(layer "B.Cu")
		(net "SENSE+_R2")
	)
	(segment
		(start 20.850606 -411.963616)
		(end 19.939 -411.05201)
		(width 0.254)
		(layer "B.Cu")
		(net "SENSE+_R2")
	)
	(segment
		(start 35.8394 -412.75)
		(end 35.8902 -412.75)
		(width 0.254)
		(layer "F.Cu")
		(net "SENSE+_R3")
	)
	(segment
		(start 28.702 -381.4445)
		(end 28.702 -382.651)
		(width 0.254)
		(layer "F.Cu")
		(net "SENSE+_R3")
	)
	(segment
		(start 34.989008 -411.404562)
		(end 34.989008 -411.899608)
		(width 0.254)
		(layer "F.Cu")
		(net "SENSE+_R3")
	)
	(segment
		(start 34.989008 -411.899608)
		(end 35.8394 -412.75)
		(width 0.254)
		(layer "F.Cu")
		(net "SENSE+_R3")
	)
	(via
		(at 28.702 -382.651)
		(size 0.5588)
		(drill 0.3048)
		(layers "F.Cu" "B.Cu")
		(net "SENSE+_R3")
	)
	(via
		(at 27.559 -381.381)
		(size 0.7112)
		(drill 0.3556)
		(layers "F.Cu" "B.Cu")
		(net "SENSE+_R3")
	)
	(via
		(at 35.8902 -412.75)
		(size 0.5588)
		(drill 0.3048)
		(layers "F.Cu" "B.Cu")
		(net "SENSE+_R3")
	)
	(segment
		(start 20.846542 -412.75)
		(end 19.3802 -411.283658)
		(width 0.254)
		(layer "B.Cu")
		(net "SENSE+_R3")
	)
	(segment
		(start 28.702 -382.524)
		(end 28.702 -382.651)
		(width 0.254)
		(layer "B.Cu")
		(net "SENSE+_R3")
	)
	(segment
		(start 19.3802 -411.283658)
		(end 19.3802 -409.694888)
		(width 0.254)
		(layer "B.Cu")
		(net "SENSE+_R3")
	)
	(segment
		(start 28.702 -382.933448)
		(end 28.702 -382.651)
		(width 0.254)
		(layer "B.Cu")
		(net "SENSE+_R3")
	)
	(segment
		(start 19.3802 -409.694888)
		(end 19.379946 -409.694634)
		(width 0.254)
		(layer "B.Cu")
		(net "SENSE+_R3")
	)
	(segment
		(start 19.379946 -409.694634)
		(end 19.379946 -406.915366)
		(width 0.254)
		(layer "B.Cu")
		(net "SENSE+_R3")
	)
	(segment
		(start 19.3802 -392.255248)
		(end 28.702 -382.933448)
		(width 0.254)
		(layer "B.Cu")
		(net "SENSE+_R3")
	)
	(segment
		(start 19.3802 -406.915112)
		(end 19.3802 -392.255248)
		(width 0.254)
		(layer "B.Cu")
		(net "SENSE+_R3")
	)
	(segment
		(start 27.559 -381.381)
		(end 28.702 -382.524)
		(width 0.254)
		(layer "B.Cu")
		(net "SENSE+_R3")
	)
	(segment
		(start 35.8902 -412.75)
		(end 20.846542 -412.75)
		(width 0.254)
		(layer "B.Cu")
		(net "SENSE+_R3")
	)
	(segment
		(start 19.379946 -406.915366)
		(end 19.3802 -406.915112)
		(width 0.254)
		(layer "B.Cu")
		(net "SENSE+_R3")
	)
	(segment
		(start 30.734 -381.4445)
		(end 30.734 -382.651)
		(width 0.254)
		(layer "F.Cu")
		(net "SENSE+_R1")
	)
	(segment
		(start 20.003008 -411.404562)
		(end 21.082 -411.404562)
		(width 0.254)
		(layer "F.Cu")
		(net "SENSE+_R1")
	)
	(via
		(at 30.734 -382.651)
		(size 0.5588)
		(drill 0.3048)
		(layers "F.Cu" "B.Cu")
		(net "SENSE+_R1")
	)
	(via
		(at 30.353 -381.254)
		(size 0.7112)
		(drill 0.3556)
		(layers "F.Cu" "B.Cu")
		(net "SENSE+_R1")
	)
	(via
		(at 21.082 -411.404562)
		(size 0.5588)
		(drill 0.3048)
		(layers "F.Cu" "B.Cu")
		(net "SENSE+_R1")
	)
	(segment
		(start 30.607 -382.651)
		(end 30.734 -382.651)
		(width 0.254)
		(layer "B.Cu")
		(net "SENSE+_R1")
	)
	(segment
		(start 30.353 -381.508)
		(end 30.353 -381.254)
		(width 0.254)
		(layer "B.Cu")
		(net "SENSE+_R1")
	)
	(segment
		(start 20.4978 -392.7602)
		(end 30.607 -382.651)
		(width 0.254)
		(layer "B.Cu")
		(net "SENSE+_R1")
	)
	(segment
		(start 30.734 -381.889)
		(end 30.353 -381.508)
		(width 0.254)
		(layer "B.Cu")
		(net "SENSE+_R1")
	)
	(segment
		(start 20.4978 -410.820362)
		(end 20.4978 -392.7602)
		(width 0.254)
		(layer "B.Cu")
		(net "SENSE+_R1")
	)
	(segment
		(start 21.082 -411.404562)
		(end 20.4978 -410.820362)
		(width 0.254)
		(layer "B.Cu")
		(net "SENSE+_R1")
	)
	(segment
		(start 30.734 -382.651)
		(end 30.734 -381.889)
		(width 0.254)
		(layer "B.Cu")
		(net "SENSE+_R1")
	)
	(segment
		(start 25.146 -247.9675)
		(end 25.146 -245.872)
		(width 0.254)
		(layer "F.Cu")
		(net "P3V3_LX_REV")
	)
	(segment
		(start 25.146 -245.872)
		(end 24.881332 -245.607332)
		(width 0.254)
		(layer "F.Cu")
		(net "P3V3_LX_REV")
	)
	(segment
		(start 24.881332 -245.607332)
		(end 23.876 -244.602)
		(width 0.254)
		(layer "F.Cu")
		(net "P3V3_LX_REV")
	)
	(via
		(at 24.881332 -245.607332)
		(size 0.7112)
		(drill 0.3556)
		(layers "F.Cu" "B.Cu")
		(net "P3V3_LX_REV")
	)
	(segment
		(start 40.546782 -176.78781)
		(end 40.767 -177.008028)
		(width 0.1397)
		(layer "F.Cu")
		(net "D_LATCH_PRE#")
	)
	(segment
		(start 41.4782 -178.2572)
		(end 41.4782 -178.3842)
		(width 0.1397)
		(layer "F.Cu")
		(net "D_LATCH_PRE#")
	)
	(segment
		(start 40.259 -176.53)
		(end 40.51681 -176.78781)
		(width 0.1397)
		(layer "F.Cu")
		(net "D_LATCH_PRE#")
	)
	(segment
		(start 40.51681 -176.78781)
		(end 40.546782 -176.78781)
		(width 0.1397)
		(layer "F.Cu")
		(net "D_LATCH_PRE#")
	)
	(segment
		(start 41.3639 -178.4985)
		(end 41.4782 -178.3842)
		(width 0.1397)
		(layer "F.Cu")
		(net "D_LATCH_PRE#")
	)
	(segment
		(start 14.4399 -48.5902)
		(end 14.3764 -48.6537)
		(width 0.1397)
		(layer "F.Cu")
		(net "D_LATCH_PRE#")
	)
	(segment
		(start 41.529 -178.435)
		(end 41.4782 -178.3842)
		(width 0.1397)
		(layer "F.Cu")
		(net "D_LATCH_PRE#")
	)
	(segment
		(start 41.529 -180.366416)
		(end 41.529 -178.435)
		(width 0.1397)
		(layer "F.Cu")
		(net "D_LATCH_PRE#")
	)
	(segment
		(start 40.259 -176.4538)
		(end 40.259 -176.53)
		(width 0.1397)
		(layer "F.Cu")
		(net "D_LATCH_PRE#")
	)
	(segment
		(start 41.021 -175.6918)
		(end 40.259 -176.4538)
		(width 0.1397)
		(layer "F.Cu")
		(net "D_LATCH_PRE#")
	)
	(segment
		(start 40.767 -177.546)
		(end 41.4782 -178.2572)
		(width 0.1397)
		(layer "F.Cu")
		(net "D_LATCH_PRE#")
	)
	(segment
		(start 14.4399 -47.5742)
		(end 14.4399 -48.5902)
		(width 0.1397)
		(layer "F.Cu")
		(net "D_LATCH_PRE#")
	)
	(segment
		(start 13.6271 -48.6537)
		(end 13.5636 -48.5902)
		(width 0.1397)
		(layer "F.Cu")
		(net "D_LATCH_PRE#")
	)
	(segment
		(start 40.259 -178.4985)
		(end 41.3639 -178.4985)
		(width 0.1397)
		(layer "F.Cu")
		(net "D_LATCH_PRE#")
	)
	(segment
		(start 40.767 -177.008028)
		(end 40.767 -177.546)
		(width 0.1397)
		(layer "F.Cu")
		(net "D_LATCH_PRE#")
	)
	(segment
		(start 14.3764 -48.6537)
		(end 13.6271 -48.6537)
		(width 0.1397)
		(layer "F.Cu")
		(net "D_LATCH_PRE#")
	)
	(via
		(at 40.259 -176.53)
		(size 0.7112)
		(drill 0.3556)
		(layers "F.Cu" "B.Cu")
		(net "D_LATCH_PRE#")
	)
	(via
		(at 13.5636 -48.5902)
		(size 0.5588)
		(drill 0.3048)
		(layers "F.Cu" "B.Cu")
		(net "D_LATCH_PRE#")
	)
	(via
		(at 41.021 -175.6918)
		(size 0.5588)
		(drill 0.3048)
		(layers "F.Cu" "B.Cu")
		(net "D_LATCH_PRE#")
	)
	(segment
		(start 41.18102 -58.3438)
		(end 41.6052 -58.76798)
		(width 0.1397)
		(layer "B.Cu")
		(net "D_LATCH_PRE#")
	)
	(segment
		(start 21.085556 -47.374556)
		(end 21.530056 -47.819056)
		(width 0.1397)
		(layer "B.Cu")
		(net "D_LATCH_PRE#")
	)
	(segment
		(start 13.5636 -48.5902)
		(end 13.76045 -48.78705)
		(width 0.1397)
		(layer "B.Cu")
		(net "D_LATCH_PRE#")
	)
	(segment
		(start 29.023056 -47.819056)
		(end 36.3982 -55.1942)
		(width 0.1397)
		(layer "B.Cu")
		(net "D_LATCH_PRE#")
	)
	(segment
		(start 19.910044 -47.374556)
		(end 21.085556 -47.374556)
		(width 0.1397)
		(layer "B.Cu")
		(net "D_LATCH_PRE#")
	)
	(segment
		(start 36.3982 -55.1942)
		(end 36.3982 -57.3278)
		(width 0.1397)
		(layer "B.Cu")
		(net "D_LATCH_PRE#")
	)
	(segment
		(start 37.4142 -58.3438)
		(end 41.18102 -58.3438)
		(width 0.1397)
		(layer "B.Cu")
		(net "D_LATCH_PRE#")
	)
	(segment
		(start 41.6052 -65.3288)
		(end 42.901616 -66.625216)
		(width 0.1397)
		(layer "B.Cu")
		(net "D_LATCH_PRE#")
	)
	(segment
		(start 42.926 -138.2522)
		(end 42.925746 -138.2522)
		(width 0.1397)
		(layer "B.Cu")
		(net "D_LATCH_PRE#")
	)
	(segment
		(start 43.1292 -173.355)
		(end 41.021 -175.4632)
		(width 0.1397)
		(layer "B.Cu")
		(net "D_LATCH_PRE#")
	)
	(segment
		(start 37.973 -143.204946)
		(end 37.973 -149.0472)
		(width 0.1397)
		(layer "B.Cu")
		(net "D_LATCH_PRE#")
	)
	(segment
		(start 37.973 -149.0472)
		(end 45.20565 -156.27985)
		(width 0.1397)
		(layer "B.Cu")
		(net "D_LATCH_PRE#")
	)
	(segment
		(start 49.3776 -108.2294)
		(end 49.3776 -111.7346)
		(width 0.1397)
		(layer "B.Cu")
		(net "D_LATCH_PRE#")
	)
	(segment
		(start 48.8442 -69.5198)
		(end 48.8442 -98.7044)
		(width 0.1397)
		(layer "B.Cu")
		(net "D_LATCH_PRE#")
	)
	(segment
		(start 43.1292 -159.4612)
		(end 43.1292 -173.355)
		(width 0.1397)
		(layer "B.Cu")
		(net "D_LATCH_PRE#")
	)
	(segment
		(start 46.3042 -134.874)
		(end 42.926 -138.2522)
		(width 0.1397)
		(layer "B.Cu")
		(net "D_LATCH_PRE#")
	)
	(segment
		(start 18.49755 -48.78705)
		(end 19.910044 -47.374556)
		(width 0.1397)
		(layer "B.Cu")
		(net "D_LATCH_PRE#")
	)
	(segment
		(start 48.2092 -107.061)
		(end 49.3776 -108.2294)
		(width 0.1397)
		(layer "B.Cu")
		(net "D_LATCH_PRE#")
	)
	(segment
		(start 49.3776 -111.7346)
		(end 47.0408 -114.0714)
		(width 0.1397)
		(layer "B.Cu")
		(net "D_LATCH_PRE#")
	)
	(segment
		(start 45.949616 -66.625216)
		(end 48.8442 -69.5198)
		(width 0.1397)
		(layer "B.Cu")
		(net "D_LATCH_PRE#")
	)
	(segment
		(start 42.925746 -138.2522)
		(end 37.973 -143.204946)
		(width 0.1397)
		(layer "B.Cu")
		(net "D_LATCH_PRE#")
	)
	(segment
		(start 45.20565 -156.27985)
		(end 45.20565 -157.38475)
		(width 0.1397)
		(layer "B.Cu")
		(net "D_LATCH_PRE#")
	)
	(segment
		(start 42.901616 -66.625216)
		(end 45.949616 -66.625216)
		(width 0.1397)
		(layer "B.Cu")
		(net "D_LATCH_PRE#")
	)
	(segment
		(start 47.0408 -114.0968)
		(end 46.3042 -114.8334)
		(width 0.1397)
		(layer "B.Cu")
		(net "D_LATCH_PRE#")
	)
	(segment
		(start 36.3982 -57.3278)
		(end 37.4142 -58.3438)
		(width 0.1397)
		(layer "B.Cu")
		(net "D_LATCH_PRE#")
	)
	(segment
		(start 21.530056 -47.819056)
		(end 29.023056 -47.819056)
		(width 0.1397)
		(layer "B.Cu")
		(net "D_LATCH_PRE#")
	)
	(segment
		(start 41.021 -175.4632)
		(end 41.021 -175.6918)
		(width 0.1397)
		(layer "B.Cu")
		(net "D_LATCH_PRE#")
	)
	(segment
		(start 48.2092 -99.3394)
		(end 48.2092 -107.061)
		(width 0.1397)
		(layer "B.Cu")
		(net "D_LATCH_PRE#")
	)
	(segment
		(start 41.6052 -58.76798)
		(end 41.6052 -65.3288)
		(width 0.1397)
		(layer "B.Cu")
		(net "D_LATCH_PRE#")
	)
	(segment
		(start 13.76045 -48.78705)
		(end 18.49755 -48.78705)
		(width 0.1397)
		(layer "B.Cu")
		(net "D_LATCH_PRE#")
	)
	(segment
		(start 45.20565 -157.38475)
		(end 43.1292 -159.4612)
		(width 0.1397)
		(layer "B.Cu")
		(net "D_LATCH_PRE#")
	)
	(segment
		(start 48.8442 -98.7044)
		(end 48.2092 -99.3394)
		(width 0.1397)
		(layer "B.Cu")
		(net "D_LATCH_PRE#")
	)
	(segment
		(start 47.0408 -114.0714)
		(end 47.0408 -114.0968)
		(width 0.1397)
		(layer "B.Cu")
		(net "D_LATCH_PRE#")
	)
	(segment
		(start 46.3042 -114.8334)
		(end 46.3042 -134.874)
		(width 0.1397)
		(layer "B.Cu")
		(net "D_LATCH_PRE#")
	)
	(via
		(at 29.845 -184.023)
		(size 0.7112)
		(drill 0.3556)
		(layers "F.Cu" "B.Cu")
		(net "P3V3_AUX_BJT_B")
	)
	(via
		(at 43.942 -175.514)
		(size 0.7112)
		(drill 0.3556)
		(layers "F.Cu" "B.Cu")
		(net "P3V3_AUX")
	)
	(via
		(at 36.068 -178.054)
		(size 0.7112)
		(drill 0.3556)
		(layers "F.Cu" "B.Cu")
		(net "P3V3_AUX")
	)
	(segment
		(start 37.973 -180.7845)
		(end 36.83 -180.7845)
		(width 0.1397)
		(layer "F.Cu")
		(net "D_LATCH_CLR")
	)
	(segment
		(start 38.391084 -180.366416)
		(end 37.973 -180.7845)
		(width 0.1397)
		(layer "F.Cu")
		(net "D_LATCH_CLR")
	)
	(segment
		(start 39.57955 -180.366416)
		(end 38.391084 -180.366416)
		(width 0.1397)
		(layer "F.Cu")
		(net "D_LATCH_CLR")
	)
	(via
		(at 36.83 -180.7845)
		(size 0.7112)
		(drill 0.3556)
		(layers "F.Cu" "B.Cu")
		(net "D_LATCH_CLR")
	)
	(segment
		(start 45.470318 -157.483302)
		(end 45.081698 -157.483302)
		(width 0.1397)
		(layer "F.Cu")
		(net "NCT7904_VSEN_P12V_AUX")
	)
	(segment
		(start 42.2021 -159.1818)
		(end 42.2021 -158.1658)
		(width 0.1397)
		(layer "F.Cu")
		(net "NCT7904_VSEN_P12V_AUX")
	)
	(segment
		(start 45.081698 -157.483302)
		(end 44.2595 -158.3055)
		(width 0.1397)
		(layer "F.Cu")
		(net "NCT7904_VSEN_P12V_AUX")
	)
	(segment
		(start 43.2308 -159.2961)
		(end 42.3164 -159.2961)
		(width 0.1397)
		(layer "F.Cu")
		(net "NCT7904_VSEN_P12V_AUX")
	)
	(segment
		(start 44.2595 -158.3055)
		(end 44.2595 -158.5722)
		(width 0.1397)
		(layer "F.Cu")
		(net "NCT7904_VSEN_P12V_AUX")
	)
	(segment
		(start 43.2308 -159.2961)
		(end 43.5356 -159.2961)
		(width 0.1397)
		(layer "F.Cu")
		(net "NCT7904_VSEN_P12V_AUX")
	)
	(segment
		(start 42.3164 -159.2961)
		(end 42.2021 -159.1818)
		(width 0.1397)
		(layer "F.Cu")
		(net "NCT7904_VSEN_P12V_AUX")
	)
	(segment
		(start 43.5356 -159.2961)
		(end 44.2595 -158.5722)
		(width 0.1397)
		(layer "F.Cu")
		(net "NCT7904_VSEN_P12V_AUX")
	)
	(via
		(at 45.470318 -157.483302)
		(size 0.7112)
		(drill 0.3556)
		(layers "F.Cu" "B.Cu")
		(net "NCT7904_VSEN_P12V_AUX")
	)
	(segment
		(start 25.0952 -210.4009)
		(end 25.096216 -210.399884)
		(width 0.254)
		(layer "F.Cu")
		(net "PWM_OUT_FAN6_NET")
	)
	(segment
		(start 15.546578 -210.4009)
		(end 25.0952 -210.4009)
		(width 0.254)
		(layer "F.Cu")
		(net "PWM_OUT_FAN6_NET")
	)
	(segment
		(start 16.08201 -14.75994)
		(end 4.040124 -14.75994)
		(width 0.254)
		(layer "F.Cu")
		(net "PWM_OUT_FAN6_NET")
	)
	(segment
		(start 17.0815 -16.129)
		(end 17.0815 -15.75943)
		(width 0.254)
		(layer "F.Cu")
		(net "PWM_OUT_FAN6_NET")
	)
	(segment
		(start 17.0815 -15.75943)
		(end 16.08201 -14.75994)
		(width 0.254)
		(layer "F.Cu")
		(net "PWM_OUT_FAN6_NET")
	)
	(segment
		(start 25.096216 -210.399884)
		(end 26.1366 -210.399884)
		(width 0.254)
		(layer "F.Cu")
		(net "PWM_OUT_FAN6_NET")
	)
	(segment
		(start 17.0815 -16.129)
		(end 16.129 -16.129)
		(width 0.254)
		(layer "F.Cu")
		(net "PWM_OUT_FAN6_NET")
	)
	(via
		(at 15.546578 -210.4009)
		(size 0.5588)
		(drill 0.3048)
		(layers "F.Cu" "B.Cu")
		(net "PWM_OUT_FAN6_NET")
	)
	(via
		(at 17.6784 -168.3258)
		(size 0.7112)
		(drill 0.3556)
		(layers "F.Cu" "B.Cu")
		(net "PWM_OUT_FAN6_NET")
	)
	(via
		(at 16.129 -16.129)
		(size 0.5588)
		(drill 0.3048)
		(layers "F.Cu" "B.Cu")
		(net "PWM_OUT_FAN6_NET")
	)
	(segment
		(start 10.5156 -47.5996)
		(end 10.5156 -51.9938)
		(width 0.254)
		(layer "B.Cu")
		(net "PWM_OUT_FAN6_NET")
	)
	(segment
		(start 16.256 -152.019)
		(end 16.256 -155.6766)
		(width 0.254)
		(layer "B.Cu")
		(net "PWM_OUT_FAN6_NET")
	)
	(segment
		(start 6.6294 -85.621876)
		(end 6.6294 -92.68333)
		(width 0.254)
		(layer "B.Cu")
		(net "PWM_OUT_FAN6_NET")
	)
	(segment
		(start 12.147296 -41.954704)
		(end 11.6332 -42.4688)
		(width 0.254)
		(layer "B.Cu")
		(net "PWM_OUT_FAN6_NET")
	)
	(segment
		(start 8.7884 -65.1002)
		(end 7.6454 -66.2432)
		(width 0.254)
		(layer "B.Cu")
		(net "PWM_OUT_FAN6_NET")
	)
	(segment
		(start 11.6332 -46.482)
		(end 10.5156 -47.5996)
		(width 0.254)
		(layer "B.Cu")
		(net "PWM_OUT_FAN6_NET")
	)
	(segment
		(start 7.6454 -66.2432)
		(end 7.6454 -84.605876)
		(width 0.254)
		(layer "B.Cu")
		(net "PWM_OUT_FAN6_NET")
	)
	(segment
		(start 16.256 -155.6766)
		(end 17.6784 -157.099)
		(width 0.254)
		(layer "B.Cu")
		(net "PWM_OUT_FAN6_NET")
	)
	(segment
		(start 17.15135 -168.85285)
		(end 17.6784 -168.3258)
		(width 0.254)
		(layer "B.Cu")
		(net "PWM_OUT_FAN6_NET")
	)
	(segment
		(start 11.53668 -53.01488)
		(end 11.53668 -59.8424)
		(width 0.254)
		(layer "B.Cu")
		(net "PWM_OUT_FAN6_NET")
	)
	(segment
		(start 16.129 -16.129)
		(end 16.129 -16.51)
		(width 0.254)
		(layer "B.Cu")
		(net "PWM_OUT_FAN6_NET")
	)
	(segment
		(start 10.5156 -51.9938)
		(end 11.53668 -53.01488)
		(width 0.254)
		(layer "B.Cu")
		(net "PWM_OUT_FAN6_NET")
	)
	(segment
		(start 17.15135 -172.01642)
		(end 17.15135 -168.85285)
		(width 0.254)
		(layer "B.Cu")
		(net "PWM_OUT_FAN6_NET")
	)
	(segment
		(start 5.364734 -93.947996)
		(end 5.364734 -114.06124)
		(width 0.254)
		(layer "B.Cu")
		(net "PWM_OUT_FAN6_NET")
	)
	(segment
		(start 15.9385 -173.22927)
		(end 17.15135 -172.01642)
		(width 0.254)
		(layer "B.Cu")
		(net "PWM_OUT_FAN6_NET")
	)
	(segment
		(start 17.6784 -157.099)
		(end 17.6784 -168.3258)
		(width 0.254)
		(layer "B.Cu")
		(net "PWM_OUT_FAN6_NET")
	)
	(segment
		(start 8.7884 -62.59068)
		(end 8.7884 -65.1002)
		(width 0.254)
		(layer "B.Cu")
		(net "PWM_OUT_FAN6_NET")
	)
	(segment
		(start 4.890516 -114.535458)
		(end 4.890516 -117.996716)
		(width 0.254)
		(layer "B.Cu")
		(net "PWM_OUT_FAN6_NET")
	)
	(segment
		(start 7.8232 -133.8326)
		(end 10.922 -136.9314)
		(width 0.254)
		(layer "B.Cu")
		(net "PWM_OUT_FAN6_NET")
	)
	(segment
		(start 7.8232 -120.9294)
		(end 7.8232 -133.8326)
		(width 0.254)
		(layer "B.Cu")
		(net "PWM_OUT_FAN6_NET")
	)
	(segment
		(start 5.364734 -114.06124)
		(end 4.890516 -114.535458)
		(width 0.254)
		(layer "B.Cu")
		(net "PWM_OUT_FAN6_NET")
	)
	(segment
		(start 10.922 -136.9314)
		(end 10.922 -146.685)
		(width 0.254)
		(layer "B.Cu")
		(net "PWM_OUT_FAN6_NET")
	)
	(segment
		(start 15.546578 -210.4009)
		(end 15.9385 -210.008978)
		(width 0.254)
		(layer "B.Cu")
		(net "PWM_OUT_FAN6_NET")
	)
	(segment
		(start 11.53668 -59.8424)
		(end 8.7884 -62.59068)
		(width 0.254)
		(layer "B.Cu")
		(net "PWM_OUT_FAN6_NET")
	)
	(segment
		(start 10.922 -146.685)
		(end 16.256 -152.019)
		(width 0.254)
		(layer "B.Cu")
		(net "PWM_OUT_FAN6_NET")
	)
	(segment
		(start 4.890516 -117.996716)
		(end 7.8232 -120.9294)
		(width 0.254)
		(layer "B.Cu")
		(net "PWM_OUT_FAN6_NET")
	)
	(segment
		(start 15.9385 -210.008978)
		(end 15.9385 -173.22927)
		(width 0.254)
		(layer "B.Cu")
		(net "PWM_OUT_FAN6_NET")
	)
	(segment
		(start 7.6454 -84.605876)
		(end 6.6294 -85.621876)
		(width 0.254)
		(layer "B.Cu")
		(net "PWM_OUT_FAN6_NET")
	)
	(segment
		(start 6.6294 -92.68333)
		(end 5.364734 -93.947996)
		(width 0.254)
		(layer "B.Cu")
		(net "PWM_OUT_FAN6_NET")
	)
	(segment
		(start 11.6332 -42.4688)
		(end 11.6332 -46.482)
		(width 0.254)
		(layer "B.Cu")
		(net "PWM_OUT_FAN6_NET")
	)
	(segment
		(start 16.129 -16.51)
		(end 12.147296 -20.491704)
		(width 0.254)
		(layer "B.Cu")
		(net "PWM_OUT_FAN6_NET")
	)
	(segment
		(start 12.147296 -20.491704)
		(end 12.147296 -41.954704)
		(width 0.254)
		(layer "B.Cu")
		(net "PWM_OUT_FAN6_NET")
	)
	(segment
		(start 6.8834 -145.7706)
		(end 7.366 -145.7706)
		(width 0.254)
		(layer "F.Cu")
		(net "PWM_OUT_FAN5_NET")
	)
	(segment
		(start 7.62 -145.078704)
		(end 7.6073 -145.066004)
		(width 0.254)
		(layer "F.Cu")
		(net "PWM_OUT_FAN5_NET")
	)
	(segment
		(start 27.4447 -209.6008)
		(end 28.2448 -210.4009)
		(width 0.254)
		(layer "F.Cu")
		(net "PWM_OUT_FAN5_NET")
	)
	(segment
		(start 7.366 -145.7706)
		(end 7.62 -145.5166)
		(width 0.254)
		(layer "F.Cu")
		(net "PWM_OUT_FAN5_NET")
	)
	(segment
		(start 13.0048 -210.058)
		(end 13.462 -209.6008)
		(width 0.254)
		(layer "F.Cu")
		(net "PWM_OUT_FAN5_NET")
	)
	(segment
		(start 6.858 -145.7452)
		(end 6.8834 -145.7706)
		(width 0.254)
		(layer "F.Cu")
		(net "PWM_OUT_FAN5_NET")
	)
	(segment
		(start 7.62 -145.5166)
		(end 7.62 -145.078704)
		(width 0.254)
		(layer "F.Cu")
		(net "PWM_OUT_FAN5_NET")
	)
	(segment
		(start 13.462 -209.6008)
		(end 27.4447 -209.6008)
		(width 0.254)
		(layer "F.Cu")
		(net "PWM_OUT_FAN5_NET")
	)
	(segment
		(start 7.6073 -145.066004)
		(end 7.6073 -144.9832)
		(width 0.254)
		(layer "F.Cu")
		(net "PWM_OUT_FAN5_NET")
	)
	(via
		(at 6.858 -145.7452)
		(size 0.5588)
		(drill 0.3048)
		(layers "F.Cu" "B.Cu")
		(net "PWM_OUT_FAN5_NET")
	)
	(via
		(at 13.0048 -210.058)
		(size 0.5588)
		(drill 0.3048)
		(layers "F.Cu" "B.Cu")
		(net "PWM_OUT_FAN5_NET")
	)
	(via
		(at 9.652 -149.733)
		(size 0.7112)
		(drill 0.3556)
		(layers "F.Cu" "B.Cu")
		(net "PWM_OUT_FAN5_NET")
	)
	(segment
		(start 9.652 -149.479)
		(end 6.858 -146.685)
		(width 0.254)
		(layer "B.Cu")
		(net "PWM_OUT_FAN5_NET")
	)
	(segment
		(start 4.475734 -142.270734)
		(end 6.951726 -144.746726)
		(width 0.254)
		(layer "B.Cu")
		(net "PWM_OUT_FAN5_NET")
	)
	(segment
		(start 5.449824 -126.209806)
		(end 5.449824 -133.742176)
		(width 0.254)
		(layer "B.Cu")
		(net "PWM_OUT_FAN5_NET")
	)
	(segment
		(start 10.107676 -191.568324)
		(end 10.7696 -190.9064)
		(width 0.254)
		(layer "B.Cu")
		(net "PWM_OUT_FAN5_NET")
	)
	(segment
		(start 9.779 -149.733)
		(end 9.652 -149.733)
		(width 0.254)
		(layer "B.Cu")
		(net "PWM_OUT_FAN5_NET")
	)
	(segment
		(start 11.8364 -177.5206)
		(end 11.8364 -151.7904)
		(width 0.254)
		(layer "B.Cu")
		(net "PWM_OUT_FAN5_NET")
	)
	(segment
		(start 5.449824 -133.742176)
		(end 4.475734 -134.716266)
		(width 0.254)
		(layer "B.Cu")
		(net "PWM_OUT_FAN5_NET")
	)
	(segment
		(start 6.858 -146.685)
		(end 6.858 -145.7452)
		(width 0.254)
		(layer "B.Cu")
		(net "PWM_OUT_FAN5_NET")
	)
	(segment
		(start 4.040124 -124.800106)
		(end 5.449824 -126.209806)
		(width 0.254)
		(layer "B.Cu")
		(net "PWM_OUT_FAN5_NET")
	)
	(segment
		(start 10.7696 -178.5874)
		(end 11.8364 -177.5206)
		(width 0.254)
		(layer "B.Cu")
		(net "PWM_OUT_FAN5_NET")
	)
	(segment
		(start 6.951726 -144.746726)
		(end 6.951726 -145.651474)
		(width 0.254)
		(layer "B.Cu")
		(net "PWM_OUT_FAN5_NET")
	)
	(segment
		(start 13.0048 -198.2978)
		(end 10.107676 -195.400676)
		(width 0.254)
		(layer "B.Cu")
		(net "PWM_OUT_FAN5_NET")
	)
	(segment
		(start 4.475734 -134.716266)
		(end 4.475734 -142.270734)
		(width 0.254)
		(layer "B.Cu")
		(net "PWM_OUT_FAN5_NET")
	)
	(segment
		(start 11.8364 -151.7904)
		(end 9.779 -149.733)
		(width 0.254)
		(layer "B.Cu")
		(net "PWM_OUT_FAN5_NET")
	)
	(segment
		(start 10.7696 -190.9064)
		(end 10.7696 -178.5874)
		(width 0.254)
		(layer "B.Cu")
		(net "PWM_OUT_FAN5_NET")
	)
	(segment
		(start 10.107676 -195.400676)
		(end 10.107676 -191.568324)
		(width 0.254)
		(layer "B.Cu")
		(net "PWM_OUT_FAN5_NET")
	)
	(segment
		(start 6.951726 -145.651474)
		(end 6.858 -145.7452)
		(width 0.254)
		(layer "B.Cu")
		(net "PWM_OUT_FAN5_NET")
	)
	(segment
		(start 13.0048 -210.058)
		(end 13.0048 -198.2978)
		(width 0.254)
		(layer "B.Cu")
		(net "PWM_OUT_FAN5_NET")
	)
	(segment
		(start 9.652 -149.733)
		(end 9.652 -149.479)
		(width 0.254)
		(layer "B.Cu")
		(net "PWM_OUT_FAN5_NET")
	)
	(segment
		(start 21.844 -183.896)
		(end 21.971 -183.769)
		(width 0.254)
		(layer "F.Cu")
		(net "PWM_OUT_FAN4_NET")
	)
	(segment
		(start 16.5735 -185.42)
		(end 16.637 -185.3565)
		(width 0.254)
		(layer "F.Cu")
		(net "PWM_OUT_FAN4_NET")
	)
	(segment
		(start 4.826 -188.849)
		(end 5.969 -187.706)
		(width 0.254)
		(layer "F.Cu")
		(net "PWM_OUT_FAN4_NET")
	)
	(segment
		(start 17.267174 -183.896)
		(end 21.844 -183.896)
		(width 0.254)
		(layer "F.Cu")
		(net "PWM_OUT_FAN4_NET")
	)
	(segment
		(start 5.969 -187.706)
		(end 13.335 -187.706)
		(width 0.254)
		(layer "F.Cu")
		(net "PWM_OUT_FAN4_NET")
	)
	(segment
		(start 16.637 -184.526174)
		(end 17.267174 -183.896)
		(width 0.254)
		(layer "F.Cu")
		(net "PWM_OUT_FAN4_NET")
	)
	(segment
		(start 13.335 -187.706)
		(end 15.621 -185.42)
		(width 0.254)
		(layer "F.Cu")
		(net "PWM_OUT_FAN4_NET")
	)
	(segment
		(start 30.2641 -210.4009)
		(end 29.1846 -209.3214)
		(width 0.254)
		(layer "F.Cu")
		(net "PWM_OUT_FAN4_NET")
	)
	(segment
		(start 30.3784 -210.4009)
		(end 30.2641 -210.4009)
		(width 0.254)
		(layer "F.Cu")
		(net "PWM_OUT_FAN4_NET")
	)
	(segment
		(start 15.621 -185.42)
		(end 16.5735 -185.42)
		(width 0.254)
		(layer "F.Cu")
		(net "PWM_OUT_FAN4_NET")
	)
	(segment
		(start 16.637 -185.3565)
		(end 16.637 -184.526174)
		(width 0.254)
		(layer "F.Cu")
		(net "PWM_OUT_FAN4_NET")
	)
	(segment
		(start 4.826 -190.014098)
		(end 4.826 -188.849)
		(width 0.254)
		(layer "F.Cu")
		(net "PWM_OUT_FAN4_NET")
	)
	(segment
		(start 4.040124 -190.799974)
		(end 4.826 -190.014098)
		(width 0.254)
		(layer "F.Cu")
		(net "PWM_OUT_FAN4_NET")
	)
	(via
		(at 29.1846 -209.3214)
		(size 0.5588)
		(drill 0.3048)
		(layers "F.Cu" "B.Cu")
		(net "PWM_OUT_FAN4_NET")
	)
	(via
		(at 26.863802 -206.822802)
		(size 0.7112)
		(drill 0.3556)
		(layers "F.Cu" "B.Cu")
		(net "PWM_OUT_FAN4_NET")
	)
	(via
		(at 21.971 -183.769)
		(size 0.5588)
		(drill 0.3048)
		(layers "F.Cu" "B.Cu")
		(net "PWM_OUT_FAN4_NET")
	)
	(segment
		(start 29.1846 -209.3214)
		(end 29.1846 -209.1436)
		(width 0.254)
		(layer "B.Cu")
		(net "PWM_OUT_FAN4_NET")
	)
	(segment
		(start 21.971 -201.93)
		(end 26.863802 -206.822802)
		(width 0.254)
		(layer "B.Cu")
		(net "PWM_OUT_FAN4_NET")
	)
	(segment
		(start 29.1846 -209.1436)
		(end 26.863802 -206.822802)
		(width 0.254)
		(layer "B.Cu")
		(net "PWM_OUT_FAN4_NET")
	)
	(segment
		(start 21.971 -183.769)
		(end 21.971 -201.93)
		(width 0.254)
		(layer "B.Cu")
		(net "PWM_OUT_FAN4_NET")
	)
	(segment
		(start 4.040124 -304.120042)
		(end 4.796282 -304.120042)
		(width 0.254)
		(layer "F.Cu")
		(net "PWM_OUT_FAN3_NET")
	)
	(segment
		(start 17.5133 -258.445)
		(end 18.3769 -259.3086)
		(width 0.254)
		(layer "F.Cu")
		(net "PWM_OUT_FAN3_NET")
	)
	(segment
		(start 29.2354 -224.7519)
		(end 29.2354 -224.79)
		(width 0.254)
		(layer "F.Cu")
		(net "PWM_OUT_FAN3_NET")
	)
	(segment
		(start 11.80465 -259.72135)
		(end 12.954 -258.572)
		(width 0.254)
		(layer "F.Cu")
		(net "PWM_OUT_FAN3_NET")
	)
	(segment
		(start 17.2212 -225.9076)
		(end 17.0688 -225.7552)
		(width 0.254)
		(layer "F.Cu")
		(net "PWM_OUT_FAN3_NET")
	)
	(segment
		(start 29.2354 -224.79)
		(end 28.1178 -225.9076)
		(width 0.254)
		(layer "F.Cu")
		(net "PWM_OUT_FAN3_NET")
	)
	(segment
		(start 11.80465 -297.111674)
		(end 11.80465 -259.72135)
		(width 0.254)
		(layer "F.Cu")
		(net "PWM_OUT_FAN3_NET")
	)
	(segment
		(start 30.3022 -224.7519)
		(end 29.2354 -224.7519)
		(width 0.254)
		(layer "F.Cu")
		(net "PWM_OUT_FAN3_NET")
	)
	(segment
		(start 12.954 -258.572)
		(end 13.081 -258.445)
		(width 0.254)
		(layer "F.Cu")
		(net "PWM_OUT_FAN3_NET")
	)
	(segment
		(start 4.796282 -304.120042)
		(end 11.80465 -297.111674)
		(width 0.254)
		(layer "F.Cu")
		(net "PWM_OUT_FAN3_NET")
	)
	(segment
		(start 13.081 -258.445)
		(end 17.5133 -258.445)
		(width 0.254)
		(layer "F.Cu")
		(net "PWM_OUT_FAN3_NET")
	)
	(segment
		(start 28.1178 -225.9076)
		(end 17.2212 -225.9076)
		(width 0.254)
		(layer "F.Cu")
		(net "PWM_OUT_FAN3_NET")
	)
	(via
		(at 14.859 -231.775)
		(size 0.7112)
		(drill 0.3556)
		(layers "F.Cu" "B.Cu")
		(net "PWM_OUT_FAN3_NET")
	)
	(via
		(at 17.0688 -225.7552)
		(size 0.5588)
		(drill 0.3048)
		(layers "F.Cu" "B.Cu")
		(net "PWM_OUT_FAN3_NET")
	)
	(via
		(at 12.954 -258.572)
		(size 0.5588)
		(drill 0.3048)
		(layers "F.Cu" "B.Cu")
		(net "PWM_OUT_FAN3_NET")
	)
	(segment
		(start 12.96035 -258.56565)
		(end 12.96035 -234.68965)
		(width 0.254)
		(layer "B.Cu")
		(net "PWM_OUT_FAN3_NET")
	)
	(segment
		(start 14.859 -232.791)
		(end 14.859 -231.775)
		(width 0.254)
		(layer "B.Cu")
		(net "PWM_OUT_FAN3_NET")
	)
	(segment
		(start 12.954 -258.572)
		(end 12.96035 -258.56565)
		(width 0.254)
		(layer "B.Cu")
		(net "PWM_OUT_FAN3_NET")
	)
	(segment
		(start 14.859 -231.775)
		(end 14.859 -230.378)
		(width 0.254)
		(layer "B.Cu")
		(net "PWM_OUT_FAN3_NET")
	)
	(segment
		(start 17.0688 -228.1682)
		(end 17.0688 -225.7552)
		(width 0.254)
		(layer "B.Cu")
		(net "PWM_OUT_FAN3_NET")
	)
	(segment
		(start 14.859 -230.378)
		(end 17.0688 -228.1682)
		(width 0.254)
		(layer "B.Cu")
		(net "PWM_OUT_FAN3_NET")
	)
	(segment
		(start 12.96035 -234.68965)
		(end 14.859 -232.791)
		(width 0.254)
		(layer "B.Cu")
		(net "PWM_OUT_FAN3_NET")
	)
	(segment
		(start 26.5684 -225.3107)
		(end 17.484852 -225.3107)
		(width 0.254)
		(layer "F.Cu")
		(net "PWM_OUT_FAN2_NET")
	)
	(segment
		(start 17.484852 -225.3107)
		(end 17.014952 -224.8408)
		(width 0.254)
		(layer "F.Cu")
		(net "PWM_OUT_FAN2_NET")
	)
	(segment
		(start 17.4625 -299.4025)
		(end 17.4752 -299.4152)
		(width 0.254)
		(layer "F.Cu")
		(net "PWM_OUT_FAN2_NET")
	)
	(segment
		(start 28.1686 -224.7519)
		(end 27.1272 -224.7519)
		(width 0.254)
		(layer "F.Cu")
		(net "PWM_OUT_FAN2_NET")
	)
	(segment
		(start 27.1272 -224.7519)
		(end 26.5684 -225.3107)
		(width 0.254)
		(layer "F.Cu")
		(net "PWM_OUT_FAN2_NET")
	)
	(segment
		(start 17.4625 -298.4754)
		(end 17.4625 -299.4025)
		(width 0.254)
		(layer "F.Cu")
		(net "PWM_OUT_FAN2_NET")
	)
	(segment
		(start 17.014952 -224.8408)
		(end 15.6464 -224.8408)
		(width 0.254)
		(layer "F.Cu")
		(net "PWM_OUT_FAN2_NET")
	)
	(via
		(at 17.4752 -299.4152)
		(size 0.5588)
		(drill 0.3048)
		(layers "F.Cu" "B.Cu")
		(net "PWM_OUT_FAN2_NET")
	)
	(via
		(at 15.6464 -224.8408)
		(size 0.5588)
		(drill 0.3048)
		(layers "F.Cu" "B.Cu")
		(net "PWM_OUT_FAN2_NET")
	)
	(via
		(at 15.4686 -226.822)
		(size 0.7112)
		(drill 0.3556)
		(layers "F.Cu" "B.Cu")
		(net "PWM_OUT_FAN2_NET")
	)
	(segment
		(start 17.0815 -297.0149)
		(end 17.0815 -299.0215)
		(width 0.254)
		(layer "B.Cu")
		(net "PWM_OUT_FAN2_NET")
	)
	(segment
		(start 15.6464 -226.6442)
		(end 15.6464 -224.8408)
		(width 0.254)
		(layer "B.Cu")
		(net "PWM_OUT_FAN2_NET")
	)
	(segment
		(start 17.0815 -299.0215)
		(end 17.4752 -299.4152)
		(width 0.254)
		(layer "B.Cu")
		(net "PWM_OUT_FAN2_NET")
	)
	(segment
		(start 11.8364 -231.5972)
		(end 11.8364 -285.2674)
		(width 0.254)
		(layer "B.Cu")
		(net "PWM_OUT_FAN2_NET")
	)
	(segment
		(start 15.4686 -226.822)
		(end 15.6464 -226.6442)
		(width 0.254)
		(layer "B.Cu")
		(net "PWM_OUT_FAN2_NET")
	)
	(segment
		(start 4.040124 -370.11991)
		(end 3.027934 -369.10772)
		(width 0.254)
		(layer "B.Cu")
		(net "PWM_OUT_FAN2_NET")
	)
	(segment
		(start 3.027934 -369.10772)
		(end 3.027934 -351.201736)
		(width 0.254)
		(layer "B.Cu")
		(net "PWM_OUT_FAN2_NET")
	)
	(segment
		(start 17.4752 -336.75447)
		(end 17.4752 -299.4152)
		(width 0.254)
		(layer "B.Cu")
		(net "PWM_OUT_FAN2_NET")
	)
	(segment
		(start 17.3736 -296.7228)
		(end 17.0815 -297.0149)
		(width 0.254)
		(layer "B.Cu")
		(net "PWM_OUT_FAN2_NET")
	)
	(segment
		(start 3.027934 -351.201736)
		(end 17.4752 -336.75447)
		(width 0.254)
		(layer "B.Cu")
		(net "PWM_OUT_FAN2_NET")
	)
	(segment
		(start 11.8364 -285.2674)
		(end 17.3736 -290.8046)
		(width 0.254)
		(layer "B.Cu")
		(net "PWM_OUT_FAN2_NET")
	)
	(segment
		(start 15.4686 -226.822)
		(end 15.4686 -227.965)
		(width 0.254)
		(layer "B.Cu")
		(net "PWM_OUT_FAN2_NET")
	)
	(segment
		(start 17.3736 -290.8046)
		(end 17.3736 -296.7228)
		(width 0.254)
		(layer "B.Cu")
		(net "PWM_OUT_FAN2_NET")
	)
	(segment
		(start 15.4686 -227.965)
		(end 11.8364 -231.5972)
		(width 0.254)
		(layer "B.Cu")
		(net "PWM_OUT_FAN2_NET")
	)
	(segment
		(start 26.0604 -224.7519)
		(end 17.7165 -224.7519)
		(width 0.254)
		(layer "F.Cu")
		(net "PWM_OUT_FAN1_NET")
	)
	(segment
		(start 17.1704 -224.2058)
		(end 16.4084 -224.2058)
		(width 0.254)
		(layer "F.Cu")
		(net "PWM_OUT_FAN1_NET")
	)
	(segment
		(start 8.8773 -454.3171)
		(end 8.8773 -454.2028)
		(width 0.254)
		(layer "F.Cu")
		(net "PWM_OUT_FAN1_NET")
	)
	(segment
		(start 9.958324 -455.245724)
		(end 9.951466 -455.245724)
		(width 0.254)
		(layer "F.Cu")
		(net "PWM_OUT_FAN1_NET")
	)
	(segment
		(start 14.23035 -459.51775)
		(end 9.958324 -455.245724)
		(width 0.254)
		(layer "F.Cu")
		(net "PWM_OUT_FAN1_NET")
	)
	(segment
		(start 17.7165 -224.7519)
		(end 17.1704 -224.2058)
		(width 0.254)
		(layer "F.Cu")
		(net "PWM_OUT_FAN1_NET")
	)
	(segment
		(start 4.040124 -480.160076)
		(end 7.646924 -480.160076)
		(width 0.254)
		(layer "F.Cu")
		(net "PWM_OUT_FAN1_NET")
	)
	(segment
		(start 14.23035 -473.57665)
		(end 14.23035 -459.51775)
		(width 0.254)
		(layer "F.Cu")
		(net "PWM_OUT_FAN1_NET")
	)
	(segment
		(start 9.951466 -455.245724)
		(end 9.805924 -455.245724)
		(width 0.254)
		(layer "F.Cu")
		(net "PWM_OUT_FAN1_NET")
	)
	(segment
		(start 9.805924 -455.245724)
		(end 8.8773 -454.3171)
		(width 0.254)
		(layer "F.Cu")
		(net "PWM_OUT_FAN1_NET")
	)
	(segment
		(start 7.646924 -480.160076)
		(end 14.23035 -473.57665)
		(width 0.254)
		(layer "F.Cu")
		(net "PWM_OUT_FAN1_NET")
	)
	(via
		(at 14.459458 -287.026858)
		(size 0.7112)
		(drill 0.3556)
		(layers "F.Cu" "B.Cu")
		(net "PWM_OUT_FAN1_NET")
	)
	(via
		(at 16.4084 -224.2058)
		(size 0.5588)
		(drill 0.3048)
		(layers "F.Cu" "B.Cu")
		(net "PWM_OUT_FAN1_NET")
	)
	(via
		(at 9.951466 -455.245724)
		(size 0.7112)
		(drill 0.4064)
		(layers "F.Cu" "B.Cu")
		(net "PWM_OUT_FAN1_NET")
	)
	(segment
		(start 14.459458 -287.026858)
		(end 18.3642 -290.9316)
		(width 0.254)
		(layer "B.Cu")
		(net "PWM_OUT_FAN1_NET")
	)
	(segment
		(start 12.3952 -231.9528)
		(end 16.4084 -227.9396)
		(width 0.254)
		(layer "B.Cu")
		(net "PWM_OUT_FAN1_NET")
	)
	(segment
		(start 14.459458 -287.026858)
		(end 12.3952 -284.9626)
		(width 0.254)
		(layer "B.Cu")
		(net "PWM_OUT_FAN1_NET")
	)
	(segment
		(start 12.3952 -284.9626)
		(end 12.3952 -231.9528)
		(width 0.254)
		(layer "B.Cu")
		(net "PWM_OUT_FAN1_NET")
	)
	(segment
		(start 19.116802 -337.803998)
		(end 4.475734 -352.445066)
		(width 0.254)
		(layer "B.Cu")
		(net "PWM_OUT_FAN1_NET")
	)
	(segment
		(start 3.586734 -379.55855)
		(end 3.586734 -416.61461)
		(width 0.254)
		(layer "B.Cu")
		(net "PWM_OUT_FAN1_NET")
	)
	(segment
		(start 3.586734 -416.61461)
		(end 4.216654 -417.24453)
		(width 0.254)
		(layer "B.Cu")
		(net "PWM_OUT_FAN1_NET")
	)
	(segment
		(start 18.3642 -290.9316)
		(end 18.3642 -293.3446)
		(width 0.254)
		(layer "B.Cu")
		(net "PWM_OUT_FAN1_NET")
	)
	(segment
		(start 18.3642 -293.3446)
		(end 19.116802 -294.097202)
		(width 0.254)
		(layer "B.Cu")
		(net "PWM_OUT_FAN1_NET")
	)
	(segment
		(start 4.216654 -417.24453)
		(end 4.216654 -449.510912)
		(width 0.254)
		(layer "B.Cu")
		(net "PWM_OUT_FAN1_NET")
	)
	(segment
		(start 5.449824 -364.732824)
		(end 5.449824 -377.69546)
		(width 0.254)
		(layer "B.Cu")
		(net "PWM_OUT_FAN1_NET")
	)
	(segment
		(start 19.116802 -294.097202)
		(end 19.116802 -337.803998)
		(width 0.254)
		(layer "B.Cu")
		(net "PWM_OUT_FAN1_NET")
	)
	(segment
		(start 5.449824 -377.69546)
		(end 3.586734 -379.55855)
		(width 0.254)
		(layer "B.Cu")
		(net "PWM_OUT_FAN1_NET")
	)
	(segment
		(start 4.475734 -363.758734)
		(end 5.449824 -364.732824)
		(width 0.254)
		(layer "B.Cu")
		(net "PWM_OUT_FAN1_NET")
	)
	(segment
		(start 4.475734 -352.445066)
		(end 4.475734 -363.758734)
		(width 0.254)
		(layer "B.Cu")
		(net "PWM_OUT_FAN1_NET")
	)
	(segment
		(start 16.4084 -227.9396)
		(end 16.4084 -224.2058)
		(width 0.254)
		(layer "B.Cu")
		(net "PWM_OUT_FAN1_NET")
	)
	(segment
		(start 4.216654 -449.510912)
		(end 9.951466 -455.245724)
		(width 0.254)
		(layer "B.Cu")
		(net "PWM_OUT_FAN1_NET")
	)
	(segment
		(start 26.2636 -211.415884)
		(end 26.2636 -212.9282)
		(width 0.254)
		(layer "F.Cu")
		(net "PWM_OUT_FAN6")
	)
	(segment
		(start 26.1366 -211.288884)
		(end 26.2636 -211.415884)
		(width 0.254)
		(layer "F.Cu")
		(net "PWM_OUT_FAN6")
	)
	(segment
		(start 26.025348 -215.985852)
		(end 24.901652 -215.985852)
		(width 0.254)
		(layer "F.Cu")
		(net "PWM_OUT_FAN6")
	)
	(segment
		(start 23.3172 -214.4014)
		(end 22.211284 -214.4014)
		(width 0.254)
		(layer "F.Cu")
		(net "PWM_OUT_FAN6")
	)
	(segment
		(start 24.901652 -215.985852)
		(end 23.3172 -214.4014)
		(width 0.254)
		(layer "F.Cu")
		(net "PWM_OUT_FAN6")
	)
	(segment
		(start 26.25852 -214.961216)
		(end 26.25852 -215.75268)
		(width 0.254)
		(layer "F.Cu")
		(net "PWM_OUT_FAN6")
	)
	(segment
		(start 26.25852 -212.93328)
		(end 26.25852 -214.961216)
		(width 0.254)
		(layer "F.Cu")
		(net "PWM_OUT_FAN6")
	)
	(segment
		(start 26.2636 -212.9282)
		(end 26.25852 -212.93328)
		(width 0.254)
		(layer "F.Cu")
		(net "PWM_OUT_FAN6")
	)
	(segment
		(start 26.25852 -215.75268)
		(end 26.025348 -215.985852)
		(width 0.254)
		(layer "F.Cu")
		(net "PWM_OUT_FAN6")
	)
	(via
		(at 26.2636 -212.9282)
		(size 0.7112)
		(drill 0.3556)
		(layers "F.Cu" "B.Cu")
		(net "PWM_OUT_FAN6")
	)
	(segment
		(start 27.559 -214.961216)
		(end 27.559 -213.80958)
		(width 0.254)
		(layer "F.Cu")
		(net "PWM_OUT_FAN5")
	)
	(segment
		(start 23.368 -215.519)
		(end 23.4696 -215.6206)
		(width 0.254)
		(layer "F.Cu")
		(net "PWM_OUT_FAN5")
	)
	(segment
		(start 27.559 -213.80958)
		(end 27.560016 -213.808564)
		(width 0.254)
		(layer "F.Cu")
		(net "PWM_OUT_FAN5")
	)
	(segment
		(start 27.559508 -213.266528)
		(end 27.559508 -211.967572)
		(width 0.254)
		(layer "F.Cu")
		(net "PWM_OUT_FAN5")
	)
	(segment
		(start 27.560016 -213.808564)
		(end 27.560016 -213.267036)
		(width 0.254)
		(layer "F.Cu")
		(net "PWM_OUT_FAN5")
	)
	(segment
		(start 28.1051 -211.4296)
		(end 28.2448 -211.2899)
		(width 0.254)
		(layer "F.Cu")
		(net "PWM_OUT_FAN5")
	)
	(segment
		(start 22.211284 -215.519)
		(end 23.368 -215.519)
		(width 0.254)
		(layer "F.Cu")
		(net "PWM_OUT_FAN5")
	)
	(segment
		(start 28.09748 -211.4296)
		(end 28.1051 -211.4296)
		(width 0.254)
		(layer "F.Cu")
		(net "PWM_OUT_FAN5")
	)
	(segment
		(start 27.559508 -211.967572)
		(end 28.09748 -211.4296)
		(width 0.254)
		(layer "F.Cu")
		(net "PWM_OUT_FAN5")
	)
	(segment
		(start 27.559 -215.9762)
		(end 27.559 -214.961216)
		(width 0.254)
		(layer "F.Cu")
		(net "PWM_OUT_FAN5")
	)
	(segment
		(start 26.990548 -216.544652)
		(end 27.559 -215.9762)
		(width 0.254)
		(layer "F.Cu")
		(net "PWM_OUT_FAN5")
	)
	(segment
		(start 27.560016 -213.267036)
		(end 27.559508 -213.266528)
		(width 0.254)
		(layer "F.Cu")
		(net "PWM_OUT_FAN5")
	)
	(segment
		(start 24.393652 -216.544652)
		(end 26.990548 -216.544652)
		(width 0.254)
		(layer "F.Cu")
		(net "PWM_OUT_FAN5")
	)
	(segment
		(start 23.4696 -215.6206)
		(end 24.393652 -216.544652)
		(width 0.254)
		(layer "F.Cu")
		(net "PWM_OUT_FAN5")
	)
	(via
		(at 23.4696 -215.6206)
		(size 0.7112)
		(drill 0.3556)
		(layers "F.Cu" "B.Cu")
		(net "PWM_OUT_FAN5")
	)
	(segment
		(start 29.50845 -223.06915)
		(end 29.50845 -220.600016)
		(width 0.254)
		(layer "F.Cu")
		(net "PWM_OUT_FAN3")
	)
	(segment
		(start 22.2123 -217.7288)
		(end 23.3172 -217.7288)
		(width 0.254)
		(layer "F.Cu")
		(net "PWM_OUT_FAN3")
	)
	(segment
		(start 30.3022 -223.8629)
		(end 29.50845 -223.06915)
		(width 0.254)
		(layer "F.Cu")
		(net "PWM_OUT_FAN3")
	)
	(segment
		(start 23.840948 -217.662252)
		(end 23.5458 -217.9574)
		(width 0.254)
		(layer "F.Cu")
		(net "PWM_OUT_FAN3")
	)
	(segment
		(start 23.3172 -217.7288)
		(end 23.5458 -217.9574)
		(width 0.254)
		(layer "F.Cu")
		(net "PWM_OUT_FAN3")
	)
	(segment
		(start 29.50845 -220.600016)
		(end 29.50845 -218.78925)
		(width 0.254)
		(layer "F.Cu")
		(net "PWM_OUT_FAN3")
	)
	(segment
		(start 29.50845 -218.78925)
		(end 28.381452 -217.662252)
		(width 0.254)
		(layer "F.Cu")
		(net "PWM_OUT_FAN3")
	)
	(segment
		(start 28.381452 -217.662252)
		(end 23.840948 -217.662252)
		(width 0.254)
		(layer "F.Cu")
		(net "PWM_OUT_FAN3")
	)
	(via
		(at 23.5458 -217.9574)
		(size 0.7112)
		(drill 0.3556)
		(layers "F.Cu" "B.Cu")
		(net "PWM_OUT_FAN3")
	)
	(segment
		(start 28.85948 -216.47912)
		(end 28.85948 -214.961216)
		(width 0.254)
		(layer "F.Cu")
		(net "PWM_OUT_FAN4")
	)
	(segment
		(start 23.911052 -217.103452)
		(end 28.285948 -217.103452)
		(width 0.254)
		(layer "F.Cu")
		(net "PWM_OUT_FAN4")
	)
	(segment
		(start 30.3022 -212.598)
		(end 30.3784 -212.5218)
		(width 0.254)
		(layer "F.Cu")
		(net "PWM_OUT_FAN4")
	)
	(segment
		(start 22.211284 -216.6366)
		(end 23.4442 -216.6366)
		(width 0.254)
		(layer "F.Cu")
		(net "PWM_OUT_FAN4")
	)
	(segment
		(start 30.3784 -212.5218)
		(end 30.3784 -211.2899)
		(width 0.254)
		(layer "F.Cu")
		(net "PWM_OUT_FAN4")
	)
	(segment
		(start 28.8544 -216.4842)
		(end 28.85948 -216.47912)
		(width 0.254)
		(layer "F.Cu")
		(net "PWM_OUT_FAN4")
	)
	(segment
		(start 28.85948 -213.40572)
		(end 29.6672 -212.598)
		(width 0.254)
		(layer "F.Cu")
		(net "PWM_OUT_FAN4")
	)
	(segment
		(start 29.6672 -212.598)
		(end 30.3022 -212.598)
		(width 0.254)
		(layer "F.Cu")
		(net "PWM_OUT_FAN4")
	)
	(segment
		(start 28.285948 -217.103452)
		(end 28.8544 -216.535)
		(width 0.254)
		(layer "F.Cu")
		(net "PWM_OUT_FAN4")
	)
	(segment
		(start 28.85948 -214.961216)
		(end 28.85948 -213.40572)
		(width 0.254)
		(layer "F.Cu")
		(net "PWM_OUT_FAN4")
	)
	(segment
		(start 28.8544 -216.535)
		(end 28.8544 -216.4842)
		(width 0.254)
		(layer "F.Cu")
		(net "PWM_OUT_FAN4")
	)
	(segment
		(start 23.4442 -216.6366)
		(end 23.911052 -217.103452)
		(width 0.254)
		(layer "F.Cu")
		(net "PWM_OUT_FAN4")
	)
	(via
		(at 30.3022 -212.598)
		(size 0.7112)
		(drill 0.3556)
		(layers "F.Cu" "B.Cu")
		(net "PWM_OUT_FAN4")
	)
	(segment
		(start 23.8506 -218.694)
		(end 22.3393 -218.694)
		(width 0.254)
		(layer "F.Cu")
		(net "PWM_OUT_FAN2")
	)
	(segment
		(start 27.174698 -218.221052)
		(end 24.323548 -218.221052)
		(width 0.254)
		(layer "F.Cu")
		(net "PWM_OUT_FAN2")
	)
	(segment
		(start 28.20924 -222.69196)
		(end 28.2194 -222.6818)
		(width 0.254)
		(layer "F.Cu")
		(net "PWM_OUT_FAN2")
	)
	(segment
		(start 28.2194 -222.6818)
		(end 28.20924 -222.67164)
		(width 0.254)
		(layer "F.Cu")
		(net "PWM_OUT_FAN2")
	)
	(segment
		(start 28.20924 -223.82226)
		(end 28.20924 -222.69196)
		(width 0.254)
		(layer "F.Cu")
		(net "PWM_OUT_FAN2")
	)
	(segment
		(start 28.20924 -219.255594)
		(end 27.174698 -218.221052)
		(width 0.254)
		(layer "F.Cu")
		(net "PWM_OUT_FAN2")
	)
	(segment
		(start 28.20924 -220.600016)
		(end 28.20924 -219.255594)
		(width 0.254)
		(layer "F.Cu")
		(net "PWM_OUT_FAN2")
	)
	(segment
		(start 24.323548 -218.221052)
		(end 23.8506 -218.694)
		(width 0.254)
		(layer "F.Cu")
		(net "PWM_OUT_FAN2")
	)
	(segment
		(start 22.3393 -218.694)
		(end 22.2123 -218.821)
		(width 0.254)
		(layer "F.Cu")
		(net "PWM_OUT_FAN2")
	)
	(segment
		(start 28.1686 -223.8629)
		(end 28.20924 -223.82226)
		(width 0.254)
		(layer "F.Cu")
		(net "PWM_OUT_FAN2")
	)
	(segment
		(start 28.20924 -222.67164)
		(end 28.20924 -220.600016)
		(width 0.254)
		(layer "F.Cu")
		(net "PWM_OUT_FAN2")
	)
	(via
		(at 28.2194 -222.6818)
		(size 0.7112)
		(drill 0.3556)
		(layers "F.Cu" "B.Cu")
		(net "PWM_OUT_FAN2")
	)
	(segment
		(start 26.90876 -219.483432)
		(end 26.20518 -218.779852)
		(width 0.254)
		(layer "F.Cu")
		(net "PWM_OUT_FAN1")
	)
	(segment
		(start 22.2123 -219.8878)
		(end 23.4696 -219.8878)
		(width 0.254)
		(layer "F.Cu")
		(net "PWM_OUT_FAN1")
	)
	(segment
		(start 26.30551 -222.62211)
		(end 26.90876 -222.01886)
		(width 0.254)
		(layer "F.Cu")
		(net "PWM_OUT_FAN1")
	)
	(segment
		(start 26.90876 -220.600016)
		(end 26.90876 -219.483432)
		(width 0.254)
		(layer "F.Cu")
		(net "PWM_OUT_FAN1")
	)
	(segment
		(start 26.90876 -222.01886)
		(end 26.90876 -220.600016)
		(width 0.254)
		(layer "F.Cu")
		(net "PWM_OUT_FAN1")
	)
	(segment
		(start 26.0604 -223.8629)
		(end 26.30551 -223.61779)
		(width 0.254)
		(layer "F.Cu")
		(net "PWM_OUT_FAN1")
	)
	(segment
		(start 26.20518 -218.779852)
		(end 24.577548 -218.779852)
		(width 0.254)
		(layer "F.Cu")
		(net "PWM_OUT_FAN1")
	)
	(segment
		(start 23.4696 -219.8878)
		(end 23.5712 -219.7862)
		(width 0.254)
		(layer "F.Cu")
		(net "PWM_OUT_FAN1")
	)
	(segment
		(start 26.30551 -223.61779)
		(end 26.30551 -222.62211)
		(width 0.254)
		(layer "F.Cu")
		(net "PWM_OUT_FAN1")
	)
	(segment
		(start 24.577548 -218.779852)
		(end 23.5712 -219.7862)
		(width 0.254)
		(layer "F.Cu")
		(net "PWM_OUT_FAN1")
	)
	(via
		(at 23.5712 -219.7862)
		(size 0.7112)
		(drill 0.3556)
		(layers "F.Cu" "B.Cu")
		(net "PWM_OUT_FAN1")
	)
	(segment
		(start 36.83508 -251.83592)
		(end 36.068 -252.603)
		(width 0.1397)
		(layer "F.Cu")
		(net "LED_DRV_RST")
	)
	(segment
		(start 36.83508 -249.3518)
		(end 36.83508 -251.83592)
		(width 0.1397)
		(layer "F.Cu")
		(net "LED_DRV_RST")
	)
	(segment
		(start 36.5252 -253.9365)
		(end 36.5252 -253.0602)
		(width 0.1397)
		(layer "F.Cu")
		(net "LED_DRV_RST")
	)
	(segment
		(start 36.5252 -253.0602)
		(end 36.068 -252.603)
		(width 0.1397)
		(layer "F.Cu")
		(net "LED_DRV_RST")
	)
	(segment
		(start 36.822126 -363.161326)
		(end 38.481 -364.8202)
		(width 0.254)
		(layer "F.Cu")
		(net "ADM1276_LATCH_B")
	)
	(segment
		(start 40.005 -370.2685)
		(end 39.9415 -370.332)
		(width 0.254)
		(layer "F.Cu")
		(net "ADM1276_LATCH_B")
	)
	(segment
		(start 40.767 -371.475)
		(end 40.767 -371.1575)
		(width 0.254)
		(layer "F.Cu")
		(net "ADM1276_LATCH_B")
	)
	(segment
		(start 38.44925 -366.9665)
		(end 38.481 -366.93475)
		(width 0.254)
		(layer "F.Cu")
		(net "ADM1276_LATCH_B")
	)
	(segment
		(start 38.481 -366.93475)
		(end 38.481 -365.379)
		(width 0.254)
		(layer "F.Cu")
		(net "ADM1276_LATCH_B")
	)
	(segment
		(start 40.767 -371.1575)
		(end 39.9415 -370.332)
		(width 0.254)
		(layer "F.Cu")
		(net "ADM1276_LATCH_B")
	)
	(segment
		(start 38.481 -364.8202)
		(end 38.481 -365.379)
		(width 0.254)
		(layer "F.Cu")
		(net "ADM1276_LATCH_B")
	)
	(segment
		(start 36.212526 -363.161326)
		(end 36.822126 -363.161326)
		(width 0.254)
		(layer "F.Cu")
		(net "ADM1276_LATCH_B")
	)
	(segment
		(start 40.005 -369.5192)
		(end 40.005 -370.2685)
		(width 0.254)
		(layer "F.Cu")
		(net "ADM1276_LATCH_B")
	)
	(via
		(at 38.481 -365.379)
		(size 0.5588)
		(drill 0.3048)
		(layers "F.Cu" "B.Cu")
		(net "ADM1276_LATCH_B")
	)
	(via
		(at 39.624 -367.665)
		(size 0.7112)
		(drill 0.3556)
		(layers "F.Cu" "B.Cu")
		(net "ADM1276_LATCH_B")
	)
	(via
		(at 40.005 -369.5192)
		(size 0.5588)
		(drill 0.3048)
		(layers "F.Cu" "B.Cu")
		(net "ADM1276_LATCH_B")
	)
	(segment
		(start 40.005 -369.5192)
		(end 40.005 -368.046)
		(width 0.254)
		(layer "B.Cu")
		(net "ADM1276_LATCH_B")
	)
	(segment
		(start 39.624 -366.522)
		(end 39.624 -367.665)
		(width 0.254)
		(layer "B.Cu")
		(net "ADM1276_LATCH_B")
	)
	(segment
		(start 38.481 -365.379)
		(end 39.624 -366.522)
		(width 0.254)
		(layer "B.Cu")
		(net "ADM1276_LATCH_B")
	)
	(segment
		(start 40.005 -368.046)
		(end 39.624 -367.665)
		(width 0.254)
		(layer "B.Cu")
		(net "ADM1276_LATCH_B")
	)
	(segment
		(start 36.703 -367.479326)
		(end 37.904674 -368.681)
		(width 0.254)
		(layer "F.Cu")
		(net "ADM1276_EN_NET")
	)
	(segment
		(start 36.48075 -366.9665)
		(end 36.703 -367.18875)
		(width 0.254)
		(layer "F.Cu")
		(net "ADM1276_EN_NET")
	)
	(segment
		(start 40.135048 -368.8588)
		(end 40.64 -369.363752)
		(width 0.254)
		(layer "F.Cu")
		(net "ADM1276_EN_NET")
	)
	(segment
		(start 34.925 -367.792)
		(end 35.052 -367.919)
		(width 0.254)
		(layer "F.Cu")
		(net "ADM1276_EN_NET")
	)
	(segment
		(start 40.64 -369.363752)
		(end 40.64 -369.6335)
		(width 0.254)
		(layer "F.Cu")
		(net "ADM1276_EN_NET")
	)
	(segment
		(start 34.925 -366.7125)
		(end 34.925 -367.792)
		(width 0.254)
		(layer "F.Cu")
		(net "ADM1276_EN_NET")
	)
	(segment
		(start 36.703 -367.18875)
		(end 36.703 -367.479326)
		(width 0.254)
		(layer "F.Cu")
		(net "ADM1276_EN_NET")
	)
	(segment
		(start 40.8305 -369.824)
		(end 40.8305 -370.332)
		(width 0.254)
		(layer "F.Cu")
		(net "ADM1276_EN_NET")
	)
	(segment
		(start 36.48075 -366.9665)
		(end 36.0045 -366.9665)
		(width 0.254)
		(layer "F.Cu")
		(net "ADM1276_EN_NET")
	)
	(segment
		(start 40.8305 -370.332)
		(end 42.3418 -370.332)
		(width 0.254)
		(layer "F.Cu")
		(net "ADM1276_EN_NET")
	)
	(segment
		(start 37.904674 -368.681)
		(end 38.800024 -368.681)
		(width 0.254)
		(layer "F.Cu")
		(net "ADM1276_EN_NET")
	)
	(segment
		(start 42.3418 -370.332)
		(end 42.418 -370.2558)
		(width 0.254)
		(layer "F.Cu")
		(net "ADM1276_EN_NET")
	)
	(segment
		(start 38.977824 -368.8588)
		(end 40.135048 -368.8588)
		(width 0.254)
		(layer "F.Cu")
		(net "ADM1276_EN_NET")
	)
	(segment
		(start 40.64 -369.6335)
		(end 40.8305 -369.824)
		(width 0.254)
		(layer "F.Cu")
		(net "ADM1276_EN_NET")
	)
	(segment
		(start 36.0045 -366.9665)
		(end 35.052 -367.919)
		(width 0.254)
		(layer "F.Cu")
		(net "ADM1276_EN_NET")
	)
	(segment
		(start 38.800024 -368.681)
		(end 38.977824 -368.8588)
		(width 0.254)
		(layer "F.Cu")
		(net "ADM1276_EN_NET")
	)
	(via
		(at 35.052 -367.919)
		(size 0.7112)
		(drill 0.3556)
		(layers "F.Cu" "B.Cu")
		(net "ADM1276_EN_NET")
	)
	(segment
		(start 42.765726 -368.4524)
		(end 43.019726 -368.1984)
		(width 0.1397)
		(layer "F.Cu")
		(net "TEMP_ALM#_REVERSE")
	)
	(segment
		(start 40.767 -367.665)
		(end 41.5544 -368.4524)
		(width 0.1397)
		(layer "F.Cu")
		(net "TEMP_ALM#_REVERSE")
	)
	(segment
		(start 40.2844 -367.386616)
		(end 40.562784 -367.665)
		(width 0.1397)
		(layer "F.Cu")
		(net "TEMP_ALM#_REVERSE")
	)
	(segment
		(start 43.019726 -368.1984)
		(end 43.019726 -367.022126)
		(width 0.1397)
		(layer "F.Cu")
		(net "TEMP_ALM#_REVERSE")
	)
	(segment
		(start 40.866314 -366.804702)
		(end 40.2844 -367.386616)
		(width 0.1397)
		(layer "F.Cu")
		(net "TEMP_ALM#_REVERSE")
	)
	(segment
		(start 42.037 -368.4524)
		(end 42.765726 -368.4524)
		(width 0.1397)
		(layer "F.Cu")
		(net "TEMP_ALM#_REVERSE")
	)
	(segment
		(start 40.562784 -367.665)
		(end 40.767 -367.665)
		(width 0.1397)
		(layer "F.Cu")
		(net "TEMP_ALM#_REVERSE")
	)
	(segment
		(start 38.692074 -363.507274)
		(end 39.784274 -363.507274)
		(width 0.1397)
		(layer "F.Cu")
		(net "TEMP_ALM#_REVERSE")
	)
	(segment
		(start 39.784274 -363.507274)
		(end 40.866314 -364.589314)
		(width 0.1397)
		(layer "F.Cu")
		(net "TEMP_ALM#_REVERSE")
	)
	(segment
		(start 41.5544 -368.4524)
		(end 42.037 -368.4524)
		(width 0.1397)
		(layer "F.Cu")
		(net "TEMP_ALM#_REVERSE")
	)
	(segment
		(start 40.866314 -364.589314)
		(end 40.866314 -366.804702)
		(width 0.1397)
		(layer "F.Cu")
		(net "TEMP_ALM#_REVERSE")
	)
	(via
		(at 42.037 -368.4524)
		(size 0.7112)
		(drill 0.3556)
		(layers "F.Cu" "B.Cu")
		(net "TEMP_ALM#_REVERSE")
	)
	(segment
		(start 8.288528 -67.243706)
		(end 7.0866 -68.445634)
		(width 0.1397)
		(layer "F.Cu")
		(net "LED_DR_LED5_B")
	)
	(segment
		(start 6.977634 -66.688462)
		(end 6.977634 -68.336668)
		(width 0.1397)
		(layer "F.Cu")
		(net "LED_DR_LED5_B")
	)
	(segment
		(start 6.977634 -68.336668)
		(end 7.0866 -68.445634)
		(width 0.1397)
		(layer "F.Cu")
		(net "LED_DR_LED5_B")
	)
	(segment
		(start 8.288528 -67.111118)
		(end 8.288528 -67.243706)
		(width 0.1397)
		(layer "F.Cu")
		(net "LED_DR_LED5_B")
	)
	(via
		(at 7.0866 -68.445634)
		(size 0.7112)
		(drill 0.3556)
		(layers "F.Cu" "B.Cu")
		(net "LED_DR_LED5_B")
	)
	(segment
		(start 5.08254 -76.957428)
		(end 5.087112 -76.962)
		(width 0.1397)
		(layer "F.Cu")
		(net "LED_DR_LED4_B")
	)
	(segment
		(start 5.087112 -76.962)
		(end 5.73405 -76.962)
		(width 0.1397)
		(layer "F.Cu")
		(net "LED_DR_LED4_B")
	)
	(segment
		(start 4.897882 -78.036928)
		(end 4.897882 -77.142086)
		(width 0.1397)
		(layer "F.Cu")
		(net "LED_DR_LED4_B")
	)
	(segment
		(start 4.897882 -77.142086)
		(end 5.08254 -76.957428)
		(width 0.1397)
		(layer "F.Cu")
		(net "LED_DR_LED4_B")
	)
	(segment
		(start 5.73405 -76.962)
		(end 6.33095 -77.5589)
		(width 0.1397)
		(layer "F.Cu")
		(net "LED_DR_LED4_B")
	)
	(via
		(at 5.08254 -76.957428)
		(size 0.7112)
		(drill 0.3556)
		(layers "F.Cu" "B.Cu")
		(net "LED_DR_LED4_B")
	)
	(segment
		(start 14.907768 -231.106472)
		(end 15.03934 -230.9749)
		(width 0.1397)
		(layer "F.Cu")
		(net "LED_DR_LED3_B")
	)
	(segment
		(start 16.2814 -230.9749)
		(end 16.2814 -229.8192)
		(width 0.1397)
		(layer "F.Cu")
		(net "LED_DR_LED3_B")
	)
	(segment
		(start 15.03934 -230.9749)
		(end 16.2814 -230.9749)
		(width 0.1397)
		(layer "F.Cu")
		(net "LED_DR_LED3_B")
	)
	(via
		(at 16.2814 -229.8192)
		(size 0.7112)
		(drill 0.3556)
		(layers "F.Cu" "B.Cu")
		(net "LED_DR_LED3_B")
	)
	(segment
		(start 9.6393 -277.4823)
		(end 9.4488 -277.2918)
		(width 0.1397)
		(layer "F.Cu")
		(net "LED_DR_LED2_B")
	)
	(segment
		(start 8.815832 -276.658832)
		(end 9.4488 -277.2918)
		(width 0.1397)
		(layer "F.Cu")
		(net "LED_DR_LED2_B")
	)
	(segment
		(start 9.6393 -278.384)
		(end 9.6393 -277.4823)
		(width 0.1397)
		(layer "F.Cu")
		(net "LED_DR_LED2_B")
	)
	(segment
		(start 8.094472 -276.658832)
		(end 8.815832 -276.658832)
		(width 0.1397)
		(layer "F.Cu")
		(net "LED_DR_LED2_B")
	)
	(via
		(at 9.4488 -277.2918)
		(size 0.7112)
		(drill 0.3556)
		(layers "F.Cu" "B.Cu")
		(net "LED_DR_LED2_B")
	)
	(segment
		(start 8.98525 -418.8587)
		(end 8.98525 -420.07155)
		(width 0.1397)
		(layer "F.Cu")
		(net "LED_DR_LED1_B")
	)
	(segment
		(start 8.98525 -420.07155)
		(end 8.3566 -420.7002)
		(width 0.1397)
		(layer "F.Cu")
		(net "LED_DR_LED1_B")
	)
	(segment
		(start 8.3566 -420.7002)
		(end 8.3566 -421.8305)
		(width 0.1397)
		(layer "F.Cu")
		(net "LED_DR_LED1_B")
	)
	(via
		(at 8.3566 -420.7002)
		(size 0.7112)
		(drill 0.3556)
		(layers "F.Cu" "B.Cu")
		(net "LED_DR_LED1_B")
	)
	(segment
		(start 7.459472 -435.576472)
		(end 6.932168 -435.576472)
		(width 0.1397)
		(layer "F.Cu")
		(net "LED_DR_LED0_B")
	)
	(segment
		(start 8.382 -436.499)
		(end 7.459472 -435.576472)
		(width 0.1397)
		(layer "F.Cu")
		(net "LED_DR_LED0_B")
	)
	(segment
		(start 6.932168 -435.576472)
		(end 6.535928 -435.576472)
		(width 0.1397)
		(layer "F.Cu")
		(net "LED_DR_LED0_B")
	)
	(segment
		(start 6.535928 -435.576472)
		(end 5.5499 -436.5625)
		(width 0.1397)
		(layer "F.Cu")
		(net "LED_DR_LED0_B")
	)
	(segment
		(start 5.5499 -436.5625)
		(end 5.5499 -437.0578)
		(width 0.1397)
		(layer "F.Cu")
		(net "LED_DR_LED0_B")
	)
	(via
		(at 8.382 -436.499)
		(size 0.7112)
		(drill 0.3556)
		(layers "F.Cu" "B.Cu")
		(net "LED_DR_LED0_B")
	)
	(segment
		(start 7.949946 -88.535002)
		(end 9.623298 -88.535002)
		(width 0.1397)
		(layer "F.Cu")
		(net "LED_DR_LED4_K")
	)
	(segment
		(start 9.623298 -88.535002)
		(end 9.9568 -88.2015)
		(width 0.1397)
		(layer "F.Cu")
		(net "LED_DR_LED4_K")
	)
	(segment
		(start 6.0325 -56.0705)
		(end 6.0325 -59.6265)
		(width 0.1397)
		(layer "F.Cu")
		(net "LED_DR_LED5_BLUE")
	)
	(segment
		(start 8.3058 -64.3763)
		(end 6.400546 -64.3763)
		(width 0.1397)
		(layer "F.Cu")
		(net "LED_DR_LED5_BLUE")
	)
	(segment
		(start 8.3058 -63.9318)
		(end 7.0866 -62.7126)
		(width 0.1397)
		(layer "F.Cu")
		(net "LED_DR_LED5_BLUE")
	)
	(segment
		(start 6.400546 -64.3763)
		(end 5.993384 -64.783462)
		(width 0.1397)
		(layer "F.Cu")
		(net "LED_DR_LED5_BLUE")
	)
	(segment
		(start 7.0866 -60.6806)
		(end 7.0866 -62.7126)
		(width 0.1397)
		(layer "F.Cu")
		(net "LED_DR_LED5_BLUE")
	)
	(segment
		(start 7.949946 -54.153054)
		(end 6.0325 -56.0705)
		(width 0.1397)
		(layer "F.Cu")
		(net "LED_DR_LED5_BLUE")
	)
	(segment
		(start 6.0325 -59.6265)
		(end 7.0866 -60.6806)
		(width 0.1397)
		(layer "F.Cu")
		(net "LED_DR_LED5_BLUE")
	)
	(segment
		(start 8.3058 -64.3763)
		(end 8.3058 -63.9318)
		(width 0.1397)
		(layer "F.Cu")
		(net "LED_DR_LED5_BLUE")
	)
	(segment
		(start 7.949946 -53.559964)
		(end 7.949946 -54.153054)
		(width 0.1397)
		(layer "F.Cu")
		(net "LED_DR_LED5_BLUE")
	)
	(segment
		(start 8.5344 -81.6102)
		(end 9.1948 -80.9498)
		(width 0.1397)
		(layer "F.Cu")
		(net "LED_DR_LED4_BLUE")
	)
	(segment
		(start 9.2202 -84.724748)
		(end 7.949946 -85.995002)
		(width 0.1397)
		(layer "F.Cu")
		(net "LED_DR_LED4_BLUE")
	)
	(segment
		(start 8.2677 -81.6102)
		(end 8.5344 -81.6102)
		(width 0.1397)
		(layer "F.Cu")
		(net "LED_DR_LED4_BLUE")
	)
	(segment
		(start 9.1948 -80.9498)
		(end 9.1313 -80.8863)
		(width 0.1397)
		(layer "F.Cu")
		(net "LED_DR_LED4_BLUE")
	)
	(segment
		(start 7.3152 -79.8703)
		(end 7.3152 -79.4639)
		(width 0.1397)
		(layer "F.Cu")
		(net "LED_DR_LED4_BLUE")
	)
	(segment
		(start 9.1313 -80.8863)
		(end 8.3312 -80.8863)
		(width 0.1397)
		(layer "F.Cu")
		(net "LED_DR_LED4_BLUE")
	)
	(segment
		(start 9.2202 -82.5627)
		(end 8.2677 -81.6102)
		(width 0.1397)
		(layer "F.Cu")
		(net "LED_DR_LED4_BLUE")
	)
	(segment
		(start 9.2202 -83.439)
		(end 9.2202 -84.724748)
		(width 0.1397)
		(layer "F.Cu")
		(net "LED_DR_LED4_BLUE")
	)
	(segment
		(start 8.3312 -80.8863)
		(end 7.3152 -79.8703)
		(width 0.1397)
		(layer "F.Cu")
		(net "LED_DR_LED4_BLUE")
	)
	(segment
		(start 9.2202 -83.439)
		(end 9.2202 -82.5627)
		(width 0.1397)
		(layer "F.Cu")
		(net "LED_DR_LED4_BLUE")
	)
	(via
		(at 9.1948 -80.9498)
		(size 0.7112)
		(drill 0.3556)
		(layers "F.Cu" "B.Cu")
		(net "LED_DR_LED4_BLUE")
	)
	(segment
		(start 13.923518 -228.528118)
		(end 12.6746 -227.2792)
		(width 0.1397)
		(layer "F.Cu")
		(net "LED_DR_LED3_BLUE")
	)
	(segment
		(start 13.923518 -229.201472)
		(end 13.923518 -228.528118)
		(width 0.1397)
		(layer "F.Cu")
		(net "LED_DR_LED3_BLUE")
	)
	(segment
		(start 16.7386 -228.6)
		(end 14.605 -228.6)
		(width 0.1397)
		(layer "F.Cu")
		(net "LED_DR_LED3_BLUE")
	)
	(segment
		(start 14.605 -228.6)
		(end 14.003528 -229.201472)
		(width 0.1397)
		(layer "F.Cu")
		(net "LED_DR_LED3_BLUE")
	)
	(segment
		(start 12.3317 -227.6221)
		(end 12.6746 -227.2792)
		(width 0.1397)
		(layer "F.Cu")
		(net "LED_DR_LED3_BLUE")
	)
	(segment
		(start 11.0236 -227.6221)
		(end 12.3317 -227.6221)
		(width 0.1397)
		(layer "F.Cu")
		(net "LED_DR_LED3_BLUE")
	)
	(segment
		(start 9.922764 -227.6221)
		(end 7.949946 -229.594918)
		(width 0.1397)
		(layer "F.Cu")
		(net "LED_DR_LED3_BLUE")
	)
	(segment
		(start 11.0236 -227.6221)
		(end 9.922764 -227.6221)
		(width 0.1397)
		(layer "F.Cu")
		(net "LED_DR_LED3_BLUE")
	)
	(segment
		(start 14.003528 -229.201472)
		(end 13.923518 -229.201472)
		(width 0.1397)
		(layer "F.Cu")
		(net "LED_DR_LED3_BLUE")
	)
	(via
		(at 16.7386 -228.6)
		(size 0.7112)
		(drill 0.3556)
		(layers "F.Cu" "B.Cu")
		(net "LED_DR_LED3_BLUE")
	)
	(segment
		(start 6.1595 -280.924)
		(end 6.1595 -279.9715)
		(width 0.1397)
		(layer "F.Cu")
		(net "LED_DR_LED2_BLUE")
	)
	(segment
		(start 7.949946 -265.325098)
		(end 7.949946 -266.427204)
		(width 0.1397)
		(layer "F.Cu")
		(net "LED_DR_LED2_BLUE")
	)
	(segment
		(start 7.949946 -266.427204)
		(end 5.7531 -268.62405)
		(width 0.1397)
		(layer "F.Cu")
		(net "LED_DR_LED2_BLUE")
	)
	(segment
		(start 5.7531 -277.20671)
		(end 6.189472 -277.643082)
		(width 0.1397)
		(layer "F.Cu")
		(net "LED_DR_LED2_BLUE")
	)
	(segment
		(start 5.7531 -268.62405)
		(end 5.7531 -277.20671)
		(width 0.1397)
		(layer "F.Cu")
		(net "LED_DR_LED2_BLUE")
	)
	(segment
		(start 6.223 -279.908)
		(end 6.189472 -279.874472)
		(width 0.1397)
		(layer "F.Cu")
		(net "LED_DR_LED2_BLUE")
	)
	(segment
		(start 9.906 -262.509)
		(end 9.906 -263.369044)
		(width 0.1397)
		(layer "F.Cu")
		(net "LED_DR_LED2_BLUE")
	)
	(segment
		(start 9.906 -263.369044)
		(end 7.949946 -265.325098)
		(width 0.1397)
		(layer "F.Cu")
		(net "LED_DR_LED2_BLUE")
	)
	(segment
		(start 6.189472 -279.874472)
		(end 6.189472 -277.643082)
		(width 0.1397)
		(layer "F.Cu")
		(net "LED_DR_LED2_BLUE")
	)
	(segment
		(start 6.1595 -279.9715)
		(end 6.223 -279.908)
		(width 0.1397)
		(layer "F.Cu")
		(net "LED_DR_LED2_BLUE")
	)
	(via
		(at 6.223 -279.908)
		(size 0.7112)
		(drill 0.3556)
		(layers "F.Cu" "B.Cu")
		(net "LED_DR_LED2_BLUE")
	)
	(segment
		(start 6.9088 -420.9034)
		(end 5.6007 -419.5953)
		(width 0.1397)
		(layer "F.Cu")
		(net "LED_DR_LED1_BLUE")
	)
	(segment
		(start 8.781796 -409.756864)
		(end 8.781796 -411.809692)
		(width 0.1397)
		(layer "F.Cu")
		(net "LED_DR_LED1_BLUE")
	)
	(segment
		(start 7.118096 -415.296096)
		(end 8.001 -416.179)
		(width 0.1397)
		(layer "F.Cu")
		(net "LED_DR_LED1_BLUE")
	)
	(segment
		(start 8.001 -416.179)
		(end 8.001 -416.9537)
		(width 0.1397)
		(layer "F.Cu")
		(net "LED_DR_LED1_BLUE")
	)
	(segment
		(start 8.001 -416.9537)
		(end 6.7183 -416.9537)
		(width 0.1397)
		(layer "F.Cu")
		(net "LED_DR_LED1_BLUE")
	)
	(segment
		(start 6.7183 -416.9537)
		(end 6.0198 -417.6522)
		(width 0.1397)
		(layer "F.Cu")
		(net "LED_DR_LED1_BLUE")
	)
	(segment
		(start 7.118096 -413.473392)
		(end 7.118096 -415.296096)
		(width 0.1397)
		(layer "F.Cu")
		(net "LED_DR_LED1_BLUE")
	)
	(segment
		(start 7.949946 -408.925014)
		(end 8.781796 -409.756864)
		(width 0.1397)
		(layer "F.Cu")
		(net "LED_DR_LED1_BLUE")
	)
	(segment
		(start 8.781796 -411.809692)
		(end 7.118096 -413.473392)
		(width 0.1397)
		(layer "F.Cu")
		(net "LED_DR_LED1_BLUE")
	)
	(segment
		(start 5.6007 -419.5953)
		(end 5.6007 -417.6522)
		(width 0.1397)
		(layer "F.Cu")
		(net "LED_DR_LED1_BLUE")
	)
	(segment
		(start 6.0198 -417.6522)
		(end 5.6007 -417.6522)
		(width 0.1397)
		(layer "F.Cu")
		(net "LED_DR_LED1_BLUE")
	)
	(segment
		(start 44.01947 -173.7868)
		(end 45.0088 -174.77613)
		(width 0.254)
		(layer "F.Cu")
		(net "ADM1276_EN")
	)
	(segment
		(start 44.5135 -176.53)
		(end 44.5135 -178.0794)
		(width 0.254)
		(layer "F.Cu")
		(net "ADM1276_EN")
	)
	(segment
		(start 33.318196 -358.8258)
		(end 32.574484 -358.8258)
		(width 0.254)
		(layer "F.Cu")
		(net "ADM1276_EN")
	)
	(segment
		(start 40.6146 -173.7868)
		(end 44.01947 -173.7868)
		(width 0.254)
		(layer "F.Cu")
		(net "ADM1276_EN")
	)
	(segment
		(start 45.0088 -174.77613)
		(end 45.0088 -176.0347)
		(width 0.254)
		(layer "F.Cu")
		(net "ADM1276_EN")
	)
	(segment
		(start 32.574484 -358.8258)
		(end 31.75 -358.001316)
		(width 0.254)
		(layer "F.Cu")
		(net "ADM1276_EN")
	)
	(segment
		(start 28.7401 -362.1786)
		(end 28.7401 -363.5629)
		(width 0.254)
		(layer "F.Cu")
		(net "ADM1276_EN")
	)
	(segment
		(start 29.718 -364.5408)
		(end 29.718 -366.3696)
		(width 0.254)
		(layer "F.Cu")
		(net "ADM1276_EN")
	)
	(segment
		(start 28.7401 -361.0864)
		(end 28.7401 -362.1786)
		(width 0.254)
		(layer "F.Cu")
		(net "ADM1276_EN")
	)
	(segment
		(start 34.098992 -365.8235)
		(end 34.925 -365.8235)
		(width 0.254)
		(layer "F.Cu")
		(net "ADM1276_EN")
	)
	(segment
		(start 45.0088 -176.0347)
		(end 44.5135 -176.53)
		(width 0.254)
		(layer "F.Cu")
		(net "ADM1276_EN")
	)
	(segment
		(start 39.4208 -172.593)
		(end 40.6146 -173.7868)
		(width 0.254)
		(layer "F.Cu")
		(net "ADM1276_EN")
	)
	(segment
		(start 28.7401 -363.5629)
		(end 29.718 -364.5408)
		(width 0.254)
		(layer "F.Cu")
		(net "ADM1276_EN")
	)
	(segment
		(start 33.984946 -365.937546)
		(end 34.098992 -365.8235)
		(width 0.254)
		(layer "F.Cu")
		(net "ADM1276_EN")
	)
	(via
		(at 33.318196 -358.8258)
		(size 0.5588)
		(drill 0.3048)
		(layers "F.Cu" "B.Cu")
		(net "ADM1276_EN")
	)
	(via
		(at 33.984946 -365.937546)
		(size 0.7112)
		(drill 0.4064)
		(layers "F.Cu" "B.Cu")
		(net "ADM1276_EN")
	)
	(via
		(at 39.4208 -172.593)
		(size 0.5588)
		(drill 0.3048)
		(layers "F.Cu" "B.Cu")
		(net "ADM1276_EN")
	)
	(via
		(at 29.718 -364.5408)
		(size 0.7112)
		(drill 0.4064)
		(layers "F.Cu" "B.Cu")
		(net "ADM1276_EN")
	)
	(via
		(at 31.115 -365.127286)
		(size 0.7112)
		(drill 0.3556)
		(layers "F.Cu" "B.Cu")
		(net "ADM1276_EN")
	)
	(segment
		(start 35.40125 -273.539966)
		(end 35.402012 -273.539204)
		(width 0.254)
		(layer "B.Cu")
		(net "ADM1276_EN")
	)
	(segment
		(start 41.0718 -252.1712)
		(end 42.007028 -252.1712)
		(width 0.254)
		(layer "B.Cu")
		(net "ADM1276_EN")
	)
	(segment
		(start 34.1884 -365.734092)
		(end 34.1884 -361.606846)
		(width 0.254)
		(layer "B.Cu")
		(net "ADM1276_EN")
	)
	(segment
		(start 43.05935 -251.118878)
		(end 43.05935 -215.685624)
		(width 0.254)
		(layer "B.Cu")
		(net "ADM1276_EN")
	)
	(segment
		(start 35.87115 -257.37185)
		(end 41.0718 -252.1712)
		(width 0.254)
		(layer "B.Cu")
		(net "ADM1276_EN")
	)
	(segment
		(start 31.115 -365.127286)
		(end 31.92526 -365.937546)
		(width 0.254)
		(layer "B.Cu")
		(net "ADM1276_EN")
	)
	(segment
		(start 39.444168 -176.426368)
		(end 39.40175 -176.38395)
		(width 0.254)
		(layer "B.Cu")
		(net "ADM1276_EN")
	)
	(segment
		(start 34.1884 -361.606846)
		(end 33.318196 -360.736642)
		(width 0.254)
		(layer "B.Cu")
		(net "ADM1276_EN")
	)
	(segment
		(start 35.40125 -274.018502)
		(end 35.40125 -273.539966)
		(width 0.254)
		(layer "B.Cu")
		(net "ADM1276_EN")
	)
	(segment
		(start 38.25875 -186.68365)
		(end 39.444168 -185.498232)
		(width 0.254)
		(layer "B.Cu")
		(net "ADM1276_EN")
	)
	(segment
		(start 33.318196 -358.8258)
		(end 33.319466 -358.82453)
		(width 0.254)
		(layer "B.Cu")
		(net "ADM1276_EN")
	)
	(segment
		(start 39.40175 -176.38395)
		(end 39.40175 -172.61205)
		(width 0.254)
		(layer "B.Cu")
		(net "ADM1276_EN")
	)
	(segment
		(start 39.40175 -172.61205)
		(end 39.4208 -172.593)
		(width 0.254)
		(layer "B.Cu")
		(net "ADM1276_EN")
	)
	(segment
		(start 31.92526 -365.937546)
		(end 33.984946 -365.937546)
		(width 0.254)
		(layer "B.Cu")
		(net "ADM1276_EN")
	)
	(segment
		(start 38.25875 -210.885024)
		(end 38.25875 -186.68365)
		(width 0.254)
		(layer "B.Cu")
		(net "ADM1276_EN")
	)
	(segment
		(start 33.319466 -278.465534)
		(end 35.401504 -276.383496)
		(width 0.254)
		(layer "B.Cu")
		(net "ADM1276_EN")
	)
	(segment
		(start 33.319466 -358.82453)
		(end 33.319466 -278.465534)
		(width 0.254)
		(layer "B.Cu")
		(net "ADM1276_EN")
	)
	(segment
		(start 43.05935 -215.685624)
		(end 38.25875 -210.885024)
		(width 0.254)
		(layer "B.Cu")
		(net "ADM1276_EN")
	)
	(segment
		(start 33.984946 -365.937546)
		(end 34.1884 -365.734092)
		(width 0.254)
		(layer "B.Cu")
		(net "ADM1276_EN")
	)
	(segment
		(start 35.401504 -276.383496)
		(end 35.401504 -274.018756)
		(width 0.254)
		(layer "B.Cu")
		(net "ADM1276_EN")
	)
	(segment
		(start 33.318196 -360.736642)
		(end 33.318196 -358.8258)
		(width 0.254)
		(layer "B.Cu")
		(net "ADM1276_EN")
	)
	(segment
		(start 29.718 -364.5408)
		(end 30.528514 -364.5408)
		(width 0.254)
		(layer "B.Cu")
		(net "ADM1276_EN")
	)
	(segment
		(start 30.528514 -364.5408)
		(end 31.115 -365.127286)
		(width 0.254)
		(layer "B.Cu")
		(net "ADM1276_EN")
	)
	(segment
		(start 39.444168 -185.498232)
		(end 39.444168 -176.426368)
		(width 0.254)
		(layer "B.Cu")
		(net "ADM1276_EN")
	)
	(segment
		(start 42.007028 -252.1712)
		(end 43.05935 -251.118878)
		(width 0.254)
		(layer "B.Cu")
		(net "ADM1276_EN")
	)
	(segment
		(start 35.402012 -273.539204)
		(end 35.402012 -260.133338)
		(width 0.254)
		(layer "B.Cu")
		(net "ADM1276_EN")
	)
	(segment
		(start 35.87115 -259.6642)
		(end 35.87115 -257.37185)
		(width 0.254)
		(layer "B.Cu")
		(net "ADM1276_EN")
	)
	(segment
		(start 35.401504 -274.018756)
		(end 35.40125 -274.018502)
		(width 0.254)
		(layer "B.Cu")
		(net "ADM1276_EN")
	)
	(segment
		(start 35.402012 -260.133338)
		(end 35.87115 -259.6642)
		(width 0.254)
		(layer "B.Cu")
		(net "ADM1276_EN")
	)
	(segment
		(start 25.146 -248.8565)
		(end 26.2255 -248.8565)
		(width 0.254)
		(layer "F.Cu")
		(net "P3V3_FB")
	)
	(segment
		(start 26.2255 -248.8565)
		(end 26.289 -248.92)
		(width 0.254)
		(layer "F.Cu")
		(net "P3V3_FB")
	)
	(segment
		(start 24.003 -249.555)
		(end 24.003 -249.936)
		(width 0.254)
		(layer "F.Cu")
		(net "P3V3_FB")
	)
	(segment
		(start 22.352 -250.444)
		(end 22.352 -248.9327)
		(width 0.254)
		(layer "F.Cu")
		(net "P3V3_FB")
	)
	(segment
		(start 22.849332 -250.941332)
		(end 22.352 -250.444)
		(width 0.254)
		(layer "F.Cu")
		(net "P3V3_FB")
	)
	(segment
		(start 24.7015 -248.8565)
		(end 24.003 -249.555)
		(width 0.254)
		(layer "F.Cu")
		(net "P3V3_FB")
	)
	(segment
		(start 25.146 -248.8565)
		(end 24.7015 -248.8565)
		(width 0.254)
		(layer "F.Cu")
		(net "P3V3_FB")
	)
	(segment
		(start 24.003 -249.936)
		(end 22.997668 -250.941332)
		(width 0.254)
		(layer "F.Cu")
		(net "P3V3_FB")
	)
	(segment
		(start 22.997668 -250.941332)
		(end 22.849332 -250.941332)
		(width 0.254)
		(layer "F.Cu")
		(net "P3V3_FB")
	)
	(via
		(at 22.997668 -250.941332)
		(size 0.7112)
		(drill 0.3556)
		(layers "F.Cu" "B.Cu")
		(net "P3V3_FB")
	)
	(segment
		(start 17.9832 -249.3264)
		(end 18.3769 -248.9327)
		(width 0.254)
		(layer "F.Cu")
		(net "P3V3_EN")
	)
	(segment
		(start 19.6596 -249.4026)
		(end 20.6756 -250.4186)
		(width 0.254)
		(layer "F.Cu")
		(net "P3V3_EN")
	)
	(segment
		(start 18.3769 -248.9327)
		(end 19.6596 -248.9327)
		(width 0.254)
		(layer "F.Cu")
		(net "P3V3_EN")
	)
	(segment
		(start 20.6756 -250.4186)
		(end 20.701 -250.4186)
		(width 0.254)
		(layer "F.Cu")
		(net "P3V3_EN")
	)
	(segment
		(start 19.5072 -250.5964)
		(end 20.5232 -250.5964)
		(width 0.254)
		(layer "F.Cu")
		(net "P3V3_EN")
	)
	(segment
		(start 20.5232 -250.5964)
		(end 20.701 -250.4186)
		(width 0.254)
		(layer "F.Cu")
		(net "P3V3_EN")
	)
	(segment
		(start 19.6596 -248.9327)
		(end 19.6596 -249.4026)
		(width 0.254)
		(layer "F.Cu")
		(net "P3V3_EN")
	)
	(via
		(at 20.701 -250.4186)
		(size 0.7112)
		(drill 0.3556)
		(layers "F.Cu" "B.Cu")
		(net "P3V3_EN")
	)
	(segment
		(start 20.7899 -245.4148)
		(end 20.8661 -245.3386)
		(width 0.254)
		(layer "F.Cu")
		(net "P3V3_BS_NET")
	)
	(segment
		(start 22.352 -245.4402)
		(end 22.2504 -245.3386)
		(width 0.254)
		(layer "F.Cu")
		(net "P3V3_BS_NET")
	)
	(segment
		(start 22.352 -247.0277)
		(end 22.352 -245.4402)
		(width 0.254)
		(layer "F.Cu")
		(net "P3V3_BS_NET")
	)
	(segment
		(start 20.8661 -245.3386)
		(end 22.2504 -245.3386)
		(width 0.254)
		(layer "F.Cu")
		(net "P3V3_BS_NET")
	)
	(via
		(at 22.2504 -245.3386)
		(size 0.7112)
		(drill 0.3556)
		(layers "F.Cu" "B.Cu")
		(net "P3V3_BS_NET")
	)
	(via
		(at 16.9926 -246.1514)
		(size 0.7112)
		(drill 0.3556)
		(layers "F.Cu" "B.Cu")
		(net "P3V3_LX")
	)
	(via
		(at 18.542 -245.364)
		(size 0.7112)
		(drill 0.3556)
		(layers "F.Cu" "B.Cu")
		(net "P3V3_LX")
	)
	(via
		(at 15.24 -245.5672)
		(size 0.7112)
		(drill 0.3556)
		(layers "F.Cu" "B.Cu")
		(net "P3V3_LX")
	)
	(segment
		(start 36.7411 -374.4341)
		(end 36.1442 -373.8372)
		(width 0.508)
		(layer "F.Cu")
		(net "ADM1276_GATE_RSV")
	)
	(segment
		(start 37.719 -374.4341)
		(end 36.7411 -374.4341)
		(width 0.508)
		(layer "F.Cu")
		(net "ADM1276_GATE_RSV")
	)
	(segment
		(start 37.719 -375.793)
		(end 37.719 -374.4341)
		(width 0.508)
		(layer "F.Cu")
		(net "ADM1276_GATE_RSV")
	)
	(via
		(at 37.719 -375.793)
		(size 0.7112)
		(drill 0.3556)
		(layers "F.Cu" "B.Cu")
		(net "ADM1276_GATE_RSV")
	)
	(segment
		(start 33.5915 -376.428)
		(end 34.52495 -376.428)
		(width 0.508)
		(layer "F.Cu")
		(net "ADM1276_GATE_RC")
	)
	(segment
		(start 34.52495 -376.428)
		(end 34.671 -376.28195)
		(width 0.508)
		(layer "F.Cu")
		(net "ADM1276_GATE_RC")
	)
	(segment
		(start 34.671 -375.92)
		(end 33.909 -375.158)
		(width 0.508)
		(layer "F.Cu")
		(net "ADM1276_GATE_RC")
	)
	(segment
		(start 34.671 -376.28195)
		(end 34.671 -375.92)
		(width 0.508)
		(layer "F.Cu")
		(net "ADM1276_GATE_RC")
	)
	(via
		(at 34.671 -376.28195)
		(size 0.7112)
		(drill 0.3556)
		(layers "F.Cu" "B.Cu")
		(net "ADM1276_GATE_RC")
	)
	(via
		(at 46.355 -406.2476)
		(size 0.7112)
		(drill 0.4064)
		(layers "F.Cu" "B.Cu")
		(net "P12V_SENSE_TRACE")
	)
	(via
		(at 29.464 -406.4)
		(size 0.7112)
		(drill 0.4064)
		(layers "F.Cu" "B.Cu")
		(net "P12V_SENSE_TRACE")
	)
	(via
		(at 12.8524 -405.2062)
		(size 0.7112)
		(drill 0.4064)
		(layers "F.Cu" "B.Cu")
		(net "P12V_SENSE_TRACE")
	)
	(via
		(at 30.607 -407.924)
		(size 0.7112)
		(drill 0.3556)
		(layers "F.Cu" "B.Cu")
		(net "P12V_SENSE_TRACE")
	)
	(via
		(at 12.8524 -403.6822)
		(size 0.7112)
		(drill 0.4064)
		(layers "F.Cu" "B.Cu")
		(net "P12V_SENSE_TRACE")
	)
	(via
		(at 38.227 -406.4)
		(size 0.7112)
		(drill 0.4064)
		(layers "F.Cu" "B.Cu")
		(net "P12V_SENSE_TRACE")
	)
	(via
		(at 14.0462 -403.6314)
		(size 0.7112)
		(drill 0.4064)
		(layers "F.Cu" "B.Cu")
		(net "P12V_SENSE_TRACE")
	)
	(via
		(at 14.859 -408.3558)
		(size 0.7112)
		(drill 0.4064)
		(layers "F.Cu" "B.Cu")
		(net "P12V_SENSE_TRACE")
	)
	(via
		(at 39.624 -401.828)
		(size 0.7112)
		(drill 0.4064)
		(layers "F.Cu" "B.Cu")
		(net "P12V_SENSE_TRACE")
	)
	(via
		(at 28.829 -407.797)
		(size 0.7112)
		(drill 0.4064)
		(layers "F.Cu" "B.Cu")
		(net "P12V_SENSE_TRACE")
	)
	(via
		(at 13.5382 -408.7368)
		(size 0.7112)
		(drill 0.3556)
		(layers "F.Cu" "B.Cu")
		(net "P12V_SENSE_TRACE")
	)
	(via
		(at 38.227 -401.828)
		(size 0.7112)
		(drill 0.4064)
		(layers "F.Cu" "B.Cu")
		(net "P12V_SENSE_TRACE")
	)
	(via
		(at 37.592 -407.924)
		(size 0.7112)
		(drill 0.4064)
		(layers "F.Cu" "B.Cu")
		(net "P12V_SENSE_TRACE")
	)
	(via
		(at 12.8524 -406.7302)
		(size 0.7112)
		(drill 0.4064)
		(layers "F.Cu" "B.Cu")
		(net "P12V_SENSE_TRACE")
	)
	(via
		(at 30.988 -402.336)
		(size 0.7112)
		(drill 0.4064)
		(layers "F.Cu" "B.Cu")
		(net "P12V_SENSE_TRACE")
	)
	(via
		(at 17.4498 -407.3906)
		(size 0.7112)
		(drill 0.4064)
		(layers "F.Cu" "B.Cu")
		(net "P12V_SENSE_TRACE")
	)
	(via
		(at 14.0462 -405.1554)
		(size 0.7112)
		(drill 0.4064)
		(layers "F.Cu" "B.Cu")
		(net "P12V_SENSE_TRACE")
	)
	(via
		(at 29.464 -404.368)
		(size 0.7112)
		(drill 0.4064)
		(layers "F.Cu" "B.Cu")
		(net "P12V_SENSE_TRACE")
	)
	(via
		(at 37.084 -409.448)
		(size 0.7112)
		(drill 0.4064)
		(layers "F.Cu" "B.Cu")
		(net "P12V_SENSE_TRACE")
	)
	(via
		(at 14.0462 -401.9804)
		(size 0.7112)
		(drill 0.4064)
		(layers "F.Cu" "B.Cu")
		(net "P12V_SENSE_TRACE")
	)
	(via
		(at 41.656 -407.924)
		(size 0.7112)
		(drill 0.4064)
		(layers "F.Cu" "B.Cu")
		(net "P12V_SENSE_TRACE")
	)
	(via
		(at 39.624 -407.924)
		(size 0.7112)
		(drill 0.4064)
		(layers "F.Cu" "B.Cu")
		(net "P12V_SENSE_TRACE")
	)
	(via
		(at 32.512 -407.924)
		(size 0.7112)
		(drill 0.4064)
		(layers "F.Cu" "B.Cu")
		(net "P12V_SENSE_TRACE")
	)
	(via
		(at 39.751 -404.114)
		(size 0.7112)
		(drill 0.4064)
		(layers "F.Cu" "B.Cu")
		(net "P12V_SENSE_TRACE")
	)
	(via
		(at 14.0462 -406.6794)
		(size 0.7112)
		(drill 0.4064)
		(layers "F.Cu" "B.Cu")
		(net "P12V_SENSE_TRACE")
	)
	(via
		(at 14.0716 -409.7782)
		(size 0.7112)
		(drill 0.4064)
		(layers "F.Cu" "B.Cu")
		(net "P12V_SENSE_TRACE")
	)
	(via
		(at 46.355 -404.368)
		(size 0.7112)
		(drill 0.4064)
		(layers "F.Cu" "B.Cu")
		(net "P12V_SENSE_TRACE")
	)
	(via
		(at 43.688 -407.924)
		(size 0.7112)
		(drill 0.4064)
		(layers "F.Cu" "B.Cu")
		(net "P12V_SENSE_TRACE")
	)
	(via
		(at 24.003 -407.797)
		(size 0.7112)
		(drill 0.4064)
		(layers "F.Cu" "B.Cu")
		(net "P12V_SENSE_TRACE")
	)
	(via
		(at 38.227 -404.114)
		(size 0.7112)
		(drill 0.4064)
		(layers "F.Cu" "B.Cu")
		(net "P12V_SENSE_TRACE")
	)
	(via
		(at 29.464 -402.336)
		(size 0.7112)
		(drill 0.4064)
		(layers "F.Cu" "B.Cu")
		(net "P12V_SENSE_TRACE")
	)
	(via
		(at 30.988 -409.448)
		(size 0.7112)
		(drill 0.4064)
		(layers "F.Cu" "B.Cu")
		(net "P12V_SENSE_TRACE")
	)
	(via
		(at 46.355 -402.463)
		(size 0.7112)
		(drill 0.4064)
		(layers "F.Cu" "B.Cu")
		(net "P12V_SENSE_TRACE")
	)
	(via
		(at 26.416 -407.797)
		(size 0.7112)
		(drill 0.4064)
		(layers "F.Cu" "B.Cu")
		(net "P12V_SENSE_TRACE")
	)
	(via
		(at 22.733 -408.94)
		(size 0.7112)
		(drill 0.3556)
		(layers "F.Cu" "B.Cu")
		(net "P12V_SENSE_TRACE")
	)
	(via
		(at 12.8524 -402.0312)
		(size 0.7112)
		(drill 0.4064)
		(layers "F.Cu" "B.Cu")
		(net "P12V_SENSE_TRACE")
	)
	(via
		(at 39.751 -406.4)
		(size 0.7112)
		(drill 0.4064)
		(layers "F.Cu" "B.Cu")
		(net "P12V_SENSE_TRACE")
	)
	(via
		(at 30.988 -404.368)
		(size 0.7112)
		(drill 0.4064)
		(layers "F.Cu" "B.Cu")
		(net "P12V_SENSE_TRACE")
	)
	(via
		(at 35.179 -407.924)
		(size 0.7112)
		(drill 0.4064)
		(layers "F.Cu" "B.Cu")
		(net "P12V_SENSE_TRACE")
	)
	(via
		(at 30.988 -406.4)
		(size 0.7112)
		(drill 0.4064)
		(layers "F.Cu" "B.Cu")
		(net "P12V_SENSE_TRACE")
	)
	(via
		(at 18.1864 -408.3558)
		(size 0.7112)
		(drill 0.4064)
		(layers "F.Cu" "B.Cu")
		(net "P12V_SENSE_TRACE")
	)
	(via
		(at 29.464 -409.448)
		(size 0.7112)
		(drill 0.4064)
		(layers "F.Cu" "B.Cu")
		(net "P12V_SENSE_TRACE")
	)
	(via
		(at 16.3576 -407.8986)
		(size 0.7112)
		(drill 0.3556)
		(layers "F.Cu" "B.Cu")
		(net "P12V_SENSE_TRACE")
	)
	(segment
		(start 32.766 -375.2215)
		(end 32.766 -376.3645)
		(width 0.508)
		(layer "F.Cu")
		(net "ADM1276_GATE")
	)
	(segment
		(start 36.1442 -377.8123)
		(end 36.068 -377.8885)
		(width 0.508)
		(layer "F.Cu")
		(net "ADM1276_GATE")
	)
	(segment
		(start 36.1442 -376.1232)
		(end 36.1442 -377.8123)
		(width 0.508)
		(layer "F.Cu")
		(net "ADM1276_GATE")
	)
	(segment
		(start 33.06572 -377.61672)
		(end 32.7025 -377.2535)
		(width 0.508)
		(layer "F.Cu")
		(net "ADM1276_GATE")
	)
	(segment
		(start 38.354 -377.8885)
		(end 37.211 -377.8885)
		(width 0.508)
		(layer "F.Cu")
		(net "ADM1276_GATE")
	)
	(segment
		(start 32.7025 -377.2535)
		(end 32.7025 -376.428)
		(width 0.508)
		(layer "F.Cu")
		(net "ADM1276_GATE")
	)
	(segment
		(start 35.0012 -377.8885)
		(end 35.0266 -377.8631)
		(width 0.508)
		(layer "F.Cu")
		(net "ADM1276_GATE")
	)
	(segment
		(start 33.3375 -377.8885)
		(end 33.06572 -377.61672)
		(width 0.508)
		(layer "F.Cu")
		(net "ADM1276_GATE")
	)
	(segment
		(start 35.0012 -377.8885)
		(end 33.3375 -377.8885)
		(width 0.508)
		(layer "F.Cu")
		(net "ADM1276_GATE")
	)
	(segment
		(start 36.068 -377.8885)
		(end 35.0012 -377.8885)
		(width 0.508)
		(layer "F.Cu")
		(net "ADM1276_GATE")
	)
	(segment
		(start 32.766 -376.3645)
		(end 32.7025 -376.428)
		(width 0.508)
		(layer "F.Cu")
		(net "ADM1276_GATE")
	)
	(segment
		(start 37.211 -377.8885)
		(end 36.068 -377.8885)
		(width 0.508)
		(layer "F.Cu")
		(net "ADM1276_GATE")
	)
	(via
		(at 33.06572 -377.61672)
		(size 0.7112)
		(drill 0.3556)
		(layers "F.Cu" "B.Cu")
		(net "ADM1276_GATE")
	)
	(segment
		(start 32.766 -374.3325)
		(end 32.766 -373.507)
		(width 0.508)
		(layer "F.Cu")
		(net "ADM1276_GATE_DRV")
	)
	(segment
		(start 32.766 -373.507)
		(end 32.3342 -373.0752)
		(width 0.508)
		(layer "F.Cu")
		(net "ADM1276_GATE_DRV")
	)
	(segment
		(start 32.3342 -373.0752)
		(end 31.5976 -372.3386)
		(width 0.508)
		(layer "F.Cu")
		(net "ADM1276_GATE_DRV")
	)
	(segment
		(start 31.5976 -372.3386)
		(end 31.017972 -371.758972)
		(width 0.381)
		(layer "F.Cu")
		(net "ADM1276_GATE_DRV")
	)
	(segment
		(start 31.017972 -371.758972)
		(end 31.017972 -371.2464)
		(width 0.381)
		(layer "F.Cu")
		(net "ADM1276_GATE_DRV")
	)
	(via
		(at 32.3342 -373.0752)
		(size 0.7112)
		(drill 0.3556)
		(layers "F.Cu" "B.Cu")
		(net "ADM1276_GATE_DRV")
	)
	(segment
		(start 32.766 -380.5555)
		(end 33.782 -380.5555)
		(width 0.254)
		(layer "F.Cu")
		(net "ADM1276_SENSE-")
	)
	(segment
		(start 31.75 -380.5555)
		(end 32.766 -380.5555)
		(width 0.254)
		(layer "F.Cu")
		(net "ADM1276_SENSE-")
	)
	(segment
		(start 36.1696 -380.9746)
		(end 35.7632 -380.5682)
		(width 0.254)
		(layer "F.Cu")
		(net "ADM1276_SENSE-")
	)
	(segment
		(start 31.4325 -380.238)
		(end 31.4325 -376.7455)
		(width 0.254)
		(layer "F.Cu")
		(net "ADM1276_SENSE-")
	)
	(segment
		(start 31.4325 -376.7455)
		(end 30.367986 -375.680986)
		(width 0.254)
		(layer "F.Cu")
		(net "ADM1276_SENSE-")
	)
	(segment
		(start 34.8107 -380.5682)
		(end 34.798 -380.5555)
		(width 0.254)
		(layer "F.Cu")
		(net "ADM1276_SENSE-")
	)
	(segment
		(start 30.367986 -375.680986)
		(end 30.367986 -371.2464)
		(width 0.254)
		(layer "F.Cu")
		(net "ADM1276_SENSE-")
	)
	(segment
		(start 35.7632 -380.5682)
		(end 34.8107 -380.5682)
		(width 0.254)
		(layer "F.Cu")
		(net "ADM1276_SENSE-")
	)
	(segment
		(start 31.75 -380.5555)
		(end 31.4325 -380.238)
		(width 0.254)
		(layer "F.Cu")
		(net "ADM1276_SENSE-")
	)
	(segment
		(start 33.782 -380.5555)
		(end 34.798 -380.5555)
		(width 0.254)
		(layer "F.Cu")
		(net "ADM1276_SENSE-")
	)
	(via
		(at 36.1696 -380.9746)
		(size 0.7112)
		(drill 0.3556)
		(layers "F.Cu" "B.Cu")
		(net "ADM1276_SENSE-")
	)
	(segment
		(start 30.8102 -376.9614)
		(end 30.8102 -380.4793)
		(width 0.254)
		(layer "F.Cu")
		(net "ADM1276_SENSE+")
	)
	(segment
		(start 30.8102 -380.4793)
		(end 30.734 -380.5555)
		(width 0.254)
		(layer "F.Cu")
		(net "ADM1276_SENSE+")
	)
	(segment
		(start 27.686 -380.5555)
		(end 28.702 -380.5555)
		(width 0.254)
		(layer "F.Cu")
		(net "ADM1276_SENSE+")
	)
	(segment
		(start 29.718 -375.8692)
		(end 30.8102 -376.9614)
		(width 0.254)
		(layer "F.Cu")
		(net "ADM1276_SENSE+")
	)
	(segment
		(start 27.664918 -380.534418)
		(end 27.686 -380.5555)
		(width 0.254)
		(layer "F.Cu")
		(net "ADM1276_SENSE+")
	)
	(segment
		(start 26.500582 -380.534418)
		(end 27.664918 -380.534418)
		(width 0.254)
		(layer "F.Cu")
		(net "ADM1276_SENSE+")
	)
	(segment
		(start 29.718 -380.5555)
		(end 30.734 -380.5555)
		(width 0.254)
		(layer "F.Cu")
		(net "ADM1276_SENSE+")
	)
	(segment
		(start 28.702 -380.5555)
		(end 29.718 -380.5555)
		(width 0.254)
		(layer "F.Cu")
		(net "ADM1276_SENSE+")
	)
	(segment
		(start 29.718 -371.2464)
		(end 29.718 -375.8692)
		(width 0.254)
		(layer "F.Cu")
		(net "ADM1276_SENSE+")
	)
	(via
		(at 26.500582 -380.534418)
		(size 0.7112)
		(drill 0.3556)
		(layers "F.Cu" "B.Cu")
		(net "ADM1276_SENSE+")
	)
	(segment
		(start 37.73424 -109.4232)
		(end 37.32784 -109.8296)
		(width 0.508)
		(layer "F.Cu")
		(net "P12VL_2490_GATE")
	)
	(segment
		(start 40.6019 -138.5824)
		(end 40.0812 -138.5824)
		(width 0.508)
		(layer "F.Cu")
		(net "P12VL_2490_GATE")
	)
	(segment
		(start 38.372288 -139.194032)
		(end 37.8968 -138.718544)
		(width 0.3048)
		(layer "F.Cu")
		(net "P12VL_2490_GATE")
	)
	(segment
		(start 38.1127 -109.4232)
		(end 37.73424 -109.4232)
		(width 0.508)
		(layer "F.Cu")
		(net "P12VL_2490_GATE")
	)
	(segment
		(start 37.8968 -138.718544)
		(end 37.8968 -137.9093)
		(width 0.3048)
		(layer "F.Cu")
		(net "P12VL_2490_GATE")
	)
	(segment
		(start 40.0812 -138.5824)
		(end 39.469568 -139.194032)
		(width 0.508)
		(layer "F.Cu")
		(net "P12VL_2490_GATE")
	)
	(segment
		(start 48.6156 -109.83087)
		(end 48.6156 -109.855)
		(width 0.508)
		(layer "F.Cu")
		(net "P12VL_2490_GATE")
	)
	(segment
		(start 40.6019 -137.6172)
		(end 40.6019 -138.5824)
		(width 0.508)
		(layer "F.Cu")
		(net "P12VL_2490_GATE")
	)
	(segment
		(start 49.3395 -110.5789)
		(end 49.3395 -111.633)
		(width 0.508)
		(layer "F.Cu")
		(net "P12VL_2490_GATE")
	)
	(segment
		(start 39.469568 -139.194032)
		(end 38.372288 -139.194032)
		(width 0.508)
		(layer "F.Cu")
		(net "P12VL_2490_GATE")
	)
	(segment
		(start 48.6156 -109.855)
		(end 49.3395 -110.5789)
		(width 0.508)
		(layer "F.Cu")
		(net "P12VL_2490_GATE")
	)
	(via
		(at 48.6156 -109.83087)
		(size 0.5588)
		(drill 0.3048)
		(layers "F.Cu" "B.Cu")
		(net "P12VL_2490_GATE")
	)
	(via
		(at 40.6019 -137.6172)
		(size 0.5588)
		(drill 0.3048)
		(layers "F.Cu" "B.Cu")
		(net "P12VL_2490_GATE")
	)
	(via
		(at 37.32784 -109.8296)
		(size 0.5588)
		(drill 0.3048)
		(layers "F.Cu" "B.Cu")
		(net "P12VL_2490_GATE")
	)
	(via
		(at 45.5422 -134.62)
		(size 0.7112)
		(drill 0.3556)
		(layers "F.Cu" "B.Cu")
		(net "P12VL_2490_GATE")
	)
	(segment
		(start 48.6156 -109.83087)
		(end 48.5394 -109.90707)
		(width 0.508)
		(layer "B.Cu")
		(net "P12VL_2490_GATE")
	)
	(segment
		(start 48.5394 -109.90707)
		(end 48.5394 -110.040928)
		(width 0.508)
		(layer "B.Cu")
		(net "P12VL_2490_GATE")
	)
	(segment
		(start 45.57395 -114.38255)
		(end 48.6156 -111.3409)
		(width 0.508)
		(layer "B.Cu")
		(net "P12VL_2490_GATE")
	)
	(segment
		(start 48.6156 -111.3409)
		(end 48.6156 -109.83087)
		(width 0.508)
		(layer "B.Cu")
		(net "P12VL_2490_GATE")
	)
	(segment
		(start 40.6019 -137.6172)
		(end 42.545 -137.6172)
		(width 0.508)
		(layer "B.Cu")
		(net "P12VL_2490_GATE")
	)
	(segment
		(start 48.5394 -110.040928)
		(end 48.090328 -110.49)
		(width 0.508)
		(layer "B.Cu")
		(net "P12VL_2490_GATE")
	)
	(segment
		(start 37.98824 -110.49)
		(end 37.32784 -109.8296)
		(width 0.508)
		(layer "B.Cu")
		(net "P12VL_2490_GATE")
	)
	(segment
		(start 42.545 -137.6172)
		(end 45.5422 -134.62)
		(width 0.508)
		(layer "B.Cu")
		(net "P12VL_2490_GATE")
	)
	(segment
		(start 45.57395 -134.58825)
		(end 45.57395 -114.38255)
		(width 0.508)
		(layer "B.Cu")
		(net "P12VL_2490_GATE")
	)
	(segment
		(start 45.5422 -134.62)
		(end 45.57395 -134.58825)
		(width 0.508)
		(layer "B.Cu")
		(net "P12VL_2490_GATE")
	)
	(segment
		(start 48.090328 -110.49)
		(end 37.98824 -110.49)
		(width 0.508)
		(layer "B.Cu")
		(net "P12VL_2490_GATE")
	)
	(segment
		(start 33.91789 -167.279066)
		(end 34.981642 -167.279066)
		(width 0.1397)
		(layer "F.Cu")
		(net "NCT7904_ADR")
	)
	(segment
		(start 32.11195 -165.36035)
		(end 32.766 -166.0144)
		(width 0.1397)
		(layer "F.Cu")
		(net "NCT7904_ADR")
	)
	(segment
		(start 32.766 -166.0144)
		(end 33.91789 -167.16629)
		(width 0.1397)
		(layer "F.Cu")
		(net "NCT7904_ADR")
	)
	(segment
		(start 34.981642 -167.279066)
		(end 34.99231 -167.289734)
		(width 0.1397)
		(layer "F.Cu")
		(net "NCT7904_ADR")
	)
	(segment
		(start 32.11195 -164.091366)
		(end 32.11195 -165.36035)
		(width 0.1397)
		(layer "F.Cu")
		(net "NCT7904_ADR")
	)
	(segment
		(start 33.91789 -167.16629)
		(end 33.91789 -167.279066)
		(width 0.1397)
		(layer "F.Cu")
		(net "NCT7904_ADR")
	)
	(via
		(at 32.766 -166.0144)
		(size 0.7112)
		(drill 0.3556)
		(layers "F.Cu" "B.Cu")
		(net "NCT7904_ADR")
	)
	(segment
		(start 19.823938 -13.867384)
		(end 19.800062 -13.843508)
		(width 0.1397)
		(layer "F.Cu")
		(net "FAN_TACH11")
	)
	(segment
		(start 18.237708 -14.350238)
		(end 19.293332 -14.350238)
		(width 0.1397)
		(layer "F.Cu")
		(net "FAN_TACH11")
	)
	(segment
		(start 17.271492 -14.364462)
		(end 18.223484 -14.364462)
		(width 0.1397)
		(layer "F.Cu")
		(net "FAN_TACH11")
	)
	(segment
		(start 18.223484 -14.364462)
		(end 18.237708 -14.350238)
		(width 0.1397)
		(layer "F.Cu")
		(net "FAN_TACH11")
	)
	(segment
		(start 14.251686 -12.21994)
		(end 4.040124 -12.21994)
		(width 0.1397)
		(layer "F.Cu")
		(net "FAN_TACH11")
	)
	(segment
		(start 19.293332 -14.350238)
		(end 19.800062 -13.843508)
		(width 0.1397)
		(layer "F.Cu")
		(net "FAN_TACH11")
	)
	(segment
		(start 17.271492 -14.364462)
		(end 16.396208 -14.364462)
		(width 0.1397)
		(layer "F.Cu")
		(net "FAN_TACH11")
	)
	(segment
		(start 16.396208 -14.364462)
		(end 14.251686 -12.21994)
		(width 0.1397)
		(layer "F.Cu")
		(net "FAN_TACH11")
	)
	(segment
		(start 19.823938 -15.595092)
		(end 19.823938 -13.867384)
		(width 0.1397)
		(layer "F.Cu")
		(net "FAN_TACH11")
	)
	(segment
		(start 24.3459 -17.399)
		(end 19.939 -17.399)
		(width 0.1397)
		(layer "F.Cu")
		(net "FAN_TACH12")
	)
	(segment
		(start 18.1356 -18.212816)
		(end 17.284446 -18.212816)
		(width 0.1397)
		(layer "F.Cu")
		(net "FAN_TACH12")
	)
	(segment
		(start 8.48614 -17.29994)
		(end 4.040124 -17.29994)
		(width 0.1397)
		(layer "F.Cu")
		(net "FAN_TACH12")
	)
	(segment
		(start 19.125184 -18.212816)
		(end 19.177 -18.161)
		(width 0.1397)
		(layer "F.Cu")
		(net "FAN_TACH12")
	)
	(segment
		(start 17.119092 -18.047462)
		(end 15.735554 -19.431)
		(width 0.1397)
		(layer "F.Cu")
		(net "FAN_TACH12")
	)
	(segment
		(start 18.1356 -18.212816)
		(end 19.125184 -18.212816)
		(width 0.1397)
		(layer "F.Cu")
		(net "FAN_TACH12")
	)
	(segment
		(start 19.939 -17.399)
		(end 19.177 -18.161)
		(width 0.1397)
		(layer "F.Cu")
		(net "FAN_TACH12")
	)
	(segment
		(start 17.284446 -18.212816)
		(end 17.119092 -18.047462)
		(width 0.1397)
		(layer "F.Cu")
		(net "FAN_TACH12")
	)
	(segment
		(start 15.735554 -19.431)
		(end 10.6172 -19.431)
		(width 0.1397)
		(layer "F.Cu")
		(net "FAN_TACH12")
	)
	(segment
		(start 10.6172 -19.431)
		(end 8.48614 -17.29994)
		(width 0.1397)
		(layer "F.Cu")
		(net "FAN_TACH12")
	)
	(segment
		(start 11.4427 -150.622)
		(end 10.287 -150.622)
		(width 0.1397)
		(layer "F.Cu")
		(net "FAN_TACH10")
	)
	(segment
		(start 8.3439 -147.6629)
		(end 8.89 -147.6629)
		(width 0.1397)
		(layer "F.Cu")
		(net "FAN_TACH10")
	)
	(segment
		(start 6.361684 -145.009108)
		(end 6.361684 -145.53184)
		(width 0.1397)
		(layer "F.Cu")
		(net "FAN_TACH10")
	)
	(segment
		(start 6.8834 -146.8374)
		(end 7.5184 -146.8374)
		(width 0.1397)
		(layer "F.Cu")
		(net "FAN_TACH10")
	)
	(segment
		(start 6.35635 -145.953226)
		(end 6.8834 -146.480276)
		(width 0.1397)
		(layer "F.Cu")
		(net "FAN_TACH10")
	)
	(segment
		(start 10.0076 -150.3426)
		(end 10.0076 -147.7645)
		(width 0.1397)
		(layer "F.Cu")
		(net "FAN_TACH10")
	)
	(segment
		(start 6.387592 -144.9832)
		(end 6.361684 -145.009108)
		(width 0.1397)
		(layer "F.Cu")
		(net "FAN_TACH10")
	)
	(segment
		(start 10.287 -150.622)
		(end 10.0076 -150.3426)
		(width 0.1397)
		(layer "F.Cu")
		(net "FAN_TACH10")
	)
	(segment
		(start 10.0076 -147.7645)
		(end 9.906 -147.6629)
		(width 0.1397)
		(layer "F.Cu")
		(net "FAN_TACH10")
	)
	(segment
		(start 6.35635 -145.537174)
		(end 6.35635 -145.953226)
		(width 0.1397)
		(layer "F.Cu")
		(net "FAN_TACH10")
	)
	(segment
		(start 9.906 -147.6629)
		(end 8.89 -147.6629)
		(width 0.1397)
		(layer "F.Cu")
		(net "FAN_TACH10")
	)
	(segment
		(start 11.4554 -148.1074)
		(end 11.4554 -150.6093)
		(width 0.1397)
		(layer "F.Cu")
		(net "FAN_TACH10")
	)
	(segment
		(start 6.8834 -146.480276)
		(end 6.8834 -146.8374)
		(width 0.1397)
		(layer "F.Cu")
		(net "FAN_TACH10")
	)
	(segment
		(start 6.361684 -145.53184)
		(end 6.35635 -145.537174)
		(width 0.1397)
		(layer "F.Cu")
		(net "FAN_TACH10")
	)
	(segment
		(start 11.4554 -150.6093)
		(end 11.4427 -150.622)
		(width 0.1397)
		(layer "F.Cu")
		(net "FAN_TACH10")
	)
	(segment
		(start 7.5184 -146.8374)
		(end 8.3439 -147.6629)
		(width 0.1397)
		(layer "F.Cu")
		(net "FAN_TACH10")
	)
	(via
		(at 6.387592 -144.9832)
		(size 0.5588)
		(drill 0.3048)
		(layers "F.Cu" "B.Cu")
		(net "FAN_TACH10")
	)
	(via
		(at 6.8834 -146.8374)
		(size 0.7112)
		(drill 0.3556)
		(layers "F.Cu" "B.Cu")
		(net "FAN_TACH10")
	)
	(segment
		(start 4.948174 -133.481826)
		(end 4.948174 -128.248156)
		(width 0.1397)
		(layer "B.Cu")
		(net "FAN_TACH10")
	)
	(segment
		(start 3.974084 -134.455916)
		(end 4.948174 -133.481826)
		(width 0.1397)
		(layer "B.Cu")
		(net "FAN_TACH10")
	)
	(segment
		(start 3.974084 -142.569692)
		(end 3.974084 -134.455916)
		(width 0.1397)
		(layer "B.Cu")
		(net "FAN_TACH10")
	)
	(segment
		(start 4.948174 -128.248156)
		(end 4.040124 -127.340106)
		(width 0.1397)
		(layer "B.Cu")
		(net "FAN_TACH10")
	)
	(segment
		(start 6.387592 -144.9832)
		(end 3.974084 -142.569692)
		(width 0.1397)
		(layer "B.Cu")
		(net "FAN_TACH10")
	)
	(segment
		(start 41.4274 -153.749756)
		(end 40.26789 -154.909266)
		(width 0.1397)
		(layer "F.Cu")
		(net "NCT7904_3VDD")
	)
	(segment
		(start 38.67531 -154.678634)
		(end 40.037258 -154.678634)
		(width 0.1397)
		(layer "F.Cu")
		(net "NCT7904_3VDD")
	)
	(segment
		(start 37.43706 -155.002484)
		(end 37.437314 -155.002484)
		(width 0.1397)
		(layer "F.Cu")
		(net "NCT7904_3VDD")
	)
	(segment
		(start 37.437314 -155.002484)
		(end 37.761164 -154.678634)
		(width 0.1397)
		(layer "F.Cu")
		(net "NCT7904_3VDD")
	)
	(segment
		(start 40.037258 -154.678634)
		(end 40.26789 -154.909266)
		(width 0.1397)
		(layer "F.Cu")
		(net "NCT7904_3VDD")
	)
	(segment
		(start 41.4274 -153.598118)
		(end 41.4274 -153.749756)
		(width 0.1397)
		(layer "F.Cu")
		(net "NCT7904_3VDD")
	)
	(segment
		(start 36.6776 -157.03804)
		(end 36.6776 -155.761944)
		(width 0.1397)
		(layer "F.Cu")
		(net "NCT7904_3VDD")
	)
	(segment
		(start 35.616134 -158.099506)
		(end 36.6776 -157.03804)
		(width 0.1397)
		(layer "F.Cu")
		(net "NCT7904_3VDD")
	)
	(segment
		(start 36.6776 -155.761944)
		(end 37.17671 -155.262834)
		(width 0.1397)
		(layer "F.Cu")
		(net "NCT7904_3VDD")
	)
	(segment
		(start 37.761164 -154.678634)
		(end 38.67531 -154.678634)
		(width 0.1397)
		(layer "F.Cu")
		(net "NCT7904_3VDD")
	)
	(segment
		(start 34.60369 -158.099506)
		(end 35.616134 -158.099506)
		(width 0.1397)
		(layer "F.Cu")
		(net "NCT7904_3VDD")
	)
	(segment
		(start 37.17671 -155.262834)
		(end 37.43706 -155.002484)
		(width 0.1397)
		(layer "F.Cu")
		(net "NCT7904_3VDD")
	)
	(via
		(at 41.4274 -153.598118)
		(size 0.7112)
		(drill 0.3556)
		(layers "F.Cu" "B.Cu")
		(net "NCT7904_3VDD")
	)
	(segment
		(start 18.1991 -148.336)
		(end 16.4719 -146.6088)
		(width 0.1397)
		(layer "F.Cu")
		(net "FAN_TACH9")
	)
	(segment
		(start 6.643624 -142.900654)
		(end 5.91185 -143.632428)
		(width 0.1397)
		(layer "F.Cu")
		(net "FAN_TACH9")
	)
	(segment
		(start 16.129 -145.288)
		(end 13.741654 -142.900654)
		(width 0.1397)
		(layer "F.Cu")
		(net "FAN_TACH9")
	)
	(segment
		(start 5.911342 -145.29435)
		(end 5.91185 -145.294858)
		(width 0.1397)
		(layer "F.Cu")
		(net "FAN_TACH9")
	)
	(segment
		(start 5.91185 -144.671542)
		(end 5.911342 -144.67205)
		(width 0.1397)
		(layer "F.Cu")
		(net "FAN_TACH9")
	)
	(segment
		(start 16.129 -145.3007)
		(end 16.129 -145.288)
		(width 0.1397)
		(layer "F.Cu")
		(net "FAN_TACH9")
	)
	(segment
		(start 18.1991 -149.1107)
		(end 18.1991 -148.336)
		(width 0.1397)
		(layer "F.Cu")
		(net "FAN_TACH9")
	)
	(segment
		(start 5.9436 -146.670014)
		(end 5.9563 -146.682714)
		(width 0.1397)
		(layer "F.Cu")
		(net "FAN_TACH9")
	)
	(segment
		(start 5.91185 -145.294858)
		(end 5.91185 -146.137376)
		(width 0.1397)
		(layer "F.Cu")
		(net "FAN_TACH9")
	)
	(segment
		(start 5.911342 -144.67205)
		(end 5.911342 -145.29435)
		(width 0.1397)
		(layer "F.Cu")
		(net "FAN_TACH9")
	)
	(segment
		(start 5.9436 -146.169126)
		(end 5.9436 -146.670014)
		(width 0.1397)
		(layer "F.Cu")
		(net "FAN_TACH9")
	)
	(segment
		(start 16.4719 -146.6088)
		(end 16.3703 -146.6088)
		(width 0.1397)
		(layer "F.Cu")
		(net "FAN_TACH9")
	)
	(segment
		(start 17.1958 -150.114)
		(end 18.1991 -149.1107)
		(width 0.1397)
		(layer "F.Cu")
		(net "FAN_TACH9")
	)
	(segment
		(start 5.91185 -143.632428)
		(end 5.91185 -144.671542)
		(width 0.1397)
		(layer "F.Cu")
		(net "FAN_TACH9")
	)
	(segment
		(start 16.3703 -146.6088)
		(end 16.3703 -145.542)
		(width 0.1397)
		(layer "F.Cu")
		(net "FAN_TACH9")
	)
	(segment
		(start 5.91185 -146.137376)
		(end 5.9436 -146.169126)
		(width 0.1397)
		(layer "F.Cu")
		(net "FAN_TACH9")
	)
	(segment
		(start 13.741654 -142.900654)
		(end 6.643624 -142.900654)
		(width 0.1397)
		(layer "F.Cu")
		(net "FAN_TACH9")
	)
	(segment
		(start 16.3703 -145.542)
		(end 16.129 -145.3007)
		(width 0.1397)
		(layer "F.Cu")
		(net "FAN_TACH9")
	)
	(via
		(at 4.58089 -145.307304)
		(size 0.7112)
		(drill 0.3556)
		(layers "F.Cu" "B.Cu")
		(net "FAN_TACH9")
	)
	(via
		(at 5.9563 -146.682714)
		(size 0.5588)
		(drill 0.3048)
		(layers "F.Cu" "B.Cu")
		(net "FAN_TACH9")
	)
	(segment
		(start 5.9563 -146.682714)
		(end 4.58089 -145.307304)
		(width 0.1397)
		(layer "B.Cu")
		(net "FAN_TACH9")
	)
	(segment
		(start 3.132074 -143.858488)
		(end 3.132074 -123.168156)
		(width 0.1397)
		(layer "B.Cu")
		(net "FAN_TACH9")
	)
	(segment
		(start 3.132074 -123.168156)
		(end 4.040124 -122.260106)
		(width 0.1397)
		(layer "B.Cu")
		(net "FAN_TACH9")
	)
	(segment
		(start 4.58089 -145.307304)
		(end 3.132074 -143.858488)
		(width 0.1397)
		(layer "B.Cu")
		(net "FAN_TACH9")
	)
	(segment
		(start 16.3068 -255.9685)
		(end 15.2781 -256.9972)
		(width 0.1397)
		(layer "F.Cu")
		(net "FAN_TACH5")
	)
	(segment
		(start 17.4371 -255.0922)
		(end 16.3068 -255.0922)
		(width 0.1397)
		(layer "F.Cu")
		(net "FAN_TACH5")
	)
	(segment
		(start 4.040124 -301.580042)
		(end 6.394958 -301.580042)
		(width 0.1397)
		(layer "F.Cu")
		(net "FAN_TACH5")
	)
	(segment
		(start 12.1793 -257.3147)
		(end 13.6652 -257.3147)
		(width 0.1397)
		(layer "F.Cu")
		(net "FAN_TACH5")
	)
	(segment
		(start 13.9827 -256.9972)
		(end 13.6652 -257.3147)
		(width 0.1397)
		(layer "F.Cu")
		(net "FAN_TACH5")
	)
	(segment
		(start 6.394958 -301.580042)
		(end 11.303 -296.672)
		(width 0.1397)
		(layer "F.Cu")
		(net "FAN_TACH5")
	)
	(segment
		(start 15.2781 -256.9972)
		(end 13.9827 -256.9972)
		(width 0.1397)
		(layer "F.Cu")
		(net "FAN_TACH5")
	)
	(segment
		(start 16.3068 -255.0922)
		(end 16.3068 -255.9685)
		(width 0.1397)
		(layer "F.Cu")
		(net "FAN_TACH5")
	)
	(segment
		(start 11.303 -258.191)
		(end 12.1793 -257.3147)
		(width 0.1397)
		(layer "F.Cu")
		(net "FAN_TACH5")
	)
	(segment
		(start 11.303 -296.672)
		(end 11.303 -258.191)
		(width 0.1397)
		(layer "F.Cu")
		(net "FAN_TACH5")
	)
	(segment
		(start 16.3703 -262.1534)
		(end 16.3703 -261.2009)
		(width 0.1397)
		(layer "F.Cu")
		(net "FAN_TACH6")
	)
	(segment
		(start 16.3703 -262.1534)
		(end 15.0749 -262.1534)
		(width 0.1397)
		(layer "F.Cu")
		(net "FAN_TACH6")
	)
	(segment
		(start 4.040124 -306.660042)
		(end 6.705854 -303.994312)
		(width 0.1397)
		(layer "F.Cu")
		(net "FAN_TACH6")
	)
	(segment
		(start 6.705854 -303.994312)
		(end 6.705854 -302.920654)
		(width 0.1397)
		(layer "F.Cu")
		(net "FAN_TACH6")
	)
	(segment
		(start 13.97 -261.62)
		(end 14.5415 -261.62)
		(width 0.1397)
		(layer "F.Cu")
		(net "FAN_TACH6")
	)
	(segment
		(start 15.0749 -262.1534)
		(end 14.7574 -261.8359)
		(width 0.1397)
		(layer "F.Cu")
		(net "FAN_TACH6")
	)
	(segment
		(start 18.2499 -260.35)
		(end 18.3515 -260.4516)
		(width 0.1397)
		(layer "F.Cu")
		(net "FAN_TACH6")
	)
	(segment
		(start 16.3703 -261.2009)
		(end 17.2212 -260.35)
		(width 0.1397)
		(layer "F.Cu")
		(net "FAN_TACH6")
	)
	(segment
		(start 12.319 -297.307508)
		(end 12.319 -263.271)
		(width 0.1397)
		(layer "F.Cu")
		(net "FAN_TACH6")
	)
	(segment
		(start 6.705854 -302.920654)
		(end 12.319 -297.307508)
		(width 0.1397)
		(layer "F.Cu")
		(net "FAN_TACH6")
	)
	(segment
		(start 12.319 -263.271)
		(end 13.97 -261.62)
		(width 0.1397)
		(layer "F.Cu")
		(net "FAN_TACH6")
	)
	(segment
		(start 14.5415 -261.62)
		(end 14.7574 -261.8359)
		(width 0.1397)
		(layer "F.Cu")
		(net "FAN_TACH6")
	)
	(segment
		(start 17.2212 -260.35)
		(end 18.2499 -260.35)
		(width 0.1397)
		(layer "F.Cu")
		(net "FAN_TACH6")
	)
	(segment
		(start 20.828 -179.9336)
		(end 22.1615 -179.9336)
		(width 0.1397)
		(layer "F.Cu")
		(net "FAN_TACH7")
	)
	(segment
		(start 19.2278 -182.6387)
		(end 19.2278 -183.134)
		(width 0.1397)
		(layer "F.Cu")
		(net "FAN_TACH7")
	)
	(segment
		(start 19.2278 -183.134)
		(end 18.9738 -183.388)
		(width 0.1397)
		(layer "F.Cu")
		(net "FAN_TACH7")
	)
	(segment
		(start 19.2278 -182.6387)
		(end 19.8628 -182.6387)
		(width 0.1397)
		(layer "F.Cu")
		(net "FAN_TACH7")
	)
	(segment
		(start 5.356098 -186.944)
		(end 4.040124 -188.259974)
		(width 0.1397)
		(layer "F.Cu")
		(net "FAN_TACH7")
	)
	(segment
		(start 18.9738 -183.388)
		(end 16.51 -183.388)
		(width 0.1397)
		(layer "F.Cu")
		(net "FAN_TACH7")
	)
	(segment
		(start 12.954 -186.944)
		(end 5.356098 -186.944)
		(width 0.1397)
		(layer "F.Cu")
		(net "FAN_TACH7")
	)
	(segment
		(start 16.51 -183.388)
		(end 12.954 -186.944)
		(width 0.1397)
		(layer "F.Cu")
		(net "FAN_TACH7")
	)
	(segment
		(start 20.7899 -181.7116)
		(end 20.7899 -179.9717)
		(width 0.1397)
		(layer "F.Cu")
		(net "FAN_TACH7")
	)
	(segment
		(start 22.1615 -179.9336)
		(end 22.2885 -179.8066)
		(width 0.1397)
		(layer "F.Cu")
		(net "FAN_TACH7")
	)
	(segment
		(start 19.8628 -182.6387)
		(end 20.7899 -181.7116)
		(width 0.1397)
		(layer "F.Cu")
		(net "FAN_TACH7")
	)
	(segment
		(start 20.7899 -179.9717)
		(end 20.828 -179.9336)
		(width 0.1397)
		(layer "F.Cu")
		(net "FAN_TACH7")
	)
	(segment
		(start 20.701 -186.2836)
		(end 21.9075 -186.2836)
		(width 0.1397)
		(layer "F.Cu")
		(net "FAN_TACH8")
	)
	(segment
		(start 17.145 -189.23)
		(end 18.1991 -189.23)
		(width 0.1397)
		(layer "F.Cu")
		(net "FAN_TACH8")
	)
	(segment
		(start 14.870176 -191.504824)
		(end 17.145 -189.23)
		(width 0.1397)
		(layer "F.Cu")
		(net "FAN_TACH8")
	)
	(segment
		(start 19.3675 -188.0616)
		(end 19.1008 -188.3283)
		(width 0.1397)
		(layer "F.Cu")
		(net "FAN_TACH8")
	)
	(segment
		(start 5.923026 -193.339974)
		(end 7.758176 -191.504824)
		(width 0.1397)
		(layer "F.Cu")
		(net "FAN_TACH8")
	)
	(segment
		(start 20.6629 -186.3217)
		(end 20.701 -186.2836)
		(width 0.1397)
		(layer "F.Cu")
		(net "FAN_TACH8")
	)
	(segment
		(start 4.040124 -193.339974)
		(end 5.923026 -193.339974)
		(width 0.1397)
		(layer "F.Cu")
		(net "FAN_TACH8")
	)
	(segment
		(start 7.758176 -191.504824)
		(end 14.870176 -191.504824)
		(width 0.1397)
		(layer "F.Cu")
		(net "FAN_TACH8")
	)
	(segment
		(start 18.1991 -189.23)
		(end 19.1008 -188.3283)
		(width 0.1397)
		(layer "F.Cu")
		(net "FAN_TACH8")
	)
	(segment
		(start 20.6629 -188.0616)
		(end 19.3675 -188.0616)
		(width 0.1397)
		(layer "F.Cu")
		(net "FAN_TACH8")
	)
	(segment
		(start 20.6629 -188.0616)
		(end 20.6629 -186.3217)
		(width 0.1397)
		(layer "F.Cu")
		(net "FAN_TACH8")
	)
	(segment
		(start 22.479508 -289.343592)
		(end 22.0853 -289.7378)
		(width 0.1397)
		(layer "F.Cu")
		(net "FAN_TACH4")
	)
	(segment
		(start 20.700492 -287.490662)
		(end 20.675092 -287.516062)
		(width 0.1397)
		(layer "F.Cu")
		(net "FAN_TACH4")
	)
	(segment
		(start 22.0853 -289.7378)
		(end 22.0853 -290.322)
		(width 0.1397)
		(layer "F.Cu")
		(net "FAN_TACH4")
	)
	(segment
		(start 22.479508 -288.606738)
		(end 22.479508 -289.343592)
		(width 0.1397)
		(layer "F.Cu")
		(net "FAN_TACH4")
	)
	(segment
		(start 20.700492 -286.068262)
		(end 20.700492 -287.490662)
		(width 0.1397)
		(layer "F.Cu")
		(net "FAN_TACH4")
	)
	(segment
		(start 21.388832 -287.516062)
		(end 20.675092 -287.516062)
		(width 0.1397)
		(layer "F.Cu")
		(net "FAN_TACH4")
	)
	(segment
		(start 20.675092 -286.042862)
		(end 20.700492 -286.068262)
		(width 0.1397)
		(layer "F.Cu")
		(net "FAN_TACH4")
	)
	(segment
		(start 22.0853 -290.322)
		(end 22.0853 -290.828222)
		(width 0.1397)
		(layer "F.Cu")
		(net "FAN_TACH4")
	)
	(segment
		(start 22.0853 -290.828222)
		(end 18.583402 -294.33012)
		(width 0.1397)
		(layer "F.Cu")
		(net "FAN_TACH4")
	)
	(segment
		(start 22.479508 -288.606738)
		(end 21.388832 -287.516062)
		(width 0.1397)
		(layer "F.Cu")
		(net "FAN_TACH4")
	)
	(via
		(at 18.583402 -294.33012)
		(size 0.5588)
		(drill 0.3048)
		(layers "F.Cu" "B.Cu")
		(net "FAN_TACH4")
	)
	(segment
		(start 4.948174 -365.297974)
		(end 3.974084 -364.323884)
		(width 0.1397)
		(layer "B.Cu")
		(net "FAN_TACH4")
	)
	(segment
		(start 3.974084 -351.930716)
		(end 18.583402 -337.321398)
		(width 0.1397)
		(layer "B.Cu")
		(net "FAN_TACH4")
	)
	(segment
		(start 3.974084 -364.323884)
		(end 3.974084 -351.930716)
		(width 0.1397)
		(layer "B.Cu")
		(net "FAN_TACH4")
	)
	(segment
		(start 4.040124 -372.65991)
		(end 4.948174 -371.75186)
		(width 0.1397)
		(layer "B.Cu")
		(net "FAN_TACH4")
	)
	(segment
		(start 4.948174 -371.75186)
		(end 4.948174 -365.297974)
		(width 0.1397)
		(layer "B.Cu")
		(net "FAN_TACH4")
	)
	(segment
		(start 18.583402 -337.321398)
		(end 18.583402 -294.33012)
		(width 0.1397)
		(layer "B.Cu")
		(net "FAN_TACH4")
	)
	(segment
		(start 16.85798 -287.35401)
		(end 17.323816 -287.35401)
		(width 0.1397)
		(layer "F.Cu")
		(net "FAN_TACH3")
	)
	(segment
		(start 16.053308 -286.549338)
		(end 16.85798 -287.35401)
		(width 0.1397)
		(layer "F.Cu")
		(net "FAN_TACH3")
	)
	(segment
		(start 17.323816 -287.35401)
		(end 17.831308 -287.861502)
		(width 0.1397)
		(layer "F.Cu")
		(net "FAN_TACH3")
	)
	(segment
		(start 16.128492 -285.458662)
		(end 16.053308 -285.533846)
		(width 0.1397)
		(layer "F.Cu")
		(net "FAN_TACH3")
	)
	(segment
		(start 17.907 -290.8681)
		(end 18.0721 -290.703)
		(width 0.1397)
		(layer "F.Cu")
		(net "FAN_TACH3")
	)
	(segment
		(start 17.831308 -287.861502)
		(end 17.831308 -289.140138)
		(width 0.1397)
		(layer "F.Cu")
		(net "FAN_TACH3")
	)
	(segment
		(start 16.053308 -285.533846)
		(end 16.053308 -286.549338)
		(width 0.1397)
		(layer "F.Cu")
		(net "FAN_TACH3")
	)
	(segment
		(start 17.831308 -290.462208)
		(end 17.831308 -289.140138)
		(width 0.1397)
		(layer "F.Cu")
		(net "FAN_TACH3")
	)
	(segment
		(start 18.0721 -290.703)
		(end 17.831308 -290.462208)
		(width 0.1397)
		(layer "F.Cu")
		(net "FAN_TACH3")
	)
	(segment
		(start 17.907 -295.021)
		(end 17.907 -290.8681)
		(width 0.1397)
		(layer "F.Cu")
		(net "FAN_TACH3")
	)
	(via
		(at 17.907 -295.021)
		(size 0.5588)
		(drill 0.3048)
		(layers "F.Cu" "B.Cu")
		(net "FAN_TACH3")
	)
	(via
		(at 7.731252 -347.360748)
		(size 0.7112)
		(drill 0.3556)
		(layers "F.Cu" "B.Cu")
		(net "FAN_TACH3")
	)
	(segment
		(start 17.58315 -297.236642)
		(end 17.58315 -298.813474)
		(width 0.1397)
		(layer "B.Cu")
		(net "FAN_TACH3")
	)
	(segment
		(start 7.731252 -347.487748)
		(end 7.731252 -347.360748)
		(width 0.1397)
		(layer "B.Cu")
		(net "FAN_TACH3")
	)
	(segment
		(start 17.97685 -337.11515)
		(end 7.731252 -347.360748)
		(width 0.1397)
		(layer "B.Cu")
		(net "FAN_TACH3")
	)
	(segment
		(start 3.529584 -367.06937)
		(end 3.529584 -351.689416)
		(width 0.1397)
		(layer "B.Cu")
		(net "FAN_TACH3")
	)
	(segment
		(start 17.907 -296.912792)
		(end 17.58315 -297.236642)
		(width 0.1397)
		(layer "B.Cu")
		(net "FAN_TACH3")
	)
	(segment
		(start 17.58315 -298.813474)
		(end 17.97685 -299.207174)
		(width 0.1397)
		(layer "B.Cu")
		(net "FAN_TACH3")
	)
	(segment
		(start 17.907 -295.021)
		(end 17.907 -296.912792)
		(width 0.1397)
		(layer "B.Cu")
		(net "FAN_TACH3")
	)
	(segment
		(start 17.97685 -299.207174)
		(end 17.97685 -337.11515)
		(width 0.1397)
		(layer "B.Cu")
		(net "FAN_TACH3")
	)
	(segment
		(start 4.040124 -367.57991)
		(end 3.529584 -367.06937)
		(width 0.1397)
		(layer "B.Cu")
		(net "FAN_TACH3")
	)
	(segment
		(start 3.529584 -351.689416)
		(end 7.731252 -347.487748)
		(width 0.1397)
		(layer "B.Cu")
		(net "FAN_TACH3")
	)
	(segment
		(start 14.732 -473.964)
		(end 14.732 -458.851)
		(width 0.1397)
		(layer "F.Cu")
		(net "FAN_TACH2")
	)
	(segment
		(start 5.9182 -480.822)
		(end 7.874 -480.822)
		(width 0.1397)
		(layer "F.Cu")
		(net "FAN_TACH2")
	)
	(segment
		(start 11.4681 -452.7931)
		(end 11.4681 -455.5871)
		(width 0.1397)
		(layer "F.Cu")
		(net "FAN_TACH2")
	)
	(segment
		(start 12.2555 -447.1162)
		(end 12.2555 -445.9732)
		(width 0.1397)
		(layer "F.Cu")
		(net "FAN_TACH2")
	)
	(segment
		(start 7.874 -480.822)
		(end 14.732 -473.964)
		(width 0.1397)
		(layer "F.Cu")
		(net "FAN_TACH2")
	)
	(segment
		(start 12.319 -448.2338)
		(end 12.319 -448.31)
		(width 0.1397)
		(layer "F.Cu")
		(net "FAN_TACH2")
	)
	(segment
		(start 11.6078 -446.532)
		(end 11.6967 -446.532)
		(width 0.1397)
		(layer "F.Cu")
		(net "FAN_TACH2")
	)
	(segment
		(start 11.5062 -449.1228)
		(end 11.5062 -450.2404)
		(width 0.1397)
		(layer "F.Cu")
		(net "FAN_TACH2")
	)
	(segment
		(start 14.732 -458.851)
		(end 14.478 -458.597)
		(width 0.1397)
		(layer "F.Cu")
		(net "FAN_TACH2")
	)
	(segment
		(start 10.9728 -450.7738)
		(end 10.9728 -452.2978)
		(width 0.1397)
		(layer "F.Cu")
		(net "FAN_TACH2")
	)
	(segment
		(start 12.319 -448.31)
		(end 11.5062 -449.1228)
		(width 0.1397)
		(layer "F.Cu")
		(net "FAN_TACH2")
	)
	(segment
		(start 11.5062 -450.2404)
		(end 10.9728 -450.7738)
		(width 0.1397)
		(layer "F.Cu")
		(net "FAN_TACH2")
	)
	(segment
		(start 12.2555 -448.1703)
		(end 12.319 -448.2338)
		(width 0.1397)
		(layer "F.Cu")
		(net "FAN_TACH2")
	)
	(segment
		(start 10.5664 -447.5734)
		(end 11.6078 -446.532)
		(width 0.1397)
		(layer "F.Cu")
		(net "FAN_TACH2")
	)
	(segment
		(start 10.5664 -448.9577)
		(end 10.5664 -447.5734)
		(width 0.1397)
		(layer "F.Cu")
		(net "FAN_TACH2")
	)
	(segment
		(start 12.2555 -445.9732)
		(end 12.2682 -445.9605)
		(width 0.1397)
		(layer "F.Cu")
		(net "FAN_TACH2")
	)
	(segment
		(start 4.040124 -482.700076)
		(end 5.9182 -480.822)
		(width 0.1397)
		(layer "F.Cu")
		(net "FAN_TACH2")
	)
	(segment
		(start 11.4681 -455.5871)
		(end 14.478 -458.597)
		(width 0.1397)
		(layer "F.Cu")
		(net "FAN_TACH2")
	)
	(segment
		(start 12.2555 -447.1162)
		(end 12.2555 -448.1703)
		(width 0.1397)
		(layer "F.Cu")
		(net "FAN_TACH2")
	)
	(segment
		(start 10.9728 -452.2978)
		(end 11.4681 -452.7931)
		(width 0.1397)
		(layer "F.Cu")
		(net "FAN_TACH2")
	)
	(segment
		(start 11.6967 -446.532)
		(end 12.2555 -445.9732)
		(width 0.1397)
		(layer "F.Cu")
		(net "FAN_TACH2")
	)
	(via
		(at 14.478 -458.597)
		(size 0.7112)
		(drill 0.3556)
		(layers "F.Cu" "B.Cu")
		(net "FAN_TACH2")
	)
	(segment
		(start 8.0264 -450.4563)
		(end 7.7851 -450.6976)
		(width 0.1397)
		(layer "F.Cu")
		(net "FAN_TACH1")
	)
	(segment
		(start 5.082794 -450.644006)
		(end 4.826 -450.9008)
		(width 0.1397)
		(layer "F.Cu")
		(net "FAN_TACH1")
	)
	(segment
		(start 7.6835 -452.9709)
		(end 7.0866 -452.374)
		(width 0.1397)
		(layer "F.Cu")
		(net "FAN_TACH1")
	)
	(segment
		(start 5.972048 -479.552)
		(end 4.040124 -477.620076)
		(width 0.1397)
		(layer "F.Cu")
		(net "FAN_TACH1")
	)
	(segment
		(start 7.7851 -450.6976)
		(end 5.147818 -450.6976)
		(width 0.1397)
		(layer "F.Cu")
		(net "FAN_TACH1")
	)
	(segment
		(start 7.6835 -454.1012)
		(end 7.951724 -454.1012)
		(width 0.1397)
		(layer "F.Cu")
		(net "FAN_TACH1")
	)
	(segment
		(start 8.5852 -449.8848)
		(end 8.0264 -450.4436)
		(width 0.1397)
		(layer "F.Cu")
		(net "FAN_TACH1")
	)
	(segment
		(start 7.545324 -479.552)
		(end 5.972048 -479.552)
		(width 0.1397)
		(layer "F.Cu")
		(net "FAN_TACH1")
	)
	(segment
		(start 8.0264 -450.4436)
		(end 8.0264 -450.4563)
		(width 0.1397)
		(layer "F.Cu")
		(net "FAN_TACH1")
	)
	(segment
		(start 13.7287 -473.368624)
		(end 7.545324 -479.552)
		(width 0.1397)
		(layer "F.Cu")
		(net "FAN_TACH1")
	)
	(segment
		(start 4.826 -451.7771)
		(end 5.4229 -452.374)
		(width 0.1397)
		(layer "F.Cu")
		(net "FAN_TACH1")
	)
	(segment
		(start 13.7287 -459.8543)
		(end 13.7287 -473.368624)
		(width 0.1397)
		(layer "F.Cu")
		(net "FAN_TACH1")
	)
	(segment
		(start 7.951724 -454.1012)
		(end 9.597898 -455.747374)
		(width 0.1397)
		(layer "F.Cu")
		(net "FAN_TACH1")
	)
	(segment
		(start 5.094224 -450.644006)
		(end 5.082794 -450.644006)
		(width 0.1397)
		(layer "F.Cu")
		(net "FAN_TACH1")
	)
	(segment
		(start 5.147818 -450.6976)
		(end 5.094224 -450.644006)
		(width 0.1397)
		(layer "F.Cu")
		(net "FAN_TACH1")
	)
	(segment
		(start 8.5852 -449.5546)
		(end 8.5852 -449.8848)
		(width 0.1397)
		(layer "F.Cu")
		(net "FAN_TACH1")
	)
	(segment
		(start 9.597898 -455.747374)
		(end 9.621774 -455.747374)
		(width 0.1397)
		(layer "F.Cu")
		(net "FAN_TACH1")
	)
	(segment
		(start 9.621774 -455.747374)
		(end 13.7287 -459.8543)
		(width 0.1397)
		(layer "F.Cu")
		(net "FAN_TACH1")
	)
	(segment
		(start 7.6835 -454.1012)
		(end 7.6835 -452.9709)
		(width 0.1397)
		(layer "F.Cu")
		(net "FAN_TACH1")
	)
	(segment
		(start 4.826 -450.9008)
		(end 4.826 -451.7771)
		(width 0.1397)
		(layer "F.Cu")
		(net "FAN_TACH1")
	)
	(segment
		(start 7.0866 -452.374)
		(end 5.4229 -452.374)
		(width 0.1397)
		(layer "F.Cu")
		(net "FAN_TACH1")
	)
	(via
		(at 5.094224 -450.644006)
		(size 0.7112)
		(drill 0.3556)
		(layers "F.Cu" "B.Cu")
		(net "FAN_TACH1")
	)
	(segment
		(start 32.261302 -367.403126)
		(end 32.1564 -367.508028)
		(width 0.1397)
		(layer "F.Cu")
		(net "I2C_C_SCL_ADM1276")
	)
	(segment
		(start 32.25165 -367.374678)
		(end 32.261302 -367.38433)
		(width 0.1397)
		(layer "F.Cu")
		(net "I2C_C_SCL_ADM1276")
	)
	(segment
		(start 32.25165 -361.89285)
		(end 32.25165 -364.5916)
		(width 0.1397)
		(layer "F.Cu")
		(net "I2C_C_SCL_ADM1276")
	)
	(segment
		(start 32.385 -361.7595)
		(end 32.25165 -361.89285)
		(width 0.1397)
		(layer "F.Cu")
		(net "I2C_C_SCL_ADM1276")
	)
	(segment
		(start 32.25165 -364.5916)
		(end 32.25165 -367.374678)
		(width 0.1397)
		(layer "F.Cu")
		(net "I2C_C_SCL_ADM1276")
	)
	(segment
		(start 32.261302 -367.38433)
		(end 32.261302 -367.403126)
		(width 0.1397)
		(layer "F.Cu")
		(net "I2C_C_SCL_ADM1276")
	)
	(via
		(at 32.25165 -364.5916)
		(size 0.7112)
		(drill 0.3556)
		(layers "F.Cu" "B.Cu")
		(net "I2C_C_SCL_ADM1276")
	)
	(segment
		(start 31.242 -361.7595)
		(end 31.242 -363.5502)
		(width 0.1397)
		(layer "F.Cu")
		(net "I2C_C_SDA_ADM1276")
	)
	(segment
		(start 31.242 -363.5502)
		(end 31.242 -366.145572)
		(width 0.1397)
		(layer "F.Cu")
		(net "I2C_C_SDA_ADM1276")
	)
	(segment
		(start 31.242 -366.145572)
		(end 31.017972 -366.3696)
		(width 0.1397)
		(layer "F.Cu")
		(net "I2C_C_SDA_ADM1276")
	)
	(via
		(at 31.242 -363.5502)
		(size 0.7112)
		(drill 0.3556)
		(layers "F.Cu" "B.Cu")
		(net "I2C_C_SDA_ADM1276")
	)
	(segment
		(start 43.079924 -65.259966)
		(end 44.159932 -65.259966)
		(width 0.635)
		(layer "F.Cu")
		(net "P12VL")
	)
	(segment
		(start 40.539924 -71.799958)
		(end 40.539924 -72.879966)
		(width 0.635)
		(layer "F.Cu")
		(net "P12VL")
	)
	(segment
		(start 37.39642 -136.906)
		(end 37.39642 -137.9093)
		(width 0.3048)
		(layer "F.Cu")
		(net "P12VL")
	)
	(segment
		(start 41.999916 -70.339966)
		(end 43.079924 -70.339966)
		(width 0.635)
		(layer "F.Cu")
		(net "P12VL")
	)
	(segment
		(start 37.999924 -70.339966)
		(end 37.999924 -71.419974)
		(width 0.635)
		(layer "F.Cu")
		(net "P12VL")
	)
	(segment
		(start 41.999916 -72.879966)
		(end 43.079924 -72.879966)
		(width 0.635)
		(layer "F.Cu")
		(net "P12VL")
	)
	(segment
		(start 43.079924 -71.799958)
		(end 43.079924 -72.879966)
		(width 0.635)
		(layer "F.Cu")
		(net "P12VL")
	)
	(segment
		(start 45.619924 -69.259958)
		(end 45.619924 -70.339966)
		(width 0.635)
		(layer "F.Cu")
		(net "P12VL")
	)
	(segment
		(start 43.079924 -66.719958)
		(end 43.079924 -67.799966)
		(width 0.635)
		(layer "F.Cu")
		(net "P12VL")
	)
	(segment
		(start 45.619924 -66.719958)
		(end 45.619924 -67.799966)
		(width 0.635)
		(layer "F.Cu")
		(net "P12VL")
	)
	(segment
		(start 43.079924 -67.799966)
		(end 44.159932 -67.799966)
		(width 0.635)
		(layer "F.Cu")
		(net "P12VL")
	)
	(segment
		(start 40.539924 -70.339966)
		(end 40.539924 -71.419974)
		(width 0.635)
		(layer "F.Cu")
		(net "P12VL")
	)
	(segment
		(start 40.539924 -67.799966)
		(end 40.539924 -68.879974)
		(width 0.635)
		(layer "F.Cu")
		(net "P12VL")
	)
	(segment
		(start 45.619924 -72.879966)
		(end 46.699932 -72.879966)
		(width 0.635)
		(layer "F.Cu")
		(net "P12VL")
	)
	(segment
		(start 45.619924 -70.339966)
		(end 46.699932 -70.339966)
		(width 0.635)
		(layer "F.Cu")
		(net "P12VL")
	)
	(segment
		(start 41.999916 -67.799966)
		(end 43.079924 -67.799966)
		(width 0.635)
		(layer "F.Cu")
		(net "P12VL")
	)
	(segment
		(start 37.999924 -67.799966)
		(end 39.079932 -67.799966)
		(width 0.635)
		(layer "F.Cu")
		(net "P12VL")
	)
	(segment
		(start 40.539924 -66.719958)
		(end 40.539924 -67.799966)
		(width 0.635)
		(layer "F.Cu")
		(net "P12VL")
	)
	(segment
		(start 40.539924 -65.259966)
		(end 40.539924 -66.339974)
		(width 0.635)
		(layer "F.Cu")
		(net "P12VL")
	)
	(segment
		(start 37.999924 -66.719958)
		(end 37.999924 -67.799966)
		(width 0.635)
		(layer "F.Cu")
		(net "P12VL")
	)
	(segment
		(start 37.999924 -72.879966)
		(end 39.079932 -72.879966)
		(width 0.635)
		(layer "F.Cu")
		(net "P12VL")
	)
	(segment
		(start 37.999924 -69.259958)
		(end 37.999924 -70.339966)
		(width 0.635)
		(layer "F.Cu")
		(net "P12VL")
	)
	(segment
		(start 43.079924 -72.879966)
		(end 44.159932 -72.879966)
		(width 0.635)
		(layer "F.Cu")
		(net "P12VL")
	)
	(segment
		(start 45.619924 -65.259966)
		(end 45.619924 -66.339974)
		(width 0.635)
		(layer "F.Cu")
		(net "P12VL")
	)
	(segment
		(start 39.459916 -65.259966)
		(end 40.539924 -65.259966)
		(width 0.635)
		(layer "F.Cu")
		(net "P12VL")
	)
	(segment
		(start 43.079924 -72.879966)
		(end 43.079924 -73.959974)
		(width 0.635)
		(layer "F.Cu")
		(net "P12VL")
	)
	(segment
		(start 43.079924 -64.179958)
		(end 43.079924 -65.259966)
		(width 0.635)
		(layer "F.Cu")
		(net "P12VL")
	)
	(segment
		(start 39.459916 -70.339966)
		(end 40.539924 -70.339966)
		(width 0.635)
		(layer "F.Cu")
		(net "P12VL")
	)
	(segment
		(start 36.919916 -72.879966)
		(end 37.999924 -72.879966)
		(width 0.635)
		(layer "F.Cu")
		(net "P12VL")
	)
	(segment
		(start 44.539916 -70.339966)
		(end 45.619924 -70.339966)
		(width 0.635)
		(layer "F.Cu")
		(net "P12VL")
	)
	(segment
		(start 43.079924 -67.799966)
		(end 43.079924 -68.879974)
		(width 0.635)
		(layer "F.Cu")
		(net "P12VL")
	)
	(segment
		(start 43.079924 -70.339966)
		(end 43.079924 -71.419974)
		(width 0.635)
		(layer "F.Cu")
		(net "P12VL")
	)
	(segment
		(start 37.999924 -70.339966)
		(end 39.079932 -70.339966)
		(width 0.635)
		(layer "F.Cu")
		(net "P12VL")
	)
	(segment
		(start 40.539924 -70.339966)
		(end 41.619932 -70.339966)
		(width 0.635)
		(layer "F.Cu")
		(net "P12VL")
	)
	(segment
		(start 45.619924 -67.799966)
		(end 45.619924 -68.879974)
		(width 0.635)
		(layer "F.Cu")
		(net "P12VL")
	)
	(segment
		(start 39.459916 -72.879966)
		(end 40.539924 -72.879966)
		(width 0.635)
		(layer "F.Cu")
		(net "P12VL")
	)
	(segment
		(start 36.919916 -70.339966)
		(end 37.999924 -70.339966)
		(width 0.635)
		(layer "F.Cu")
		(net "P12VL")
	)
	(segment
		(start 37.999924 -65.259966)
		(end 39.079932 -65.259966)
		(width 0.635)
		(layer "F.Cu")
		(net "P12VL")
	)
	(segment
		(start 39.459916 -67.799966)
		(end 40.539924 -67.799966)
		(width 0.635)
		(layer "F.Cu")
		(net "P12VL")
	)
	(segment
		(start 43.079924 -65.259966)
		(end 43.079924 -66.339974)
		(width 0.635)
		(layer "F.Cu")
		(net "P12VL")
	)
	(segment
		(start 40.539924 -65.259966)
		(end 41.619932 -65.259966)
		(width 0.635)
		(layer "F.Cu")
		(net "P12VL")
	)
	(segment
		(start 45.619924 -65.259966)
		(end 46.699932 -65.259966)
		(width 0.635)
		(layer "F.Cu")
		(net "P12VL")
	)
	(segment
		(start 36.919916 -65.259966)
		(end 37.999924 -65.259966)
		(width 0.635)
		(layer "F.Cu")
		(net "P12VL")
	)
	(segment
		(start 31.0642 -146.05)
		(end 30.453838 -146.05)
		(width 0.508)
		(layer "F.Cu")
		(net "P12VL")
	)
	(segment
		(start 30.453838 -146.05)
		(end 29.6672 -146.836638)
		(width 0.508)
		(layer "F.Cu")
		(net "P12VL")
	)
	(segment
		(start 45.619924 -64.179958)
		(end 45.619924 -65.259966)
		(width 0.635)
		(layer "F.Cu")
		(net "P12VL")
	)
	(segment
		(start 29.6672 -146.836638)
		(end 29.6672 -148.627084)
		(width 0.508)
		(layer "F.Cu")
		(net "P12VL")
	)
	(segment
		(start 37.999924 -67.799966)
		(end 37.999924 -68.879974)
		(width 0.635)
		(layer "F.Cu")
		(net "P12VL")
	)
	(segment
		(start 45.619924 -70.339966)
		(end 45.619924 -71.419974)
		(width 0.635)
		(layer "F.Cu")
		(net "P12VL")
	)
	(segment
		(start 34.741866 -137.063734)
		(end 35.2044 -136.6012)
		(width 0.3048)
		(layer "F.Cu")
		(net "P12VL")
	)
	(segment
		(start 34.741866 -137.063734)
		(end 33.655 -137.063734)
		(width 0.508)
		(layer "F.Cu")
		(net "P12VL")
	)
	(segment
		(start 40.539924 -72.879966)
		(end 40.539924 -73.959974)
		(width 0.635)
		(layer "F.Cu")
		(net "P12VL")
	)
	(segment
		(start 36.919916 -67.799966)
		(end 37.999924 -67.799966)
		(width 0.635)
		(layer "F.Cu")
		(net "P12VL")
	)
	(segment
		(start 37.09162 -136.6012)
		(end 37.39642 -136.906)
		(width 0.3048)
		(layer "F.Cu")
		(net "P12VL")
	)
	(segment
		(start 37.999924 -65.259966)
		(end 37.999924 -66.339974)
		(width 0.635)
		(layer "F.Cu")
		(net "P12VL")
	)
	(segment
		(start 44.539916 -67.799966)
		(end 45.619924 -67.799966)
		(width 0.635)
		(layer "F.Cu")
		(net "P12VL")
	)
	(segment
		(start 43.079924 -69.259958)
		(end 43.079924 -70.339966)
		(width 0.635)
		(layer "F.Cu")
		(net "P12VL")
	)
	(segment
		(start 40.539924 -69.259958)
		(end 40.539924 -70.339966)
		(width 0.635)
		(layer "F.Cu")
		(net "P12VL")
	)
	(segment
		(start 41.999916 -65.259966)
		(end 43.079924 -65.259966)
		(width 0.635)
		(layer "F.Cu")
		(net "P12VL")
	)
	(segment
		(start 37.999924 -72.879966)
		(end 37.999924 -73.959974)
		(width 0.635)
		(layer "F.Cu")
		(net "P12VL")
	)
	(segment
		(start 45.619924 -72.879966)
		(end 45.619924 -73.959974)
		(width 0.635)
		(layer "F.Cu")
		(net "P12VL")
	)
	(segment
		(start 45.619924 -71.799958)
		(end 45.619924 -72.879966)
		(width 0.635)
		(layer "F.Cu")
		(net "P12VL")
	)
	(segment
		(start 45.619924 -67.799966)
		(end 46.699932 -67.799966)
		(width 0.635)
		(layer "F.Cu")
		(net "P12VL")
	)
	(segment
		(start 37.999924 -71.799958)
		(end 37.999924 -72.879966)
		(width 0.635)
		(layer "F.Cu")
		(net "P12VL")
	)
	(segment
		(start 44.539916 -65.259966)
		(end 45.619924 -65.259966)
		(width 0.635)
		(layer "F.Cu")
		(net "P12VL")
	)
	(segment
		(start 40.539924 -64.179958)
		(end 40.539924 -65.259966)
		(width 0.635)
		(layer "F.Cu")
		(net "P12VL")
	)
	(segment
		(start 37.999924 -64.179958)
		(end 37.999924 -65.259966)
		(width 0.635)
		(layer "F.Cu")
		(net "P12VL")
	)
	(segment
		(start 40.539924 -67.799966)
		(end 41.619932 -67.799966)
		(width 0.635)
		(layer "F.Cu")
		(net "P12VL")
	)
	(segment
		(start 43.079924 -70.339966)
		(end 44.159932 -70.339966)
		(width 0.635)
		(layer "F.Cu")
		(net "P12VL")
	)
	(segment
		(start 35.2044 -136.6012)
		(end 37.09162 -136.6012)
		(width 0.3048)
		(layer "F.Cu")
		(net "P12VL")
	)
	(segment
		(start 44.539916 -72.879966)
		(end 45.619924 -72.879966)
		(width 0.635)
		(layer "F.Cu")
		(net "P12VL")
	)
	(segment
		(start 40.539924 -72.879966)
		(end 41.619932 -72.879966)
		(width 0.635)
		(layer "F.Cu")
		(net "P12VL")
	)
	(via
		(at 46.228 -75.184)
		(size 0.7112)
		(drill 0.4064)
		(layers "F.Cu" "B.Cu")
		(net "P12VL")
	)
	(via
		(at 41.148 -75.184)
		(size 0.7112)
		(drill 0.4064)
		(layers "F.Cu" "B.Cu")
		(net "P12VL")
	)
	(via
		(at 34.036 -98.044)
		(size 0.7112)
		(drill 0.4064)
		(layers "F.Cu" "B.Cu")
		(net "P12VL")
	)
	(via
		(at 41.656 -80.264)
		(size 0.7112)
		(drill 0.4064)
		(layers "F.Cu" "B.Cu")
		(net "P12VL")
	)
	(via
		(at 38.1 -105.156)
		(size 0.7112)
		(drill 0.4064)
		(layers "F.Cu" "B.Cu")
		(net "P12VL")
	)
	(via
		(at 33.655 -137.063734)
		(size 0.5588)
		(drill 0.3048)
		(layers "F.Cu" "B.Cu")
		(net "P12VL")
	)
	(via
		(at 36.4236 -80.9498)
		(size 0.7112)
		(drill 0.4064)
		(layers "F.Cu" "B.Cu")
		(net "P12VL")
	)
	(via
		(at 31.7754 -103.8606)
		(size 0.7112)
		(drill 0.3556)
		(layers "F.Cu" "B.Cu")
		(net "P12VL")
	)
	(via
		(at 36.957 -108.458)
		(size 0.7112)
		(drill 0.4064)
		(layers "F.Cu" "B.Cu")
		(net "P12VL")
	)
	(via
		(at 29.972 -102.616)
		(size 0.7112)
		(drill 0.4064)
		(layers "F.Cu" "B.Cu")
		(net "P12VL")
	)
	(via
		(at 36.3982 -87.2236)
		(size 0.7112)
		(drill 0.4064)
		(layers "F.Cu" "B.Cu")
		(net "P12VL")
	)
	(via
		(at 36.4236 -103.6828)
		(size 0.7112)
		(drill 0.3556)
		(layers "F.Cu" "B.Cu")
		(net "P12VL")
	)
	(via
		(at 31.115 -108.966)
		(size 0.7112)
		(drill 0.3556)
		(layers "F.Cu" "B.Cu")
		(net "P12VL")
	)
	(via
		(at 33.02 -109.728)
		(size 0.7112)
		(drill 0.4064)
		(layers "F.Cu" "B.Cu")
		(net "P12VL")
	)
	(via
		(at 44.704 -76.708)
		(size 0.7112)
		(drill 0.4064)
		(layers "F.Cu" "B.Cu")
		(net "P12VL")
	)
	(via
		(at 42.164 -76.708)
		(size 0.7112)
		(drill 0.4064)
		(layers "F.Cu" "B.Cu")
		(net "P12VL")
	)
	(via
		(at 34.036 -105.156)
		(size 0.7112)
		(drill 0.4064)
		(layers "F.Cu" "B.Cu")
		(net "P12VL")
	)
	(via
		(at 34.036 -107.696)
		(size 0.7112)
		(drill 0.4064)
		(layers "F.Cu" "B.Cu")
		(net "P12VL")
	)
	(via
		(at 41.148 -109.728)
		(size 0.7112)
		(drill 0.4064)
		(layers "F.Cu" "B.Cu")
		(net "P12VL")
	)
	(via
		(at 38.1 -100.584)
		(size 0.7112)
		(drill 0.4064)
		(layers "F.Cu" "B.Cu")
		(net "P12VL")
	)
	(via
		(at 38.1 -107.696)
		(size 0.7112)
		(drill 0.4064)
		(layers "F.Cu" "B.Cu")
		(net "P12VL")
	)
	(via
		(at 43.688 -75.184)
		(size 0.7112)
		(drill 0.4064)
		(layers "F.Cu" "B.Cu")
		(net "P12VL")
	)
	(via
		(at 38.4302 -75.7428)
		(size 0.7112)
		(drill 0.4064)
		(layers "F.Cu" "B.Cu")
		(net "P12VL")
	)
	(via
		(at 44.323 -109.728)
		(size 0.7112)
		(drill 0.4064)
		(layers "F.Cu" "B.Cu")
		(net "P12VL")
	)
	(via
		(at 46.228 -78.74)
		(size 0.7112)
		(drill 0.4064)
		(layers "F.Cu" "B.Cu")
		(net "P12VL")
	)
	(via
		(at 34.036 -102.743)
		(size 0.7112)
		(drill 0.4064)
		(layers "F.Cu" "B.Cu")
		(net "P12VL")
	)
	(via
		(at 34.036 -100.584)
		(size 0.7112)
		(drill 0.4064)
		(layers "F.Cu" "B.Cu")
		(net "P12VL")
	)
	(via
		(at 34.417 -112.014)
		(size 0.5588)
		(drill 0.3048)
		(layers "F.Cu" "B.Cu")
		(net "P12VL")
	)
	(via
		(at 29.972 -107.696)
		(size 0.7112)
		(drill 0.4064)
		(layers "F.Cu" "B.Cu")
		(net "P12VL")
	)
	(via
		(at 36.068 -109.728)
		(size 0.7112)
		(drill 0.4064)
		(layers "F.Cu" "B.Cu")
		(net "P12VL")
	)
	(via
		(at 29.972 -100.584)
		(size 0.7112)
		(drill 0.4064)
		(layers "F.Cu" "B.Cu")
		(net "P12VL")
	)
	(via
		(at 46.736 -76.962)
		(size 0.7112)
		(drill 0.4064)
		(layers "F.Cu" "B.Cu")
		(net "P12VL")
	)
	(via
		(at 29.972 -105.156)
		(size 0.7112)
		(drill 0.4064)
		(layers "F.Cu" "B.Cu")
		(net "P12VL")
	)
	(via
		(at 38.1 -102.616)
		(size 0.7112)
		(drill 0.4064)
		(layers "F.Cu" "B.Cu")
		(net "P12VL")
	)
	(via
		(at 44.196 -80.264)
		(size 0.7112)
		(drill 0.4064)
		(layers "F.Cu" "B.Cu")
		(net "P12VL")
	)
	(via
		(at 31.0642 -146.05)
		(size 0.5588)
		(drill 0.3048)
		(layers "F.Cu" "B.Cu")
		(net "P12VL")
	)
	(via
		(at 38.1 -98.044)
		(size 0.7112)
		(drill 0.4064)
		(layers "F.Cu" "B.Cu")
		(net "P12VL")
	)
	(via
		(at 29.972 -98.044)
		(size 0.7112)
		(drill 0.4064)
		(layers "F.Cu" "B.Cu")
		(net "P12VL")
	)
	(via
		(at 43.688 -78.74)
		(size 0.7112)
		(drill 0.4064)
		(layers "F.Cu" "B.Cu")
		(net "P12VL")
	)
	(via
		(at 36.068 -73.914)
		(size 0.7112)
		(drill 0.4064)
		(layers "F.Cu" "B.Cu")
		(net "P12VL")
	)
	(segment
		(start 31.0642 -146.05)
		(end 31.3436 -146.05)
		(width 0.508)
		(layer "B.Cu")
		(net "P12VL")
	)
	(segment
		(start 37.7571 -115.080542)
		(end 37.7571 -132.961634)
		(width 0.508)
		(layer "B.Cu")
		(net "P12VL")
	)
	(segment
		(start 34.690558 -112.014)
		(end 37.7571 -115.080542)
		(width 0.508)
		(layer "B.Cu")
		(net "P12VL")
	)
	(segment
		(start 37.7571 -132.961634)
		(end 33.655 -137.063734)
		(width 0.508)
		(layer "B.Cu")
		(net "P12VL")
	)
	(segment
		(start 34.417 -112.014)
		(end 34.690558 -112.014)
		(width 0.508)
		(layer "B.Cu")
		(net "P12VL")
	)
	(segment
		(start 32.4866 -138.232134)
		(end 33.655 -137.063734)
		(width 0.508)
		(layer "B.Cu")
		(net "P12VL")
	)
	(segment
		(start 32.4866 -144.907)
		(end 32.4866 -138.232134)
		(width 0.508)
		(layer "B.Cu")
		(net "P12VL")
	)
	(segment
		(start 31.3436 -146.05)
		(end 32.4866 -144.907)
		(width 0.508)
		(layer "B.Cu")
		(net "P12VL")
	)
	(segment
		(start 28.120086 -70.339966)
		(end 28.120086 -71.419974)
		(width 0.635)
		(layer "F.Cu")
		(net "P12VU")
	)
	(segment
		(start 23.040086 -72.879966)
		(end 24.120094 -72.879966)
		(width 0.635)
		(layer "F.Cu")
		(net "P12VU")
	)
	(segment
		(start 19.420078 -65.259966)
		(end 20.500086 -65.259966)
		(width 0.635)
		(layer "F.Cu")
		(net "P12VU")
	)
	(segment
		(start 27.040078 -72.879966)
		(end 28.120086 -72.879966)
		(width 0.635)
		(layer "F.Cu")
		(net "P12VU")
	)
	(segment
		(start 24.500078 -72.879966)
		(end 25.580086 -72.879966)
		(width 0.635)
		(layer "F.Cu")
		(net "P12VU")
	)
	(segment
		(start 27.040078 -70.339966)
		(end 28.120086 -70.339966)
		(width 0.635)
		(layer "F.Cu")
		(net "P12VU")
	)
	(segment
		(start 23.040086 -66.719958)
		(end 23.040086 -67.799966)
		(width 0.635)
		(layer "F.Cu")
		(net "P12VU")
	)
	(segment
		(start 32.7406 -148.627084)
		(end 32.7406 -147.447)
		(width 0.508)
		(layer "F.Cu")
		(net "P12VU")
	)
	(segment
		(start 20.500086 -72.879966)
		(end 21.580094 -72.879966)
		(width 0.635)
		(layer "F.Cu")
		(net "P12VU")
	)
	(segment
		(start 20.500086 -70.339966)
		(end 20.500086 -71.419974)
		(width 0.635)
		(layer "F.Cu")
		(net "P12VU")
	)
	(segment
		(start 28.120086 -72.879966)
		(end 28.120086 -73.959974)
		(width 0.635)
		(layer "F.Cu")
		(net "P12VU")
	)
	(segment
		(start 18.7198 -137.1219)
		(end 18.8341 -137.2362)
		(width 0.3048)
		(layer "F.Cu")
		(net "P12VU")
	)
	(segment
		(start 25.580086 -70.339966)
		(end 25.580086 -71.419974)
		(width 0.635)
		(layer "F.Cu")
		(net "P12VU")
	)
	(segment
		(start 20.500086 -71.799958)
		(end 20.500086 -72.879966)
		(width 0.635)
		(layer "F.Cu")
		(net "P12VU")
	)
	(segment
		(start 23.040086 -72.879966)
		(end 23.040086 -73.959974)
		(width 0.635)
		(layer "F.Cu")
		(net "P12VU")
	)
	(segment
		(start 25.580086 -66.719958)
		(end 25.580086 -67.799966)
		(width 0.635)
		(layer "F.Cu")
		(net "P12VU")
	)
	(segment
		(start 20.500086 -66.719958)
		(end 20.500086 -67.799966)
		(width 0.635)
		(layer "F.Cu")
		(net "P12VU")
	)
	(segment
		(start 25.580086 -65.259966)
		(end 26.660094 -65.259966)
		(width 0.635)
		(layer "F.Cu")
		(net "P12VU")
	)
	(segment
		(start 19.420078 -72.879966)
		(end 20.500086 -72.879966)
		(width 0.635)
		(layer "F.Cu")
		(net "P12VU")
	)
	(segment
		(start 20.500086 -65.259966)
		(end 20.500086 -66.339974)
		(width 0.635)
		(layer "F.Cu")
		(net "P12VU")
	)
	(segment
		(start 21.960078 -67.799966)
		(end 23.040086 -67.799966)
		(width 0.635)
		(layer "F.Cu")
		(net "P12VU")
	)
	(segment
		(start 25.580086 -65.259966)
		(end 25.580086 -66.339974)
		(width 0.635)
		(layer "F.Cu")
		(net "P12VU")
	)
	(segment
		(start 25.580086 -67.799966)
		(end 25.580086 -68.879974)
		(width 0.635)
		(layer "F.Cu")
		(net "P12VU")
	)
	(segment
		(start 23.040086 -70.339966)
		(end 23.040086 -71.419974)
		(width 0.635)
		(layer "F.Cu")
		(net "P12VU")
	)
	(segment
		(start 20.9931 -137.2362)
		(end 19.7612 -137.2362)
		(width 0.3048)
		(layer "F.Cu")
		(net "P12VU")
	)
	(segment
		(start 21.960078 -72.879966)
		(end 23.040086 -72.879966)
		(width 0.635)
		(layer "F.Cu")
		(net "P12VU")
	)
	(segment
		(start 27.040078 -65.259966)
		(end 28.120086 -65.259966)
		(width 0.635)
		(layer "F.Cu")
		(net "P12VU")
	)
	(segment
		(start 25.580086 -70.339966)
		(end 26.660094 -70.339966)
		(width 0.635)
		(layer "F.Cu")
		(net "P12VU")
	)
	(segment
		(start 28.120086 -69.259958)
		(end 28.120086 -70.339966)
		(width 0.635)
		(layer "F.Cu")
		(net "P12VU")
	)
	(segment
		(start 20.500086 -69.259958)
		(end 20.500086 -70.339966)
		(width 0.635)
		(layer "F.Cu")
		(net "P12VU")
	)
	(segment
		(start 25.580086 -72.879966)
		(end 25.580086 -73.959974)
		(width 0.635)
		(layer "F.Cu")
		(net "P12VU")
	)
	(segment
		(start 20.500086 -67.799966)
		(end 21.580094 -67.799966)
		(width 0.635)
		(layer "F.Cu")
		(net "P12VU")
	)
	(segment
		(start 20.500086 -65.259966)
		(end 21.580094 -65.259966)
		(width 0.635)
		(layer "F.Cu")
		(net "P12VU")
	)
	(segment
		(start 21.19122 -138.3665)
		(end 21.19122 -137.43432)
		(width 0.3048)
		(layer "F.Cu")
		(net "P12VU")
	)
	(segment
		(start 23.040086 -67.799966)
		(end 24.120094 -67.799966)
		(width 0.635)
		(layer "F.Cu")
		(net "P12VU")
	)
	(segment
		(start 24.500078 -65.259966)
		(end 25.580086 -65.259966)
		(width 0.635)
		(layer "F.Cu")
		(net "P12VU")
	)
	(segment
		(start 27.040078 -67.799966)
		(end 28.120086 -67.799966)
		(width 0.635)
		(layer "F.Cu")
		(net "P12VU")
	)
	(segment
		(start 23.040086 -71.799958)
		(end 23.040086 -72.879966)
		(width 0.635)
		(layer "F.Cu")
		(net "P12VU")
	)
	(segment
		(start 21.960078 -65.259966)
		(end 23.040086 -65.259966)
		(width 0.635)
		(layer "F.Cu")
		(net "P12VU")
	)
	(segment
		(start 20.500086 -67.799966)
		(end 20.500086 -68.879974)
		(width 0.635)
		(layer "F.Cu")
		(net "P12VU")
	)
	(segment
		(start 24.500078 -67.799966)
		(end 25.580086 -67.799966)
		(width 0.635)
		(layer "F.Cu")
		(net "P12VU")
	)
	(segment
		(start 25.580086 -67.799966)
		(end 26.660094 -67.799966)
		(width 0.635)
		(layer "F.Cu")
		(net "P12VU")
	)
	(segment
		(start 28.120086 -66.719958)
		(end 28.120086 -67.799966)
		(width 0.635)
		(layer "F.Cu")
		(net "P12VU")
	)
	(segment
		(start 28.120086 -70.339966)
		(end 29.200094 -70.339966)
		(width 0.635)
		(layer "F.Cu")
		(net "P12VU")
	)
	(segment
		(start 21.960078 -70.339966)
		(end 23.040086 -70.339966)
		(width 0.635)
		(layer "F.Cu")
		(net "P12VU")
	)
	(segment
		(start 28.120086 -71.799958)
		(end 28.120086 -72.879966)
		(width 0.635)
		(layer "F.Cu")
		(net "P12VU")
	)
	(segment
		(start 23.040086 -69.259958)
		(end 23.040086 -70.339966)
		(width 0.635)
		(layer "F.Cu")
		(net "P12VU")
	)
	(segment
		(start 25.580086 -69.259958)
		(end 25.580086 -70.339966)
		(width 0.635)
		(layer "F.Cu")
		(net "P12VU")
	)
	(segment
		(start 25.580086 -71.799958)
		(end 25.580086 -72.879966)
		(width 0.635)
		(layer "F.Cu")
		(net "P12VU")
	)
	(segment
		(start 28.120086 -67.799966)
		(end 29.200094 -67.799966)
		(width 0.635)
		(layer "F.Cu")
		(net "P12VU")
	)
	(segment
		(start 21.19122 -137.43432)
		(end 20.9931 -137.2362)
		(width 0.3048)
		(layer "F.Cu")
		(net "P12VU")
	)
	(segment
		(start 24.500078 -70.339966)
		(end 25.580086 -70.339966)
		(width 0.635)
		(layer "F.Cu")
		(net "P12VU")
	)
	(segment
		(start 23.040086 -70.339966)
		(end 24.120094 -70.339966)
		(width 0.635)
		(layer "F.Cu")
		(net "P12VU")
	)
	(segment
		(start 28.120086 -65.259966)
		(end 28.120086 -66.339974)
		(width 0.635)
		(layer "F.Cu")
		(net "P12VU")
	)
	(segment
		(start 23.040086 -65.259966)
		(end 24.120094 -65.259966)
		(width 0.635)
		(layer "F.Cu")
		(net "P12VU")
	)
	(segment
		(start 19.420078 -67.799966)
		(end 20.500086 -67.799966)
		(width 0.635)
		(layer "F.Cu")
		(net "P12VU")
	)
	(segment
		(start 28.120086 -67.799966)
		(end 28.120086 -68.879974)
		(width 0.635)
		(layer "F.Cu")
		(net "P12VU")
	)
	(segment
		(start 20.500086 -72.879966)
		(end 20.500086 -73.959974)
		(width 0.635)
		(layer "F.Cu")
		(net "P12VU")
	)
	(segment
		(start 20.500086 -70.339966)
		(end 21.580094 -70.339966)
		(width 0.635)
		(layer "F.Cu")
		(net "P12VU")
	)
	(segment
		(start 18.8341 -137.2362)
		(end 19.7612 -137.2362)
		(width 0.3048)
		(layer "F.Cu")
		(net "P12VU")
	)
	(segment
		(start 25.580086 -72.879966)
		(end 26.660094 -72.879966)
		(width 0.635)
		(layer "F.Cu")
		(net "P12VU")
	)
	(segment
		(start 28.120086 -72.879966)
		(end 29.200094 -72.879966)
		(width 0.635)
		(layer "F.Cu")
		(net "P12VU")
	)
	(segment
		(start 23.040086 -65.259966)
		(end 23.040086 -66.339974)
		(width 0.635)
		(layer "F.Cu")
		(net "P12VU")
	)
	(segment
		(start 19.420078 -70.339966)
		(end 20.500086 -70.339966)
		(width 0.635)
		(layer "F.Cu")
		(net "P12VU")
	)
	(segment
		(start 23.040086 -67.799966)
		(end 23.040086 -68.879974)
		(width 0.635)
		(layer "F.Cu")
		(net "P12VU")
	)
	(via
		(at 21.9456 -104.267)
		(size 0.7112)
		(drill 0.4064)
		(layers "F.Cu" "B.Cu")
		(net "P12VU")
	)
	(via
		(at 19.304 -75.184)
		(size 0.7112)
		(drill 0.4064)
		(layers "F.Cu" "B.Cu")
		(net "P12VU")
	)
	(via
		(at 32.7406 -147.447)
		(size 0.5588)
		(drill 0.3048)
		(layers "F.Cu" "B.Cu")
		(net "P12VU")
	)
	(via
		(at 23.876 -77.216)
		(size 0.7112)
		(drill 0.4064)
		(layers "F.Cu" "B.Cu")
		(net "P12VU")
	)
	(via
		(at 17.272 -77.216)
		(size 0.7112)
		(drill 0.4064)
		(layers "F.Cu" "B.Cu")
		(net "P12VU")
	)
	(via
		(at 19.7612 -137.2362)
		(size 0.5588)
		(drill 0.3048)
		(layers "F.Cu" "B.Cu")
		(net "P12VU")
	)
	(via
		(at 21.844 -75.184)
		(size 0.7112)
		(drill 0.4064)
		(layers "F.Cu" "B.Cu")
		(net "P12VU")
	)
	(via
		(at 14.732 -103.632)
		(size 0.7112)
		(drill 0.4064)
		(layers "F.Cu" "B.Cu")
		(net "P12VU")
	)
	(via
		(at 18.796 -103.632)
		(size 0.7112)
		(drill 0.4064)
		(layers "F.Cu" "B.Cu")
		(net "P12VU")
	)
	(via
		(at 17.272 -81.28)
		(size 0.7112)
		(drill 0.4064)
		(layers "F.Cu" "B.Cu")
		(net "P12VU")
	)
	(via
		(at 16.764 -106.172)
		(size 0.7112)
		(drill 0.4064)
		(layers "F.Cu" "B.Cu")
		(net "P12VU")
	)
	(via
		(at 14.732 -106.045)
		(size 0.7112)
		(drill 0.4064)
		(layers "F.Cu" "B.Cu")
		(net "P12VU")
	)
	(via
		(at 18.796 -106.172)
		(size 0.7112)
		(drill 0.4064)
		(layers "F.Cu" "B.Cu")
		(net "P12VU")
	)
	(via
		(at 23.876 -81.28)
		(size 0.7112)
		(drill 0.4064)
		(layers "F.Cu" "B.Cu")
		(net "P12VU")
	)
	(via
		(at 14.732 -108.204)
		(size 0.7112)
		(drill 0.4064)
		(layers "F.Cu" "B.Cu")
		(net "P12VU")
	)
	(via
		(at 15.9766 -104.8766)
		(size 0.7112)
		(drill 0.3556)
		(layers "F.Cu" "B.Cu")
		(net "P12VU")
	)
	(via
		(at 17.272 -72.644)
		(size 0.7112)
		(drill 0.4064)
		(layers "F.Cu" "B.Cu")
		(net "P12VU")
	)
	(via
		(at 15.6718 -107.1626)
		(size 0.7112)
		(drill 0.3556)
		(layers "F.Cu" "B.Cu")
		(net "P12VU")
	)
	(via
		(at 16.0528 -97.8154)
		(size 0.7112)
		(drill 0.3556)
		(layers "F.Cu" "B.Cu")
		(net "P12VU")
	)
	(via
		(at 18.7198 -107.442)
		(size 0.7112)
		(drill 0.4064)
		(layers "F.Cu" "B.Cu")
		(net "P12VU")
	)
	(via
		(at 21.463 -109.982)
		(size 0.7112)
		(drill 0.4064)
		(layers "F.Cu" "B.Cu")
		(net "P12VU")
	)
	(via
		(at 20.574 -104.267)
		(size 0.7112)
		(drill 0.4064)
		(layers "F.Cu" "B.Cu")
		(net "P12VU")
	)
	(via
		(at 15.8496 -109.3724)
		(size 0.7112)
		(drill 0.3556)
		(layers "F.Cu" "B.Cu")
		(net "P12VU")
	)
	(via
		(at 23.876 -79.248)
		(size 0.7112)
		(drill 0.4064)
		(layers "F.Cu" "B.Cu")
		(net "P12VU")
	)
	(via
		(at 26.416 -77.216)
		(size 0.7112)
		(drill 0.4064)
		(layers "F.Cu" "B.Cu")
		(net "P12VU")
	)
	(via
		(at 14.732 -101.6)
		(size 0.7112)
		(drill 0.4064)
		(layers "F.Cu" "B.Cu")
		(net "P12VU")
	)
	(via
		(at 16.764 -108.204)
		(size 0.7112)
		(drill 0.4064)
		(layers "F.Cu" "B.Cu")
		(net "P12VU")
	)
	(via
		(at 16.764 -99.06)
		(size 0.7112)
		(drill 0.4064)
		(layers "F.Cu" "B.Cu")
		(net "P12VU")
	)
	(via
		(at 24.384 -75.184)
		(size 0.7112)
		(drill 0.4064)
		(layers "F.Cu" "B.Cu")
		(net "P12VU")
	)
	(via
		(at 18.796 -101.6)
		(size 0.7112)
		(drill 0.4064)
		(layers "F.Cu" "B.Cu")
		(net "P12VU")
	)
	(via
		(at 28.956 -75.184)
		(size 0.7112)
		(drill 0.4064)
		(layers "F.Cu" "B.Cu")
		(net "P12VU")
	)
	(via
		(at 16.764 -101.6)
		(size 0.7112)
		(drill 0.4064)
		(layers "F.Cu" "B.Cu")
		(net "P12VU")
	)
	(via
		(at 17.272 -79.248)
		(size 0.7112)
		(drill 0.4064)
		(layers "F.Cu" "B.Cu")
		(net "P12VU")
	)
	(via
		(at 26.924 -75.184)
		(size 0.7112)
		(drill 0.4064)
		(layers "F.Cu" "B.Cu")
		(net "P12VU")
	)
	(via
		(at 14.732 -99.06)
		(size 0.7112)
		(drill 0.4064)
		(layers "F.Cu" "B.Cu")
		(net "P12VU")
	)
	(via
		(at 22.479 -108.331)
		(size 0.7112)
		(drill 0.4064)
		(layers "F.Cu" "B.Cu")
		(net "P12VU")
	)
	(via
		(at 23.3426 -104.267)
		(size 0.7112)
		(drill 0.4064)
		(layers "F.Cu" "B.Cu")
		(net "P12VU")
	)
	(via
		(at 17.399 -110.3122)
		(size 0.7112)
		(drill 0.4064)
		(layers "F.Cu" "B.Cu")
		(net "P12VU")
	)
	(via
		(at 14.7574 -109.7026)
		(size 0.7112)
		(drill 0.4064)
		(layers "F.Cu" "B.Cu")
		(net "P12VU")
	)
	(via
		(at 25.908 -79.248)
		(size 0.7112)
		(drill 0.4064)
		(layers "F.Cu" "B.Cu")
		(net "P12VU")
	)
	(via
		(at 16.764 -103.632)
		(size 0.7112)
		(drill 0.4064)
		(layers "F.Cu" "B.Cu")
		(net "P12VU")
	)
	(via
		(at 16.026384 -110.37316)
		(size 0.7112)
		(drill 0.4064)
		(layers "F.Cu" "B.Cu")
		(net "P12VU")
	)
	(via
		(at 18.796 -99.06)
		(size 0.7112)
		(drill 0.4064)
		(layers "F.Cu" "B.Cu")
		(net "P12VU")
	)
	(via
		(at 17.272 -75.184)
		(size 0.7112)
		(drill 0.4064)
		(layers "F.Cu" "B.Cu")
		(net "P12VU")
	)
	(segment
		(start 19.7612 -135.185658)
		(end 19.771868 -135.17499)
		(width 0.508)
		(layer "B.Cu")
		(net "P12VU")
	)
	(segment
		(start 19.7612 -138.049)
		(end 28.575254 -146.863054)
		(width 0.508)
		(layer "B.Cu")
		(net "P12VU")
	)
	(segment
		(start 19.771868 -135.17499)
		(end 19.771868 -134.564374)
		(width 0.508)
		(layer "B.Cu")
		(net "P12VU")
	)
	(segment
		(start 19.7612 -137.2362)
		(end 19.7612 -135.185658)
		(width 0.508)
		(layer "B.Cu")
		(net "P12VU")
	)
	(segment
		(start 19.05 -113.396776)
		(end 16.026384 -110.37316)
		(width 0.508)
		(layer "B.Cu")
		(net "P12VU")
	)
	(segment
		(start 19.7612 -137.2362)
		(end 19.7612 -138.049)
		(width 0.508)
		(layer "B.Cu")
		(net "P12VU")
	)
	(segment
		(start 19.771868 -134.564374)
		(end 19.05 -133.842506)
		(width 0.508)
		(layer "B.Cu")
		(net "P12VU")
	)
	(segment
		(start 19.05 -133.842506)
		(end 19.05 -113.396776)
		(width 0.508)
		(layer "B.Cu")
		(net "P12VU")
	)
	(segment
		(start 32.156654 -146.863054)
		(end 32.7406 -147.447)
		(width 0.508)
		(layer "B.Cu")
		(net "P12VU")
	)
	(segment
		(start 28.575254 -146.863054)
		(end 32.156654 -146.863054)
		(width 0.508)
		(layer "B.Cu")
		(net "P12VU")
	)
	(segment
		(start 38.9128 -165.9128)
		(end 38.069266 -165.069266)
		(width 0.1397)
		(layer "F.Cu")
		(net "I2C_C_SCL_NCT7904")
	)
	(segment
		(start 38.069266 -165.069266)
		(end 37.70249 -165.069266)
		(width 0.1397)
		(layer "F.Cu")
		(net "I2C_C_SCL_NCT7904")
	)
	(segment
		(start 37.70249 -163.50869)
		(end 36.293806 -162.100006)
		(width 0.1397)
		(layer "F.Cu")
		(net "I2C_C_SCL_NCT7904")
	)
	(segment
		(start 37.70249 -165.069266)
		(end 37.70249 -163.50869)
		(width 0.1397)
		(layer "F.Cu")
		(net "I2C_C_SCL_NCT7904")
	)
	(segment
		(start 36.293806 -162.100006)
		(end 34.60369 -162.100006)
		(width 0.1397)
		(layer "F.Cu")
		(net "I2C_C_SCL_NCT7904")
	)
	(via
		(at 38.9128 -165.9128)
		(size 0.7112)
		(drill 0.3556)
		(layers "F.Cu" "B.Cu")
		(net "I2C_C_SCL_NCT7904")
	)
	(segment
		(start 35.751516 -162.599116)
		(end 36.8808 -163.7284)
		(width 0.1397)
		(layer "F.Cu")
		(net "I2C_C_SDA_NCT7904")
	)
	(segment
		(start 34.60369 -162.599116)
		(end 35.751516 -162.599116)
		(width 0.1397)
		(layer "F.Cu")
		(net "I2C_C_SDA_NCT7904")
	)
	(segment
		(start 37.181282 -164.028882)
		(end 37.181282 -164.765736)
		(width 0.1397)
		(layer "F.Cu")
		(net "I2C_C_SDA_NCT7904")
	)
	(segment
		(start 36.8808 -163.7284)
		(end 37.181282 -164.028882)
		(width 0.1397)
		(layer "F.Cu")
		(net "I2C_C_SDA_NCT7904")
	)
	(segment
		(start 37.181282 -164.765736)
		(end 36.877752 -165.069266)
		(width 0.1397)
		(layer "F.Cu")
		(net "I2C_C_SDA_NCT7904")
	)
	(segment
		(start 36.877752 -165.069266)
		(end 36.63569 -165.069266)
		(width 0.1397)
		(layer "F.Cu")
		(net "I2C_C_SDA_NCT7904")
	)
	(via
		(at 36.8808 -163.7284)
		(size 0.7112)
		(drill 0.3556)
		(layers "F.Cu" "B.Cu")
		(net "I2C_C_SDA_NCT7904")
	)
	(segment
		(start 35.8521 -255.2827)
		(end 35.8521 -254.3175)
		(width 0.1397)
		(layer "F.Cu")
		(net "I2C_C_SCL_LEDDRV")
	)
	(segment
		(start 35.3314 -253.9111)
		(end 35.3314 -252.1966)
		(width 0.1397)
		(layer "F.Cu")
		(net "I2C_C_SCL_LEDDRV")
	)
	(segment
		(start 35.3314 -252.1966)
		(end 36.195 -251.333)
		(width 0.1397)
		(layer "F.Cu")
		(net "I2C_C_SCL_LEDDRV")
	)
	(segment
		(start 36.3474 -255.778)
		(end 35.8521 -255.2827)
		(width 0.1397)
		(layer "F.Cu")
		(net "I2C_C_SCL_LEDDRV")
	)
	(segment
		(start 35.8521 -254.3175)
		(end 35.4457 -253.9111)
		(width 0.1397)
		(layer "F.Cu")
		(net "I2C_C_SCL_LEDDRV")
	)
	(segment
		(start 36.195 -251.333)
		(end 36.195 -249.36196)
		(width 0.1397)
		(layer "F.Cu")
		(net "I2C_C_SCL_LEDDRV")
	)
	(segment
		(start 36.3474 -255.8034)
		(end 36.3474 -255.778)
		(width 0.1397)
		(layer "F.Cu")
		(net "I2C_C_SCL_LEDDRV")
	)
	(segment
		(start 36.195 -249.36196)
		(end 36.18484 -249.3518)
		(width 0.1397)
		(layer "F.Cu")
		(net "I2C_C_SCL_LEDDRV")
	)
	(segment
		(start 35.4457 -253.9111)
		(end 35.3314 -253.9111)
		(width 0.1397)
		(layer "F.Cu")
		(net "I2C_C_SCL_LEDDRV")
	)
	(via
		(at 36.3474 -255.8034)
		(size 0.7112)
		(drill 0.3556)
		(layers "F.Cu" "B.Cu")
		(net "I2C_C_SCL_LEDDRV")
	)
	(segment
		(start 35.433 -241.0079)
		(end 35.687 -240.7539)
		(width 0.1397)
		(layer "F.Cu")
		(net "LED_DRV_A2")
	)
	(segment
		(start 35.433 -241.935)
		(end 35.433 -241.681)
		(width 0.1397)
		(layer "F.Cu")
		(net "LED_DRV_A2")
	)
	(segment
		(start 36.18484 -242.68684)
		(end 35.433 -241.935)
		(width 0.1397)
		(layer "F.Cu")
		(net "LED_DRV_A2")
	)
	(segment
		(start 36.18484 -243.713)
		(end 36.18484 -242.68684)
		(width 0.1397)
		(layer "F.Cu")
		(net "LED_DRV_A2")
	)
	(segment
		(start 35.433 -241.681)
		(end 35.433 -241.0079)
		(width 0.1397)
		(layer "F.Cu")
		(net "LED_DRV_A2")
	)
	(via
		(at 35.433 -241.681)
		(size 0.7112)
		(drill 0.3556)
		(layers "F.Cu" "B.Cu")
		(net "LED_DRV_A2")
	)
	(segment
		(start 35.5346 -242.6716)
		(end 35.5346 -243.713)
		(width 0.1397)
		(layer "F.Cu")
		(net "LED_DRV_A1")
	)
	(segment
		(start 35.433 -242.57)
		(end 35.5346 -242.6716)
		(width 0.1397)
		(layer "F.Cu")
		(net "LED_DRV_A1")
	)
	(segment
		(start 33.909 -242.062)
		(end 34.417 -242.57)
		(width 0.1397)
		(layer "F.Cu")
		(net "LED_DRV_A1")
	)
	(segment
		(start 33.909 -242.062)
		(end 33.909 -241.3889)
		(width 0.1397)
		(layer "F.Cu")
		(net "LED_DRV_A1")
	)
	(segment
		(start 34.417 -242.57)
		(end 35.433 -242.57)
		(width 0.1397)
		(layer "F.Cu")
		(net "LED_DRV_A1")
	)
	(segment
		(start 33.909 -241.3889)
		(end 34.544 -240.7539)
		(width 0.1397)
		(layer "F.Cu")
		(net "LED_DRV_A1")
	)
	(via
		(at 33.909 -242.062)
		(size 0.7112)
		(drill 0.3556)
		(layers "F.Cu" "B.Cu")
		(net "LED_DRV_A1")
	)
	(segment
		(start 33.02 -241.554)
		(end 33.02 -243.14785)
		(width 0.1397)
		(layer "F.Cu")
		(net "LED_DRV_A0")
	)
	(segment
		(start 33.249362 -243.434362)
		(end 33.528 -243.713)
		(width 0.1397)
		(layer "F.Cu")
		(net "LED_DRV_A0")
	)
	(segment
		(start 33.02 -243.14785)
		(end 33.249362 -243.377212)
		(width 0.1397)
		(layer "F.Cu")
		(net "LED_DRV_A0")
	)
	(segment
		(start 33.528 -243.713)
		(end 34.88436 -243.713)
		(width 0.1397)
		(layer "F.Cu")
		(net "LED_DRV_A0")
	)
	(segment
		(start 33.401 -241.173)
		(end 33.02 -241.554)
		(width 0.1397)
		(layer "F.Cu")
		(net "LED_DRV_A0")
	)
	(segment
		(start 33.249362 -243.377212)
		(end 33.249362 -243.434362)
		(width 0.1397)
		(layer "F.Cu")
		(net "LED_DRV_A0")
	)
	(segment
		(start 33.401 -240.7539)
		(end 33.401 -241.173)
		(width 0.1397)
		(layer "F.Cu")
		(net "LED_DRV_A0")
	)
	(via
		(at 33.249362 -243.377212)
		(size 0.7112)
		(drill 0.3556)
		(layers "F.Cu" "B.Cu")
		(net "LED_DRV_A0")
	)
	(segment
		(start 38.354 -379.476)
		(end 38.989 -380.111)
		(width 0.508)
		(layer "F.Cu")
		(net "ADM1276_GATE_DRV3")
	)
	(segment
		(start 45.085 -400.177)
		(end 45.085 -398.653)
		(width 0.508)
		(layer "F.Cu")
		(net "ADM1276_GATE_DRV3")
	)
	(segment
		(start 38.354 -378.7775)
		(end 38.354 -379.476)
		(width 0.508)
		(layer "F.Cu")
		(net "ADM1276_GATE_DRV3")
	)
	(via
		(at 45.085 -398.653)
		(size 0.5588)
		(drill 0.3048)
		(layers "F.Cu" "B.Cu")
		(net "ADM1276_GATE_DRV3")
	)
	(via
		(at 38.989 -380.111)
		(size 0.5588)
		(drill 0.3048)
		(layers "F.Cu" "B.Cu")
		(net "ADM1276_GATE_DRV3")
	)
	(via
		(at 39.878 -388.112)
		(size 0.7112)
		(drill 0.3556)
		(layers "F.Cu" "B.Cu")
		(net "ADM1276_GATE_DRV3")
	)
	(segment
		(start 45.085 -398.653)
		(end 44.043092 -398.653)
		(width 0.508)
		(layer "B.Cu")
		(net "ADM1276_GATE_DRV3")
	)
	(segment
		(start 39.878 -381)
		(end 39.878 -388.112)
		(width 0.508)
		(layer "B.Cu")
		(net "ADM1276_GATE_DRV3")
	)
	(segment
		(start 38.989 -380.111)
		(end 39.878 -381)
		(width 0.508)
		(layer "B.Cu")
		(net "ADM1276_GATE_DRV3")
	)
	(segment
		(start 39.878 -394.487908)
		(end 39.878 -388.112)
		(width 0.508)
		(layer "B.Cu")
		(net "ADM1276_GATE_DRV3")
	)
	(segment
		(start 44.043092 -398.653)
		(end 39.878 -394.487908)
		(width 0.508)
		(layer "B.Cu")
		(net "ADM1276_GATE_DRV3")
	)
	(segment
		(start 36.449 -400.177)
		(end 36.449 -398.154652)
		(width 0.508)
		(layer "F.Cu")
		(net "ADM1276_GATE_DRV2")
	)
	(segment
		(start 37.211 -378.7775)
		(end 37.211 -380.238)
		(width 0.508)
		(layer "F.Cu")
		(net "ADM1276_GATE_DRV2")
	)
	(segment
		(start 36.449 -398.154652)
		(end 36.453572 -398.15008)
		(width 0.508)
		(layer "F.Cu")
		(net "ADM1276_GATE_DRV2")
	)
	(segment
		(start 37.211 -380.238)
		(end 37.465 -380.492)
		(width 0.508)
		(layer "F.Cu")
		(net "ADM1276_GATE_DRV2")
	)
	(via
		(at 36.453572 -391.16)
		(size 0.7112)
		(drill 0.3556)
		(layers "F.Cu" "B.Cu")
		(net "ADM1276_GATE_DRV2")
	)
	(via
		(at 37.465 -382.27)
		(size 0.7112)
		(drill 0.3556)
		(layers "F.Cu" "B.Cu")
		(net "ADM1276_GATE_DRV2")
	)
	(via
		(at 36.453572 -398.15008)
		(size 0.5588)
		(drill 0.3048)
		(layers "F.Cu" "B.Cu")
		(net "ADM1276_GATE_DRV2")
	)
	(via
		(at 37.465 -380.492)
		(size 0.5588)
		(drill 0.3048)
		(layers "F.Cu" "B.Cu")
		(net "ADM1276_GATE_DRV2")
	)
	(segment
		(start 36.453572 -391.16)
		(end 36.453572 -387.472428)
		(width 0.508)
		(layer "B.Cu")
		(net "ADM1276_GATE_DRV2")
	)
	(segment
		(start 37.465 -386.461)
		(end 37.465 -382.27)
		(width 0.508)
		(layer "B.Cu")
		(net "ADM1276_GATE_DRV2")
	)
	(segment
		(start 36.453572 -398.15008)
		(end 36.453572 -391.16)
		(width 0.508)
		(layer "B.Cu")
		(net "ADM1276_GATE_DRV2")
	)
	(segment
		(start 36.453572 -387.472428)
		(end 37.465 -386.461)
		(width 0.508)
		(layer "B.Cu")
		(net "ADM1276_GATE_DRV2")
	)
	(segment
		(start 37.465 -380.492)
		(end 37.465 -382.27)
		(width 0.508)
		(layer "B.Cu")
		(net "ADM1276_GATE_DRV2")
	)
	(segment
		(start 30.89656 -250.2408)
		(end 30.89656 -253.03226)
		(width 0.1397)
		(layer "F.Cu")
		(net "I2C_C_SDA_EEPROM")
	)
	(segment
		(start 31.3182 -253.4539)
		(end 31.4579 -253.5936)
		(width 0.1397)
		(layer "F.Cu")
		(net "I2C_C_SDA_EEPROM")
	)
	(segment
		(start 30.89656 -253.03226)
		(end 31.3182 -253.4539)
		(width 0.1397)
		(layer "F.Cu")
		(net "I2C_C_SDA_EEPROM")
	)
	(segment
		(start 31.4579 -253.5936)
		(end 32.4358 -253.5936)
		(width 0.1397)
		(layer "F.Cu")
		(net "I2C_C_SDA_EEPROM")
	)
	(via
		(at 32.4358 -253.5936)
		(size 0.7112)
		(drill 0.3556)
		(layers "F.Cu" "B.Cu")
		(net "I2C_C_SDA_EEPROM")
	)
	(segment
		(start 36.068 -378.7775)
		(end 36.068 -379.6792)
		(width 0.508)
		(layer "F.Cu")
		(net "ADM1276_GATE_DRV1")
	)
	(segment
		(start 27.559 -400.177)
		(end 27.559 -398.526)
		(width 0.508)
		(layer "F.Cu")
		(net "ADM1276_GATE_DRV1")
	)
	(via
		(at 27.559 -395.351)
		(size 0.7112)
		(drill 0.3556)
		(layers "F.Cu" "B.Cu")
		(net "ADM1276_GATE_DRV1")
	)
	(via
		(at 27.559 -398.526)
		(size 0.5588)
		(drill 0.3048)
		(layers "F.Cu" "B.Cu")
		(net "ADM1276_GATE_DRV1")
	)
	(via
		(at 34.036 -385.953)
		(size 0.7112)
		(drill 0.3556)
		(layers "F.Cu" "B.Cu")
		(net "ADM1276_GATE_DRV1")
	)
	(via
		(at 36.068 -379.6792)
		(size 0.5588)
		(drill 0.3048)
		(layers "F.Cu" "B.Cu")
		(net "ADM1276_GATE_DRV1")
	)
	(segment
		(start 34.036 -385.826)
		(end 36.068 -383.794)
		(width 0.508)
		(layer "B.Cu")
		(net "ADM1276_GATE_DRV1")
	)
	(segment
		(start 27.559 -395.351)
		(end 27.559 -398.526)
		(width 0.508)
		(layer "B.Cu")
		(net "ADM1276_GATE_DRV1")
	)
	(segment
		(start 34.036 -385.953)
		(end 34.036 -385.826)
		(width 0.508)
		(layer "B.Cu")
		(net "ADM1276_GATE_DRV1")
	)
	(segment
		(start 27.559 -395.351)
		(end 27.559 -392.4046)
		(width 0.508)
		(layer "B.Cu")
		(net "ADM1276_GATE_DRV1")
	)
	(segment
		(start 34.0106 -385.953)
		(end 34.036 -385.953)
		(width 0.508)
		(layer "B.Cu")
		(net "ADM1276_GATE_DRV1")
	)
	(segment
		(start 36.068 -383.794)
		(end 36.068 -379.6792)
		(width 0.508)
		(layer "B.Cu")
		(net "ADM1276_GATE_DRV1")
	)
	(segment
		(start 27.559 -392.4046)
		(end 34.0106 -385.953)
		(width 0.508)
		(layer "B.Cu")
		(net "ADM1276_GATE_DRV1")
	)
	(segment
		(start 30.3022 -253.4539)
		(end 30.24632 -253.39802)
		(width 0.1397)
		(layer "F.Cu")
		(net "I2C_C_SCL_EEPROM")
	)
	(segment
		(start 30.24632 -252.1966)
		(end 30.24632 -250.2408)
		(width 0.1397)
		(layer "F.Cu")
		(net "I2C_C_SCL_EEPROM")
	)
	(segment
		(start 30.24632 -253.39802)
		(end 30.24632 -252.1966)
		(width 0.1397)
		(layer "F.Cu")
		(net "I2C_C_SCL_EEPROM")
	)
	(via
		(at 30.24632 -252.1966)
		(size 0.7112)
		(drill 0.3556)
		(layers "F.Cu" "B.Cu")
		(net "I2C_C_SCL_EEPROM")
	)
	(segment
		(start 40.132 -120.3452)
		(end 41.9862 -122.1994)
		(width 0.508)
		(layer "F.Cu")
		(net "P12VL_NET")
	)
	(segment
		(start 39.7891 -134.0866)
		(end 39.5224 -134.3533)
		(width 0.508)
		(layer "F.Cu")
		(net "P12VL_NET")
	)
	(segment
		(start 41.275 -134.0866)
		(end 39.7891 -134.0866)
		(width 0.508)
		(layer "F.Cu")
		(net "P12VL_NET")
	)
	(segment
		(start 41.9862 -122.1994)
		(end 41.9862 -122.174)
		(width 0.508)
		(layer "F.Cu")
		(net "P12VL_NET")
	)
	(segment
		(start 40.132 -120.154192)
		(end 40.132 -120.3452)
		(width 0.508)
		(layer "F.Cu")
		(net "P12VL_NET")
	)
	(segment
		(start 44.006008 -120.154192)
		(end 44.704 -120.154192)
		(width 0.508)
		(layer "F.Cu")
		(net "P12VL_NET")
	)
	(segment
		(start 41.9862 -122.174)
		(end 44.006008 -120.154192)
		(width 0.508)
		(layer "F.Cu")
		(net "P12VL_NET")
	)
	(via
		(at 49.403 -120.523)
		(size 0.7112)
		(drill 0.4064)
		(layers "F.Cu" "B.Cu")
		(net "P12VL_NET")
	)
	(via
		(at 33.147 -118.872)
		(size 0.7112)
		(drill 0.4064)
		(layers "F.Cu" "B.Cu")
		(net "P12VL_NET")
	)
	(via
		(at 33.147 -120.523)
		(size 0.7112)
		(drill 0.4064)
		(layers "F.Cu" "B.Cu")
		(net "P12VL_NET")
	)
	(via
		(at 49.6824 -113.665)
		(size 0.7112)
		(drill 0.4064)
		(layers "F.Cu" "B.Cu")
		(net "P12VL_NET")
	)
	(via
		(at 49.657 -115.189)
		(size 0.7112)
		(drill 0.4064)
		(layers "F.Cu" "B.Cu")
		(net "P12VL_NET")
	)
	(via
		(at 48.320706 -113.652046)
		(size 0.7112)
		(drill 0.4064)
		(layers "F.Cu" "B.Cu")
		(net "P12VL_NET")
	)
	(via
		(at 33.274 -113.538)
		(size 0.7112)
		(drill 0.4064)
		(layers "F.Cu" "B.Cu")
		(net "P12VL_NET")
	)
	(via
		(at 41.9862 -122.1994)
		(size 0.5588)
		(drill 0.3048)
		(layers "F.Cu" "B.Cu")
		(net "P12VL_NET")
	)
	(via
		(at 34.417 -118.872)
		(size 0.7112)
		(drill 0.4064)
		(layers "F.Cu" "B.Cu")
		(net "P12VL_NET")
	)
	(via
		(at 34.544 -113.538)
		(size 0.7112)
		(drill 0.4064)
		(layers "F.Cu" "B.Cu")
		(net "P12VL_NET")
	)
	(via
		(at 36.6776 -119.5832)
		(size 0.7112)
		(drill 0.3556)
		(layers "F.Cu" "B.Cu")
		(net "P12VL_NET")
	)
	(via
		(at 34.417 -120.523)
		(size 0.7112)
		(drill 0.4064)
		(layers "F.Cu" "B.Cu")
		(net "P12VL_NET")
	)
	(via
		(at 41.0464 -113.2586)
		(size 0.7112)
		(drill 0.4064)
		(layers "F.Cu" "B.Cu")
		(net "P12VL_NET")
	)
	(via
		(at 34.417 -115.316)
		(size 0.7112)
		(drill 0.4064)
		(layers "F.Cu" "B.Cu")
		(net "P12VL_NET")
	)
	(via
		(at 34.417 -117.094)
		(size 0.7112)
		(drill 0.4064)
		(layers "F.Cu" "B.Cu")
		(net "P12VL_NET")
	)
	(via
		(at 49.53 -116.967)
		(size 0.7112)
		(drill 0.4064)
		(layers "F.Cu" "B.Cu")
		(net "P12VL_NET")
	)
	(via
		(at 33.147 -115.316)
		(size 0.7112)
		(drill 0.4064)
		(layers "F.Cu" "B.Cu")
		(net "P12VL_NET")
	)
	(via
		(at 41.275 -134.0866)
		(size 0.5588)
		(drill 0.3048)
		(layers "F.Cu" "B.Cu")
		(net "P12VL_NET")
	)
	(via
		(at 47.879 -120.523)
		(size 0.7112)
		(drill 0.4064)
		(layers "F.Cu" "B.Cu")
		(net "P12VL_NET")
	)
	(via
		(at 41.1226 -117.6782)
		(size 0.7112)
		(drill 0.4064)
		(layers "F.Cu" "B.Cu")
		(net "P12VL_NET")
	)
	(via
		(at 33.147 -117.094)
		(size 0.7112)
		(drill 0.4064)
		(layers "F.Cu" "B.Cu")
		(net "P12VL_NET")
	)
	(via
		(at 48.2346 -116.967)
		(size 0.7112)
		(drill 0.4064)
		(layers "F.Cu" "B.Cu")
		(net "P12VL_NET")
	)
	(via
		(at 41.1226 -114.7064)
		(size 0.7112)
		(drill 0.4064)
		(layers "F.Cu" "B.Cu")
		(net "P12VL_NET")
	)
	(via
		(at 48.2346 -118.745)
		(size 0.7112)
		(drill 0.4064)
		(layers "F.Cu" "B.Cu")
		(net "P12VL_NET")
	)
	(via
		(at 48.3616 -115.189)
		(size 0.7112)
		(drill 0.4064)
		(layers "F.Cu" "B.Cu")
		(net "P12VL_NET")
	)
	(via
		(at 49.53 -118.745)
		(size 0.7112)
		(drill 0.4064)
		(layers "F.Cu" "B.Cu")
		(net "P12VL_NET")
	)
	(via
		(at 41.148 -116.2304)
		(size 0.7112)
		(drill 0.4064)
		(layers "F.Cu" "B.Cu")
		(net "P12VL_NET")
	)
	(segment
		(start 41.9862 -124.1806)
		(end 41.275 -124.8918)
		(width 0.508)
		(layer "B.Cu")
		(net "P12VL_NET")
	)
	(segment
		(start 41.275 -124.8918)
		(end 41.275 -134.0866)
		(width 0.508)
		(layer "B.Cu")
		(net "P12VL_NET")
	)
	(segment
		(start 41.9862 -122.1994)
		(end 41.9862 -124.1806)
		(width 0.508)
		(layer "B.Cu")
		(net "P12VL_NET")
	)
	(segment
		(start 19.8628 -122.3518)
		(end 21.933408 -120.281192)
		(width 0.508)
		(layer "F.Cu")
		(net "P12VU_NET")
	)
	(segment
		(start 21.6535 -134.7343)
		(end 22.2758 -134.112)
		(width 0.508)
		(layer "F.Cu")
		(net "P12VU_NET")
	)
	(segment
		(start 18.288 -120.281192)
		(end 18.288 -120.777)
		(width 0.508)
		(layer "F.Cu")
		(net "P12VU_NET")
	)
	(segment
		(start 18.288 -120.777)
		(end 19.8628 -122.3518)
		(width 0.508)
		(layer "F.Cu")
		(net "P12VU_NET")
	)
	(segment
		(start 21.933408 -120.281192)
		(end 22.86 -120.281192)
		(width 0.508)
		(layer "F.Cu")
		(net "P12VU_NET")
	)
	(segment
		(start 20.6756 -134.7343)
		(end 21.6535 -134.7343)
		(width 0.508)
		(layer "F.Cu")
		(net "P12VU_NET")
	)
	(via
		(at 29.718 -116.967)
		(size 0.7112)
		(drill 0.4064)
		(layers "F.Cu" "B.Cu")
		(net "P12VU_NET")
	)
	(via
		(at 29.718 -115.57)
		(size 0.7112)
		(drill 0.4064)
		(layers "F.Cu" "B.Cu")
		(net "P12VU_NET")
	)
	(via
		(at 31.115 -114.427)
		(size 0.7112)
		(drill 0.4064)
		(layers "F.Cu" "B.Cu")
		(net "P12VU_NET")
	)
	(via
		(at 28.321 -120.142)
		(size 0.7112)
		(drill 0.4064)
		(layers "F.Cu" "B.Cu")
		(net "P12VU_NET")
	)
	(via
		(at 27.051 -119.253)
		(size 0.7112)
		(drill 0.3556)
		(layers "F.Cu" "B.Cu")
		(net "P12VU_NET")
	)
	(via
		(at 15.9004 -118.999)
		(size 0.7112)
		(drill 0.4064)
		(layers "F.Cu" "B.Cu")
		(net "P12VU_NET")
	)
	(via
		(at 22.8092 -113.284)
		(size 0.7112)
		(drill 0.4064)
		(layers "F.Cu" "B.Cu")
		(net "P12VU_NET")
	)
	(via
		(at 16.256 -114.554)
		(size 0.7112)
		(drill 0.4064)
		(layers "F.Cu" "B.Cu")
		(net "P12VU_NET")
	)
	(via
		(at 29.718 -118.364)
		(size 0.7112)
		(drill 0.4064)
		(layers "F.Cu" "B.Cu")
		(net "P12VU_NET")
	)
	(via
		(at 29.337 -121.0818)
		(size 0.7112)
		(drill 0.3556)
		(layers "F.Cu" "B.Cu")
		(net "P12VU_NET")
	)
	(via
		(at 16.0782 -117.9576)
		(size 0.7112)
		(drill 0.4064)
		(layers "F.Cu" "B.Cu")
		(net "P12VU_NET")
	)
	(via
		(at 29.718 -114.046)
		(size 0.7112)
		(drill 0.4064)
		(layers "F.Cu" "B.Cu")
		(net "P12VU_NET")
	)
	(via
		(at 16.256 -116.84)
		(size 0.7112)
		(drill 0.4064)
		(layers "F.Cu" "B.Cu")
		(net "P12VU_NET")
	)
	(via
		(at 25.273 -120.142)
		(size 0.7112)
		(drill 0.4064)
		(layers "F.Cu" "B.Cu")
		(net "P12VU_NET")
	)
	(via
		(at 31.115 -119.253)
		(size 0.7112)
		(drill 0.4064)
		(layers "F.Cu" "B.Cu")
		(net "P12VU_NET")
	)
	(via
		(at 31.115 -116.205)
		(size 0.7112)
		(drill 0.4064)
		(layers "F.Cu" "B.Cu")
		(net "P12VU_NET")
	)
	(via
		(at 31.115 -117.729)
		(size 0.7112)
		(drill 0.4064)
		(layers "F.Cu" "B.Cu")
		(net "P12VU_NET")
	)
	(via
		(at 29.718 -119.761)
		(size 0.7112)
		(drill 0.4064)
		(layers "F.Cu" "B.Cu")
		(net "P12VU_NET")
	)
	(via
		(at 22.2758 -134.112)
		(size 0.5588)
		(drill 0.3048)
		(layers "F.Cu" "B.Cu")
		(net "P12VU_NET")
	)
	(via
		(at 22.8092 -115.0366)
		(size 0.7112)
		(drill 0.4064)
		(layers "F.Cu" "B.Cu")
		(net "P12VU_NET")
	)
	(via
		(at 22.8092 -116.586)
		(size 0.7112)
		(drill 0.4064)
		(layers "F.Cu" "B.Cu")
		(net "P12VU_NET")
	)
	(via
		(at 15.875 -120.1166)
		(size 0.7112)
		(drill 0.4064)
		(layers "F.Cu" "B.Cu")
		(net "P12VU_NET")
	)
	(via
		(at 22.8092 -118.0592)
		(size 0.7112)
		(drill 0.4064)
		(layers "F.Cu" "B.Cu")
		(net "P12VU_NET")
	)
	(via
		(at 16.256 -113.411)
		(size 0.7112)
		(drill 0.4064)
		(layers "F.Cu" "B.Cu")
		(net "P12VU_NET")
	)
	(via
		(at 16.256 -115.697)
		(size 0.7112)
		(drill 0.4064)
		(layers "F.Cu" "B.Cu")
		(net "P12VU_NET")
	)
	(via
		(at 19.8628 -122.3518)
		(size 0.7112)
		(drill 0.4064)
		(layers "F.Cu" "B.Cu")
		(net "P12VU_NET")
	)
	(via
		(at 30.861 -120.777)
		(size 0.7112)
		(drill 0.4064)
		(layers "F.Cu" "B.Cu")
		(net "P12VU_NET")
	)
	(via
		(at 15.875 -121.158)
		(size 0.7112)
		(drill 0.4064)
		(layers "F.Cu" "B.Cu")
		(net "P12VU_NET")
	)
	(segment
		(start 19.8628 -124.758196)
		(end 19.8628 -122.3518)
		(width 0.508)
		(layer "B.Cu")
		(net "P12VU_NET")
	)
	(segment
		(start 22.2758 -133.927342)
		(end 22.8092 -133.393942)
		(width 0.508)
		(layer "B.Cu")
		(net "P12VU_NET")
	)
	(segment
		(start 22.8092 -127.704596)
		(end 19.8628 -124.758196)
		(width 0.508)
		(layer "B.Cu")
		(net "P12VU_NET")
	)
	(segment
		(start 22.2758 -134.112)
		(end 22.2758 -133.927342)
		(width 0.508)
		(layer "B.Cu")
		(net "P12VU_NET")
	)
	(segment
		(start 22.8092 -133.393942)
		(end 22.8092 -127.704596)
		(width 0.508)
		(layer "B.Cu")
		(net "P12VU_NET")
	)
	(segment
		(start 41.7068 -138.3665)
		(end 41.4909 -138.5824)
		(width 0.508)
		(layer "F.Cu")
		(net "P12VL_2490_RC")
	)
	(segment
		(start 41.4909 -138.5824)
		(end 41.4909 -139.5222)
		(width 0.508)
		(layer "F.Cu")
		(net "P12VL_2490_RC")
	)
	(segment
		(start 41.7068 -137.6426)
		(end 41.7068 -138.3665)
		(width 0.508)
		(layer "F.Cu")
		(net "P12VL_2490_RC")
	)
	(via
		(at 41.7068 -137.6426)
		(size 0.7112)
		(drill 0.3556)
		(layers "F.Cu" "B.Cu")
		(net "P12VL_2490_RC")
	)
	(segment
		(start 28.321 -111.633)
		(end 28.829 -111.125)
		(width 0.508)
		(layer "F.Cu")
		(net "P12VU_2490_GATE_DRV")
	)
	(segment
		(start 29.9339 -112.1029)
		(end 29.9339 -111.125)
		(width 0.508)
		(layer "F.Cu")
		(net "P12VU_2490_GATE_DRV")
	)
	(segment
		(start 30.099 -112.268)
		(end 29.9339 -112.1029)
		(width 0.508)
		(layer "F.Cu")
		(net "P12VU_2490_GATE_DRV")
	)
	(segment
		(start 28.829 -111.125)
		(end 29.9339 -111.125)
		(width 0.508)
		(layer "F.Cu")
		(net "P12VU_2490_GATE_DRV")
	)
	(via
		(at 30.099 -112.268)
		(size 0.7112)
		(drill 0.3556)
		(layers "F.Cu" "B.Cu")
		(net "P12VU_2490_GATE_DRV")
	)
	(segment
		(start 39.624 -111.633)
		(end 39.624 -110.0455)
		(width 0.508)
		(layer "F.Cu")
		(net "P12VL_2490_GATE_DRV")
	)
	(segment
		(start 39.624 -110.0455)
		(end 39.0017 -109.4232)
		(width 0.508)
		(layer "F.Cu")
		(net "P12VL_2490_GATE_DRV")
	)
	(segment
		(start 40.965374 -111.633)
		(end 41.303448 -111.294926)
		(width 0.508)
		(layer "F.Cu")
		(net "P12VL_2490_GATE_DRV")
	)
	(segment
		(start 39.624 -111.633)
		(end 40.965374 -111.633)
		(width 0.508)
		(layer "F.Cu")
		(net "P12VL_2490_GATE_DRV")
	)
	(via
		(at 41.303448 -111.294926)
		(size 0.7112)
		(drill 0.3556)
		(layers "F.Cu" "B.Cu")
		(net "P12VL_2490_GATE_DRV")
	)
	(segment
		(start 40.8813 -136.271)
		(end 38.7604 -136.271)
		(width 0.3048)
		(layer "F.Cu")
		(net "P12VL_2490_SENSE")
	)
	(segment
		(start 40.5765 -135.2423)
		(end 40.6654 -135.1534)
		(width 0.508)
		(layer "F.Cu")
		(net "P12VL_2490_SENSE")
	)
	(segment
		(start 38.39718 -136.63422)
		(end 38.39718 -137.9093)
		(width 0.3048)
		(layer "F.Cu")
		(net "P12VL_2490_SENSE")
	)
	(segment
		(start 39.5224 -135.2423)
		(end 38.6207 -135.2423)
		(width 0.508)
		(layer "F.Cu")
		(net "P12VL_2490_SENSE")
	)
	(segment
		(start 38.6207 -135.2423)
		(end 38.481 -135.382)
		(width 0.508)
		(layer "F.Cu")
		(net "P12VL_2490_SENSE")
	)
	(segment
		(start 39.5224 -135.2423)
		(end 40.5765 -135.2423)
		(width 0.508)
		(layer "F.Cu")
		(net "P12VL_2490_SENSE")
	)
	(segment
		(start 40.8813 -136.271)
		(end 40.8813 -135.3693)
		(width 0.508)
		(layer "F.Cu")
		(net "P12VL_2490_SENSE")
	)
	(segment
		(start 38.7604 -136.271)
		(end 38.39718 -136.63422)
		(width 0.3048)
		(layer "F.Cu")
		(net "P12VL_2490_SENSE")
	)
	(segment
		(start 40.8813 -135.3693)
		(end 40.6654 -135.1534)
		(width 0.508)
		(layer "F.Cu")
		(net "P12VL_2490_SENSE")
	)
	(via
		(at 38.481 -135.382)
		(size 0.7112)
		(drill 0.3556)
		(layers "F.Cu" "B.Cu")
		(net "P12VL_2490_SENSE")
	)
	(segment
		(start 44.2976 -135.2804)
		(end 44.3992 -135.1788)
		(width 0.508)
		(layer "F.Cu")
		(net "P12VL_2490_VCC")
	)
	(segment
		(start 38.89629 -137.07491)
		(end 39.0906 -136.8806)
		(width 0.3048)
		(layer "F.Cu")
		(net "P12VL_2490_VCC")
	)
	(segment
		(start 41.7703 -135.5725)
		(end 42.1894 -135.1534)
		(width 0.508)
		(layer "F.Cu")
		(net "P12VL_2490_VCC")
	)
	(segment
		(start 42.3037 -135.2677)
		(end 42.1894 -135.1534)
		(width 0.508)
		(layer "F.Cu")
		(net "P12VL_2490_VCC")
	)
	(segment
		(start 43.3451 -136.2456)
		(end 43.3451 -135.2804)
		(width 0.508)
		(layer "F.Cu")
		(net "P12VL_2490_VCC")
	)
	(segment
		(start 43.3451 -135.2804)
		(end 43.3324 -135.2677)
		(width 0.508)
		(layer "F.Cu")
		(net "P12VL_2490_VCC")
	)
	(segment
		(start 38.89629 -137.9093)
		(end 38.89629 -137.07491)
		(width 0.3048)
		(layer "F.Cu")
		(net "P12VL_2490_VCC")
	)
	(segment
		(start 41.7703 -136.271)
		(end 41.7703 -135.5725)
		(width 0.508)
		(layer "F.Cu")
		(net "P12VL_2490_VCC")
	)
	(segment
		(start 43.3324 -135.2677)
		(end 42.3037 -135.2677)
		(width 0.508)
		(layer "F.Cu")
		(net "P12VL_2490_VCC")
	)
	(segment
		(start 41.4274 -136.8806)
		(end 41.7703 -136.5377)
		(width 0.3048)
		(layer "F.Cu")
		(net "P12VL_2490_VCC")
	)
	(segment
		(start 41.7703 -136.5377)
		(end 41.7703 -136.271)
		(width 0.3048)
		(layer "F.Cu")
		(net "P12VL_2490_VCC")
	)
	(segment
		(start 39.0906 -136.8806)
		(end 41.4274 -136.8806)
		(width 0.3048)
		(layer "F.Cu")
		(net "P12VL_2490_VCC")
	)
	(segment
		(start 43.3451 -135.2804)
		(end 44.2976 -135.2804)
		(width 0.508)
		(layer "F.Cu")
		(net "P12VL_2490_VCC")
	)
	(via
		(at 44.3992 -135.1788)
		(size 0.7112)
		(drill 0.3556)
		(layers "F.Cu" "B.Cu")
		(net "P12VL_2490_VCC")
	)
	(segment
		(start 37.39642 -142.86738)
		(end 37.39642 -142.0495)
		(width 0.254)
		(layer "F.Cu")
		(net "P12VL_2490_TIMER")
	)
	(segment
		(start 35.6616 -143.9164)
		(end 36.3474 -143.9164)
		(width 0.254)
		(layer "F.Cu")
		(net "P12VL_2490_TIMER")
	)
	(segment
		(start 36.3474 -143.9164)
		(end 37.39642 -142.86738)
		(width 0.254)
		(layer "F.Cu")
		(net "P12VL_2490_TIMER")
	)
	(segment
		(start 34.3408 -143.8656)
		(end 34.3916 -143.9164)
		(width 0.254)
		(layer "F.Cu")
		(net "P12VL_2490_TIMER")
	)
	(segment
		(start 34.3916 -143.9164)
		(end 35.6616 -143.9164)
		(width 0.254)
		(layer "F.Cu")
		(net "P12VL_2490_TIMER")
	)
	(via
		(at 34.3408 -143.8656)
		(size 0.7112)
		(drill 0.3556)
		(layers "F.Cu" "B.Cu")
		(net "P12VL_2490_TIMER")
	)
	(segment
		(start 37.8968 -142.0495)
		(end 37.8968 -143.2687)
		(width 0.254)
		(layer "F.Cu")
		(net "P12VL_2490_PROG")
	)
	(segment
		(start 36.9062 -145.22958)
		(end 36.88842 -145.2118)
		(width 0.254)
		(layer "F.Cu")
		(net "P12VL_2490_PROG")
	)
	(segment
		(start 37.006784 -145.093436)
		(end 37.006784 -144.385284)
		(width 0.254)
		(layer "F.Cu")
		(net "P12VL_2490_PROG")
	)
	(segment
		(start 37.8968 -143.2687)
		(end 36.8935 -144.272)
		(width 0.254)
		(layer "F.Cu")
		(net "P12VL_2490_PROG")
	)
	(segment
		(start 36.9062 -147.0025)
		(end 36.9062 -145.22958)
		(width 0.254)
		(layer "F.Cu")
		(net "P12VL_2490_PROG")
	)
	(segment
		(start 36.88842 -145.2118)
		(end 37.006784 -145.093436)
		(width 0.254)
		(layer "F.Cu")
		(net "P12VL_2490_PROG")
	)
	(segment
		(start 37.006784 -144.385284)
		(end 36.8935 -144.272)
		(width 0.254)
		(layer "F.Cu")
		(net "P12VL_2490_PROG")
	)
	(via
		(at 36.88842 -145.2118)
		(size 0.7112)
		(drill 0.3556)
		(layers "F.Cu" "B.Cu")
		(net "P12VL_2490_PROG")
	)
	(segment
		(start 38.39718 -142.0495)
		(end 38.39718 -143.65732)
		(width 0.254)
		(layer "F.Cu")
		(net "P12VL_2490_VREF")
	)
	(segment
		(start 37.7825 -144.272)
		(end 37.9222 -144.4117)
		(width 0.254)
		(layer "F.Cu")
		(net "P12VL_2490_VREF")
	)
	(segment
		(start 38.39718 -143.65732)
		(end 37.7825 -144.272)
		(width 0.254)
		(layer "F.Cu")
		(net "P12VL_2490_VREF")
	)
	(segment
		(start 37.973 -145.9484)
		(end 37.9222 -145.9992)
		(width 0.254)
		(layer "F.Cu")
		(net "P12VL_2490_VREF")
	)
	(segment
		(start 37.9222 -144.4117)
		(end 37.9222 -145.8976)
		(width 0.254)
		(layer "F.Cu")
		(net "P12VL_2490_VREF")
	)
	(segment
		(start 37.9222 -146.9263)
		(end 37.973 -146.9771)
		(width 0.254)
		(layer "F.Cu")
		(net "P12VL_2490_VREF")
	)
	(segment
		(start 37.9222 -145.9992)
		(end 37.9222 -146.9263)
		(width 0.254)
		(layer "F.Cu")
		(net "P12VL_2490_VREF")
	)
	(segment
		(start 37.9222 -145.8976)
		(end 37.973 -145.9484)
		(width 0.254)
		(layer "F.Cu")
		(net "P12VL_2490_VREF")
	)
	(via
		(at 37.973 -145.9484)
		(size 0.7112)
		(drill 0.3556)
		(layers "F.Cu" "B.Cu")
		(net "P12VL_2490_VREF")
	)
	(segment
		(start 34.7853 -137.9093)
		(end 36.89731 -137.9093)
		(width 0.1397)
		(layer "F.Cu")
		(net "P12VL_2490_PG")
	)
	(segment
		(start 34.739834 -139.324334)
		(end 34.741866 -139.322302)
		(width 0.1397)
		(layer "F.Cu")
		(net "P12VL_2490_PG")
	)
	(segment
		(start 34.716466 -140.645134)
		(end 34.716466 -139.347702)
		(width 0.1397)
		(layer "F.Cu")
		(net "P12VL_2490_PG")
	)
	(segment
		(start 34.741866 -139.322302)
		(end 34.741866 -137.952734)
		(width 0.1397)
		(layer "F.Cu")
		(net "P12VL_2490_PG")
	)
	(segment
		(start 34.741866 -137.952734)
		(end 34.7853 -137.9093)
		(width 0.1397)
		(layer "F.Cu")
		(net "P12VL_2490_PG")
	)
	(segment
		(start 34.716466 -139.347702)
		(end 34.739834 -139.324334)
		(width 0.1397)
		(layer "F.Cu")
		(net "P12VL_2490_PG")
	)
	(segment
		(start 19.8755 -138.3665)
		(end 20.69211 -138.3665)
		(width 0.1397)
		(layer "F.Cu")
		(net "P12VU_2490_PG")
	)
	(segment
		(start 18.7706 -141.0589)
		(end 18.7706 -139.7254)
		(width 0.1397)
		(layer "F.Cu")
		(net "P12VU_2490_PG")
	)
	(segment
		(start 18.7198 -139.6746)
		(end 18.7198 -138.0109)
		(width 0.1397)
		(layer "F.Cu")
		(net "P12VU_2490_PG")
	)
	(segment
		(start 18.7706 -139.7254)
		(end 18.7198 -139.6746)
		(width 0.1397)
		(layer "F.Cu")
		(net "P12VU_2490_PG")
	)
	(segment
		(start 18.7198 -138.0109)
		(end 19.5199 -138.0109)
		(width 0.1397)
		(layer "F.Cu")
		(net "P12VU_2490_PG")
	)
	(segment
		(start 19.5199 -138.0109)
		(end 19.8755 -138.3665)
		(width 0.1397)
		(layer "F.Cu")
		(net "P12VU_2490_PG")
	)
	(segment
		(start 25.0571 -140.8049)
		(end 25.0571 -140.5382)
		(width 0.508)
		(layer "F.Cu")
		(net "P12VU_2490_RC")
	)
	(segment
		(start 25.8572 -141.5796)
		(end 25.8318 -141.5796)
		(width 0.508)
		(layer "F.Cu")
		(net "P12VU_2490_RC")
	)
	(segment
		(start 25.0571 -140.5382)
		(end 25.0571 -139.5984)
		(width 0.508)
		(layer "F.Cu")
		(net "P12VU_2490_RC")
	)
	(segment
		(start 25.8318 -141.5796)
		(end 25.0571 -140.8049)
		(width 0.508)
		(layer "F.Cu")
		(net "P12VU_2490_RC")
	)
	(via
		(at 25.8572 -141.5796)
		(size 0.7112)
		(drill 0.3556)
		(layers "F.Cu" "B.Cu")
		(net "P12VU_2490_RC")
	)
	(segment
		(start 30.8229 -111.7219)
		(end 30.8229 -111.125)
		(width 0.508)
		(layer "F.Cu")
		(net "P12VU_2490_GATE")
	)
	(segment
		(start 23.2156 -139.6746)
		(end 24.3078 -138.5824)
		(width 0.508)
		(layer "F.Cu")
		(net "P12VU_2490_GATE")
	)
	(segment
		(start 31.115 -112.014)
		(end 30.8229 -111.7219)
		(width 0.508)
		(layer "F.Cu")
		(net "P12VU_2490_GATE")
	)
	(segment
		(start 25.3492 -138.5824)
		(end 25.4254 -138.5824)
		(width 0.508)
		(layer "F.Cu")
		(net "P12VU_2490_GATE")
	)
	(segment
		(start 22.0726 -139.6746)
		(end 23.2156 -139.6746)
		(width 0.508)
		(layer "F.Cu")
		(net "P12VU_2490_GATE")
	)
	(segment
		(start 19.3548 -109.5502)
		(end 19.812 -109.093)
		(width 0.508)
		(layer "F.Cu")
		(net "P12VU_2490_GATE")
	)
	(segment
		(start 27.7368 -139.5984)
		(end 28.0416 -139.9032)
		(width 0.508)
		(layer "F.Cu")
		(net "P12VU_2490_GATE")
	)
	(segment
		(start 21.6916 -139.2936)
		(end 22.0726 -139.6746)
		(width 0.3048)
		(layer "F.Cu")
		(net "P12VU_2490_GATE")
	)
	(segment
		(start 24.3078 -138.5824)
		(end 25.3492 -138.5824)
		(width 0.508)
		(layer "F.Cu")
		(net "P12VU_2490_GATE")
	)
	(segment
		(start 18.8595 -109.5502)
		(end 19.3548 -109.5502)
		(width 0.508)
		(layer "F.Cu")
		(net "P12VU_2490_GATE")
	)
	(segment
		(start 25.9461 -139.5984)
		(end 27.7368 -139.5984)
		(width 0.508)
		(layer "F.Cu")
		(net "P12VU_2490_GATE")
	)
	(segment
		(start 25.9461 -139.1031)
		(end 25.9461 -139.5984)
		(width 0.508)
		(layer "F.Cu")
		(net "P12VU_2490_GATE")
	)
	(segment
		(start 21.6916 -138.3665)
		(end 21.6916 -139.2936)
		(width 0.3048)
		(layer "F.Cu")
		(net "P12VU_2490_GATE")
	)
	(segment
		(start 25.4254 -138.5824)
		(end 25.9461 -139.1031)
		(width 0.508)
		(layer "F.Cu")
		(net "P12VU_2490_GATE")
	)
	(via
		(at 19.812 -109.093)
		(size 0.5588)
		(drill 0.3048)
		(layers "F.Cu" "B.Cu")
		(net "P12VU_2490_GATE")
	)
	(via
		(at 26.7462 -133.4008)
		(size 0.7112)
		(drill 0.3556)
		(layers "F.Cu" "B.Cu")
		(net "P12VU_2490_GATE")
	)
	(via
		(at 28.0416 -139.9032)
		(size 0.5588)
		(drill 0.3048)
		(layers "F.Cu" "B.Cu")
		(net "P12VU_2490_GATE")
	)
	(via
		(at 25.3492 -138.5824)
		(size 0.7112)
		(drill 0.3556)
		(layers "F.Cu" "B.Cu")
		(net "P12VU_2490_GATE")
	)
	(via
		(at 31.115 -112.014)
		(size 0.5588)
		(drill 0.3048)
		(layers "F.Cu" "B.Cu")
		(net "P12VU_2490_GATE")
	)
	(segment
		(start 19.939 -109.22)
		(end 28.321 -109.22)
		(width 0.508)
		(layer "B.Cu")
		(net "P12VU_2490_GATE")
	)
	(segment
		(start 29.8196 -112.014)
		(end 26.29535 -115.53825)
		(width 0.508)
		(layer "B.Cu")
		(net "P12VU_2490_GATE")
	)
	(segment
		(start 28.0416 -139.9032)
		(end 26.7462 -138.6078)
		(width 0.508)
		(layer "B.Cu")
		(net "P12VU_2490_GATE")
	)
	(segment
		(start 28.321 -109.22)
		(end 31.115 -112.014)
		(width 0.508)
		(layer "B.Cu")
		(net "P12VU_2490_GATE")
	)
	(segment
		(start 26.29535 -115.53825)
		(end 26.29535 -132.94995)
		(width 0.508)
		(layer "B.Cu")
		(net "P12VU_2490_GATE")
	)
	(segment
		(start 31.115 -112.014)
		(end 29.8196 -112.014)
		(width 0.508)
		(layer "B.Cu")
		(net "P12VU_2490_GATE")
	)
	(segment
		(start 26.7462 -138.6078)
		(end 26.7462 -133.4008)
		(width 0.508)
		(layer "B.Cu")
		(net "P12VU_2490_GATE")
	)
	(segment
		(start 19.812 -109.093)
		(end 19.939 -109.22)
		(width 0.508)
		(layer "B.Cu")
		(net "P12VU_2490_GATE")
	)
	(segment
		(start 26.29535 -132.94995)
		(end 26.7462 -133.4008)
		(width 0.508)
		(layer "B.Cu")
		(net "P12VU_2490_GATE")
	)
	(segment
		(start 17.8816 -143.9418)
		(end 17.8816 -143.637)
		(width 0.254)
		(layer "F.Cu")
		(net "P12VU_2490_TIMER")
	)
	(segment
		(start 18.8214 -144.8816)
		(end 17.8816 -143.9418)
		(width 0.254)
		(layer "F.Cu")
		(net "P12VU_2490_TIMER")
	)
	(segment
		(start 19.3802 -144.3228)
		(end 18.8214 -144.8816)
		(width 0.254)
		(layer "F.Cu")
		(net "P12VU_2490_TIMER")
	)
	(segment
		(start 21.19122 -143.60398)
		(end 20.4724 -144.3228)
		(width 0.254)
		(layer "F.Cu")
		(net "P12VU_2490_TIMER")
	)
	(segment
		(start 20.4724 -144.3228)
		(end 19.3802 -144.3228)
		(width 0.254)
		(layer "F.Cu")
		(net "P12VU_2490_TIMER")
	)
	(segment
		(start 21.19122 -142.5067)
		(end 21.19122 -143.60398)
		(width 0.254)
		(layer "F.Cu")
		(net "P12VU_2490_TIMER")
	)
	(via
		(at 17.8816 -143.637)
		(size 0.7112)
		(drill 0.3556)
		(layers "F.Cu" "B.Cu")
		(net "P12VU_2490_TIMER")
	)
	(segment
		(start 21.0566 -145.923)
		(end 21.2471 -145.7325)
		(width 0.254)
		(layer "F.Cu")
		(net "P12VU_2490_PROG")
	)
	(segment
		(start 21.2471 -145.7325)
		(end 21.2471 -144.7546)
		(width 0.254)
		(layer "F.Cu")
		(net "P12VU_2490_PROG")
	)
	(segment
		(start 20.0533 -145.0467)
		(end 20.9296 -145.923)
		(width 0.254)
		(layer "F.Cu")
		(net "P12VU_2490_PROG")
	)
	(segment
		(start 21.2471 -144.7546)
		(end 21.2471 -144.4879)
		(width 0.254)
		(layer "F.Cu")
		(net "P12VU_2490_PROG")
	)
	(segment
		(start 21.2471 -144.4879)
		(end 21.6916 -144.0434)
		(width 0.254)
		(layer "F.Cu")
		(net "P12VU_2490_PROG")
	)
	(segment
		(start 19.9644 -145.0467)
		(end 20.0533 -145.0467)
		(width 0.254)
		(layer "F.Cu")
		(net "P12VU_2490_PROG")
	)
	(segment
		(start 21.6916 -144.0434)
		(end 21.6916 -142.5067)
		(width 0.254)
		(layer "F.Cu")
		(net "P12VU_2490_PROG")
	)
	(segment
		(start 20.9296 -145.923)
		(end 21.0566 -145.923)
		(width 0.254)
		(layer "F.Cu")
		(net "P12VU_2490_PROG")
	)
	(via
		(at 21.0566 -145.923)
		(size 0.7112)
		(drill 0.3556)
		(layers "F.Cu" "B.Cu")
		(net "P12VU_2490_PROG")
	)
	(segment
		(start 22.1361 -145.7706)
		(end 22.1996 -145.8341)
		(width 0.254)
		(layer "F.Cu")
		(net "P12VU_2490_VREF")
	)
	(segment
		(start 22.0091 -146.0246)
		(end 21.9202 -146.0246)
		(width 0.254)
		(layer "F.Cu")
		(net "P12VU_2490_VREF")
	)
	(segment
		(start 22.1361 -144.7546)
		(end 22.1361 -145.7706)
		(width 0.254)
		(layer "F.Cu")
		(net "P12VU_2490_VREF")
	)
	(segment
		(start 21.9202 -146.0246)
		(end 21.239226 -146.705574)
		(width 0.254)
		(layer "F.Cu")
		(net "P12VU_2490_VREF")
	)
	(segment
		(start 22.19198 -144.69872)
		(end 22.19198 -142.5067)
		(width 0.254)
		(layer "F.Cu")
		(net "P12VU_2490_VREF")
	)
	(segment
		(start 22.1996 -145.8341)
		(end 22.0091 -146.0246)
		(width 0.254)
		(layer "F.Cu")
		(net "P12VU_2490_VREF")
	)
	(segment
		(start 22.1361 -144.7546)
		(end 22.19198 -144.69872)
		(width 0.254)
		(layer "F.Cu")
		(net "P12VU_2490_VREF")
	)
	(segment
		(start 21.239226 -146.705574)
		(end 21.239226 -147.762468)
		(width 0.254)
		(layer "F.Cu")
		(net "P12VU_2490_VREF")
	)
	(via
		(at 21.239226 -147.762468)
		(size 0.7112)
		(drill 0.3556)
		(layers "F.Cu" "B.Cu")
		(net "P12VU_2490_VREF")
	)
	(segment
		(start 24.4221 -137.3759)
		(end 24.4221 -136.6012)
		(width 0.508)
		(layer "F.Cu")
		(net "P12VU_2490_VCC")
	)
	(segment
		(start 24.4221 -136.6012)
		(end 24.4221 -135.636)
		(width 0.508)
		(layer "F.Cu")
		(net "P12VU_2490_VCC")
	)
	(segment
		(start 24.6126 -137.5664)
		(end 24.4221 -137.3759)
		(width 0.508)
		(layer "F.Cu")
		(net "P12VU_2490_VCC")
	)
	(segment
		(start 22.69109 -136.85901)
		(end 22.9489 -136.6012)
		(width 0.254)
		(layer "F.Cu")
		(net "P12VU_2490_VCC")
	)
	(segment
		(start 23.368 -135.6233)
		(end 23.299166 -135.554466)
		(width 0.508)
		(layer "F.Cu")
		(net "P12VU_2490_VCC")
	)
	(segment
		(start 22.9489 -136.6012)
		(end 22.9489 -135.904732)
		(width 0.508)
		(layer "F.Cu")
		(net "P12VU_2490_VCC")
	)
	(segment
		(start 24.4094 -135.6233)
		(end 23.368 -135.6233)
		(width 0.508)
		(layer "F.Cu")
		(net "P12VU_2490_VCC")
	)
	(segment
		(start 22.69109 -138.3665)
		(end 22.69109 -136.85901)
		(width 0.254)
		(layer "F.Cu")
		(net "P12VU_2490_VCC")
	)
	(segment
		(start 22.9489 -135.904732)
		(end 23.299166 -135.554466)
		(width 0.508)
		(layer "F.Cu")
		(net "P12VU_2490_VCC")
	)
	(segment
		(start 24.4221 -135.636)
		(end 24.4094 -135.6233)
		(width 0.508)
		(layer "F.Cu")
		(net "P12VU_2490_VCC")
	)
	(via
		(at 24.6126 -137.5664)
		(size 0.7112)
		(drill 0.3556)
		(layers "F.Cu" "B.Cu")
		(net "P12VU_2490_VCC")
	)
	(segment
		(start 40.5892 -161.244026)
		(end 38.70833 -161.244026)
		(width 0.1397)
		(layer "F.Cu")
		(net "NCT7904_CLK")
	)
	(segment
		(start 38.43909 -162.6616)
		(end 38.43909 -161.513266)
		(width 0.1397)
		(layer "F.Cu")
		(net "NCT7904_CLK")
	)
	(segment
		(start 38.70833 -161.244026)
		(end 38.43909 -161.513266)
		(width 0.1397)
		(layer "F.Cu")
		(net "NCT7904_CLK")
	)
	(via
		(at 38.43909 -162.6616)
		(size 0.7112)
		(drill 0.3556)
		(layers "F.Cu" "B.Cu")
		(net "NCT7904_CLK")
	)
	(segment
		(start 22.19198 -138.3665)
		(end 22.19198 -136.73328)
		(width 0.254)
		(layer "F.Cu")
		(net "P12VU_2490_SENSE")
	)
	(segment
		(start 22.0599 -135.8392)
		(end 21.775166 -135.554466)
		(width 0.508)
		(layer "F.Cu")
		(net "P12VU_2490_SENSE")
	)
	(segment
		(start 21.706332 -135.6233)
		(end 21.775166 -135.554466)
		(width 0.508)
		(layer "F.Cu")
		(net "P12VU_2490_SENSE")
	)
	(segment
		(start 22.0599 -136.6012)
		(end 22.0599 -135.8392)
		(width 0.508)
		(layer "F.Cu")
		(net "P12VU_2490_SENSE")
	)
	(segment
		(start 20.6756 -135.6233)
		(end 21.706332 -135.6233)
		(width 0.508)
		(layer "F.Cu")
		(net "P12VU_2490_SENSE")
	)
	(segment
		(start 20.2565 -135.6233)
		(end 19.6596 -136.2202)
		(width 0.508)
		(layer "F.Cu")
		(net "P12VU_2490_SENSE")
	)
	(segment
		(start 22.19198 -136.73328)
		(end 22.0599 -136.6012)
		(width 0.254)
		(layer "F.Cu")
		(net "P12VU_2490_SENSE")
	)
	(segment
		(start 20.6756 -135.6233)
		(end 20.2565 -135.6233)
		(width 0.508)
		(layer "F.Cu")
		(net "P12VU_2490_SENSE")
	)
	(via
		(at 19.6596 -136.2202)
		(size 0.7112)
		(drill 0.3556)
		(layers "F.Cu" "B.Cu")
		(net "P12VU_2490_SENSE")
	)
	(segment
		(start 22.96795 -158.01467)
		(end 23.231602 -158.278322)
		(width 0.1397)
		(layer "F.Cu")
		(net "NCT7904_TMPALM")
	)
	(segment
		(start 23.48611 -155.046934)
		(end 22.96795 -155.565094)
		(width 0.1397)
		(layer "F.Cu")
		(net "NCT7904_TMPALM")
	)
	(segment
		(start 26.12009 -159.098996)
		(end 24.052276 -159.098996)
		(width 0.1397)
		(layer "F.Cu")
		(net "NCT7904_TMPALM")
	)
	(segment
		(start 24.052276 -159.098996)
		(end 23.231602 -158.278322)
		(width 0.1397)
		(layer "F.Cu")
		(net "NCT7904_TMPALM")
	)
	(segment
		(start 22.96795 -155.565094)
		(end 22.96795 -158.01467)
		(width 0.1397)
		(layer "F.Cu")
		(net "NCT7904_TMPALM")
	)
	(via
		(at 23.231602 -158.278322)
		(size 0.7112)
		(drill 0.3556)
		(layers "F.Cu" "B.Cu")
		(net "NCT7904_TMPALM")
	)
	(segment
		(start 32.075374 -167.279066)
		(end 31.801308 -167.005)
		(width 0.1397)
		(layer "F.Cu")
		(net "NCT7904_RSTOUT")
	)
	(segment
		(start 31.61157 -166.815262)
		(end 31.61157 -164.091366)
		(width 0.1397)
		(layer "F.Cu")
		(net "NCT7904_RSTOUT")
	)
	(segment
		(start 31.801308 -167.005)
		(end 31.61157 -166.815262)
		(width 0.1397)
		(layer "F.Cu")
		(net "NCT7904_RSTOUT")
	)
	(segment
		(start 32.85109 -167.279066)
		(end 32.075374 -167.279066)
		(width 0.1397)
		(layer "F.Cu")
		(net "NCT7904_RSTOUT")
	)
	(via
		(at 31.801308 -167.005)
		(size 0.7112)
		(drill 0.3556)
		(layers "F.Cu" "B.Cu")
		(net "NCT7904_RSTOUT")
	)
	(segment
		(start 38.56482 -156.22651)
		(end 38.678866 -156.22651)
		(width 0.1397)
		(layer "F.Cu")
		(net "NCT7904_SMI")
	)
	(segment
		(start 37.74313 -157.0482)
		(end 38.56482 -156.22651)
		(width 0.1397)
		(layer "F.Cu")
		(net "NCT7904_SMI")
	)
	(segment
		(start 35.873944 -159.098996)
		(end 37.74313 -157.22981)
		(width 0.1397)
		(layer "F.Cu")
		(net "NCT7904_SMI")
	)
	(segment
		(start 34.60369 -159.098996)
		(end 35.873944 -159.098996)
		(width 0.1397)
		(layer "F.Cu")
		(net "NCT7904_SMI")
	)
	(segment
		(start 37.74313 -157.22981)
		(end 37.74313 -157.0482)
		(width 0.1397)
		(layer "F.Cu")
		(net "NCT7904_SMI")
	)
	(via
		(at 37.74313 -157.0482)
		(size 0.7112)
		(drill 0.3556)
		(layers "F.Cu" "B.Cu")
		(net "NCT7904_SMI")
	)
	(segment
		(start 23.614634 -156.80309)
		(end 23.614634 -157.447234)
		(width 0.1397)
		(layer "F.Cu")
		(net "NCT7904_LED")
	)
	(segment
		(start 23.614634 -157.447234)
		(end 24.767286 -158.599886)
		(width 0.1397)
		(layer "F.Cu")
		(net "NCT7904_LED")
	)
	(segment
		(start 24.767286 -158.599886)
		(end 26.12009 -158.599886)
		(width 0.1397)
		(layer "F.Cu")
		(net "NCT7904_LED")
	)
	(segment
		(start 38.43909 -160.624266)
		(end 37.67709 -160.624266)
		(width 0.1397)
		(layer "F.Cu")
		(net "NCT7904_CLKIN")
	)
	(segment
		(start 34.60369 -161.599626)
		(end 36.70173 -161.599626)
		(width 0.1397)
		(layer "F.Cu")
		(net "NCT7904_CLKIN")
	)
	(segment
		(start 37.67709 -160.624266)
		(end 37.252402 -161.048954)
		(width 0.1397)
		(layer "F.Cu")
		(net "NCT7904_CLKIN")
	)
	(segment
		(start 36.70173 -161.599626)
		(end 37.252402 -161.048954)
		(width 0.1397)
		(layer "F.Cu")
		(net "NCT7904_CLKIN")
	)
	(via
		(at 37.252402 -161.048954)
		(size 0.7112)
		(drill 0.3556)
		(layers "F.Cu" "B.Cu")
		(net "NCT7904_CLKIN")
	)
	(segment
		(start 24.01443 -152.68194)
		(end 24.01443 -152.704038)
		(width 0.1397)
		(layer "F.Cu")
		(net "NCT7904_RESET")
	)
	(segment
		(start 25.060656 -158.099506)
		(end 26.12009 -158.099506)
		(width 0.1397)
		(layer "F.Cu")
		(net "NCT7904_RESET")
	)
	(segment
		(start 24.3459 -153.035508)
		(end 24.3459 -157.38475)
		(width 0.1397)
		(layer "F.Cu")
		(net "NCT7904_RESET")
	)
	(segment
		(start 23.63851 -152.30602)
		(end 24.01443 -152.68194)
		(width 0.1397)
		(layer "F.Cu")
		(net "NCT7904_RESET")
	)
	(segment
		(start 24.01443 -152.704038)
		(end 24.3459 -153.035508)
		(width 0.1397)
		(layer "F.Cu")
		(net "NCT7904_RESET")
	)
	(segment
		(start 24.3459 -157.38475)
		(end 25.060656 -158.099506)
		(width 0.1397)
		(layer "F.Cu")
		(net "NCT7904_RESET")
	)
	(segment
		(start 23.63851 -151.770334)
		(end 23.63851 -152.30602)
		(width 0.1397)
		(layer "F.Cu")
		(net "NCT7904_RESET")
	)
	(via
		(at 24.01443 -152.704038)
		(size 0.7112)
		(drill 0.3556)
		(layers "F.Cu" "B.Cu")
		(net "NCT7904_RESET")
	)
	(segment
		(start 40.64 -368.3)
		(end 41.402 -369.062)
		(width 0.254)
		(layer "F.Cu")
		(net "ADM1276_LATCH#")
	)
	(segment
		(start 37.338 -367.048034)
		(end 38.335966 -368.046)
		(width 0.254)
		(layer "F.Cu")
		(net "ADM1276_LATCH#")
	)
	(segment
		(start 33.528 -364.871)
		(end 35.578034 -364.871)
		(width 0.254)
		(layer "F.Cu")
		(net "ADM1276_LATCH#")
	)
	(segment
		(start 42.0116 -363.2835)
		(end 41.991026 -363.304074)
		(width 0.254)
		(layer "F.Cu")
		(net "ADM1276_LATCH#")
	)
	(segment
		(start 28.418028 -366.3696)
		(end 27.9146 -366.3696)
		(width 0.254)
		(layer "F.Cu")
		(net "ADM1276_LATCH#")
	)
	(segment
		(start 27.305 -361.6325)
		(end 27.8511 -362.1786)
		(width 0.254)
		(layer "F.Cu")
		(net "ADM1276_LATCH#")
	)
	(segment
		(start 41.991026 -363.304074)
		(end 40.851074 -363.304074)
		(width 0.254)
		(layer "F.Cu")
		(net "ADM1276_LATCH#")
	)
	(segment
		(start 43.654726 -366.234726)
		(end 42.537126 -365.117126)
		(width 0.254)
		(layer "F.Cu")
		(net "ADM1276_LATCH#")
	)
	(segment
		(start 27.8511 -362.1786)
		(end 27.8511 -363.0041)
		(width 0.254)
		(layer "F.Cu")
		(net "ADM1276_LATCH#")
	)
	(segment
		(start 25.527 -362.458)
		(end 25.527 -361.6325)
		(width 0.254)
		(layer "F.Cu")
		(net "ADM1276_LATCH#")
	)
	(segment
		(start 39.37 -368.3)
		(end 40.64 -368.3)
		(width 0.254)
		(layer "F.Cu")
		(net "ADM1276_LATCH#")
	)
	(segment
		(start 37.338 -366.630966)
		(end 37.338 -367.048034)
		(width 0.254)
		(layer "F.Cu")
		(net "ADM1276_LATCH#")
	)
	(segment
		(start 43.654726 -368.273076)
		(end 43.654726 -366.234726)
		(width 0.254)
		(layer "F.Cu")
		(net "ADM1276_LATCH#")
	)
	(segment
		(start 27.8511 -363.0041)
		(end 27.94 -363.093)
		(width 0.254)
		(layer "F.Cu")
		(net "ADM1276_LATCH#")
	)
	(segment
		(start 26.162 -363.093)
		(end 25.527 -362.458)
		(width 0.254)
		(layer "F.Cu")
		(net "ADM1276_LATCH#")
	)
	(segment
		(start 42.537126 -365.117126)
		(end 42.035476 -365.117126)
		(width 0.254)
		(layer "F.Cu")
		(net "ADM1276_LATCH#")
	)
	(segment
		(start 41.402 -369.062)
		(end 42.865802 -369.062)
		(width 0.254)
		(layer "F.Cu")
		(net "ADM1276_LATCH#")
	)
	(segment
		(start 38.335966 -368.046)
		(end 39.116 -368.046)
		(width 0.254)
		(layer "F.Cu")
		(net "ADM1276_LATCH#")
	)
	(segment
		(start 39.116 -368.046)
		(end 39.37 -368.3)
		(width 0.254)
		(layer "F.Cu")
		(net "ADM1276_LATCH#")
	)
	(segment
		(start 42.865802 -369.062)
		(end 43.654726 -368.273076)
		(width 0.254)
		(layer "F.Cu")
		(net "ADM1276_LATCH#")
	)
	(segment
		(start 42.035476 -363.307376)
		(end 42.0116 -363.2835)
		(width 0.254)
		(layer "F.Cu")
		(net "ADM1276_LATCH#")
	)
	(segment
		(start 26.543 -363.474)
		(end 26.162 -363.093)
		(width 0.254)
		(layer "F.Cu")
		(net "ADM1276_LATCH#")
	)
	(segment
		(start 25.527 -361.6325)
		(end 26.67 -361.6325)
		(width 0.254)
		(layer "F.Cu")
		(net "ADM1276_LATCH#")
	)
	(segment
		(start 26.543 -364.998)
		(end 26.543 -363.474)
		(width 0.254)
		(layer "F.Cu")
		(net "ADM1276_LATCH#")
	)
	(segment
		(start 42.035476 -365.117126)
		(end 42.035476 -363.307376)
		(width 0.254)
		(layer "F.Cu")
		(net "ADM1276_LATCH#")
	)
	(segment
		(start 26.67 -361.6325)
		(end 27.305 -361.6325)
		(width 0.254)
		(layer "F.Cu")
		(net "ADM1276_LATCH#")
	)
	(segment
		(start 35.578034 -364.871)
		(end 37.338 -366.630966)
		(width 0.254)
		(layer "F.Cu")
		(net "ADM1276_LATCH#")
	)
	(segment
		(start 27.9146 -366.3696)
		(end 26.543 -364.998)
		(width 0.254)
		(layer "F.Cu")
		(net "ADM1276_LATCH#")
	)
	(via
		(at 26.162 -363.093)
		(size 0.7112)
		(drill 0.3556)
		(layers "F.Cu" "B.Cu")
		(net "ADM1276_LATCH#")
	)
	(via
		(at 27.94 -363.093)
		(size 0.5588)
		(drill 0.3048)
		(layers "F.Cu" "B.Cu")
		(net "ADM1276_LATCH#")
	)
	(via
		(at 33.528 -364.871)
		(size 0.5588)
		(drill 0.3048)
		(layers "F.Cu" "B.Cu")
		(net "ADM1276_LATCH#")
	)
	(segment
		(start 30.861 -363.474)
		(end 32.258 -364.871)
		(width 0.254)
		(layer "B.Cu")
		(net "ADM1276_LATCH#")
	)
	(segment
		(start 32.258 -364.871)
		(end 33.528 -364.871)
		(width 0.254)
		(layer "B.Cu")
		(net "ADM1276_LATCH#")
	)
	(segment
		(start 28.321 -363.474)
		(end 30.861 -363.474)
		(width 0.254)
		(layer "B.Cu")
		(net "ADM1276_LATCH#")
	)
	(segment
		(start 27.94 -363.093)
		(end 28.321 -363.474)
		(width 0.254)
		(layer "B.Cu")
		(net "ADM1276_LATCH#")
	)
	(segment
		(start 32.1564 -368.158014)
		(end 33.076642 -368.158014)
		(width 0.254)
		(layer "F.Cu")
		(net "ADM1276_PWRGD")
	)
	(segment
		(start 33.782 -367.6904)
		(end 33.8074 -367.6904)
		(width 0.254)
		(layer "F.Cu")
		(net "ADM1276_PWRGD")
	)
	(segment
		(start 33.8074 -367.6904)
		(end 35.2552 -369.1382)
		(width 0.254)
		(layer "F.Cu")
		(net "ADM1276_PWRGD")
	)
	(segment
		(start 33.544256 -367.6904)
		(end 33.782 -367.6904)
		(width 0.254)
		(layer "F.Cu")
		(net "ADM1276_PWRGD")
	)
	(segment
		(start 33.076642 -368.158014)
		(end 33.544256 -367.6904)
		(width 0.254)
		(layer "F.Cu")
		(net "ADM1276_PWRGD")
	)
	(segment
		(start 35.2552 -369.1382)
		(end 35.5981 -369.1382)
		(width 0.254)
		(layer "F.Cu")
		(net "ADM1276_PWRGD")
	)
	(via
		(at 33.782 -367.6904)
		(size 0.7112)
		(drill 0.3556)
		(layers "F.Cu" "B.Cu")
		(net "ADM1276_PWRGD")
	)
	(segment
		(start 31.11246 -152.781)
		(end 31.11246 -155.607766)
		(width 0.1397)
		(layer "F.Cu")
		(net "NCT7904_VSEN8")
	)
	(segment
		(start 31.96209 -151.93137)
		(end 31.11246 -152.781)
		(width 0.1397)
		(layer "F.Cu")
		(net "NCT7904_VSEN8")
	)
	(segment
		(start 31.96209 -150.781766)
		(end 31.96209 -151.93137)
		(width 0.1397)
		(layer "F.Cu")
		(net "NCT7904_VSEN8")
	)
	(segment
		(start 39.38524 -158.22676)
		(end 39.9288 -157.6832)
		(width 0.1397)
		(layer "F.Cu")
		(net "NCT7904_VSEN1")
	)
	(segment
		(start 36.130484 -160.099756)
		(end 38.00348 -158.22676)
		(width 0.1397)
		(layer "F.Cu")
		(net "NCT7904_VSEN1")
	)
	(segment
		(start 40.8305 -157.6832)
		(end 39.9288 -157.6832)
		(width 0.1397)
		(layer "F.Cu")
		(net "NCT7904_VSEN1")
	)
	(segment
		(start 38.00348 -158.22676)
		(end 39.38524 -158.22676)
		(width 0.1397)
		(layer "F.Cu")
		(net "NCT7904_VSEN1")
	)
	(segment
		(start 41.3131 -158.1658)
		(end 40.8305 -157.6832)
		(width 0.1397)
		(layer "F.Cu")
		(net "NCT7904_VSEN1")
	)
	(segment
		(start 34.60369 -160.099756)
		(end 36.130484 -160.099756)
		(width 0.1397)
		(layer "F.Cu")
		(net "NCT7904_VSEN1")
	)
	(via
		(at 39.9288 -157.6832)
		(size 0.7112)
		(drill 0.3556)
		(layers "F.Cu" "B.Cu")
		(net "NCT7904_VSEN1")
	)
	(segment
		(start 30.11551 -150.582884)
		(end 30.1498 -150.582884)
		(width 0.1397)
		(layer "F.Cu")
		(net "NCT7904_VSEN6")
	)
	(segment
		(start 30.681168 -149.516084)
		(end 30.6832 -149.518116)
		(width 0.1397)
		(layer "F.Cu")
		(net "NCT7904_VSEN6")
	)
	(segment
		(start 30.1117 -155.607766)
		(end 30.1117 -154.493468)
		(width 0.1397)
		(layer "F.Cu")
		(net "NCT7904_VSEN6")
	)
	(segment
		(start 30.6832 -150.051516)
		(end 30.6832 -149.518116)
		(width 0.1397)
		(layer "F.Cu")
		(net "NCT7904_VSEN6")
	)
	(segment
		(start 30.4038 -150.330916)
		(end 30.6832 -150.051516)
		(width 0.1397)
		(layer "F.Cu")
		(net "NCT7904_VSEN6")
	)
	(segment
		(start 30.1498 -150.582884)
		(end 30.401768 -150.330916)
		(width 0.1397)
		(layer "F.Cu")
		(net "NCT7904_VSEN6")
	)
	(segment
		(start 30.1117 -154.493468)
		(end 30.11551 -154.489658)
		(width 0.1397)
		(layer "F.Cu")
		(net "NCT7904_VSEN6")
	)
	(segment
		(start 30.401768 -150.330916)
		(end 30.4038 -150.330916)
		(width 0.1397)
		(layer "F.Cu")
		(net "NCT7904_VSEN6")
	)
	(segment
		(start 29.6672 -149.516084)
		(end 30.681168 -149.516084)
		(width 0.1397)
		(layer "F.Cu")
		(net "NCT7904_VSEN6")
	)
	(segment
		(start 30.11551 -154.489658)
		(end 30.11551 -150.582884)
		(width 0.1397)
		(layer "F.Cu")
		(net "NCT7904_VSEN6")
	)
	(via
		(at 30.11551 -150.582884)
		(size 0.7112)
		(drill 0.3556)
		(layers "F.Cu" "B.Cu")
		(net "NCT7904_VSEN6")
	)
	(segment
		(start 29.11221 -153.71191)
		(end 28.6893 -153.289)
		(width 0.1397)
		(layer "F.Cu")
		(net "NCT7904_D2+")
	)
	(segment
		(start 29.11221 -155.607766)
		(end 29.11221 -153.71191)
		(width 0.1397)
		(layer "F.Cu")
		(net "NCT7904_D2+")
	)
	(segment
		(start 28.6893 -152.417272)
		(end 28.86837 -152.238202)
		(width 0.1397)
		(layer "F.Cu")
		(net "NCT7904_D2+")
	)
	(segment
		(start 27.468322 -320.000122)
		(end 28.452572 -319.015872)
		(width 0.1397)
		(layer "F.Cu")
		(net "NCT7904_D2+")
	)
	(segment
		(start 28.6893 -153.289)
		(end 28.6893 -152.417272)
		(width 0.1397)
		(layer "F.Cu")
		(net "NCT7904_D2+")
	)
	(segment
		(start 28.452572 -319.015872)
		(end 30.226 -319.015872)
		(width 0.1397)
		(layer "F.Cu")
		(net "NCT7904_D2+")
	)
	(segment
		(start 26.547572 -320.000122)
		(end 27.468322 -320.000122)
		(width 0.1397)
		(layer "F.Cu")
		(net "NCT7904_D2+")
	)
	(via
		(at 28.86837 -152.238202)
		(size 0.5588)
		(drill 0.3048)
		(layers "F.Cu" "B.Cu")
		(net "NCT7904_D2+")
	)
	(via
		(at 30.226 -319.015872)
		(size 0.5588)
		(drill 0.3048)
		(layers "F.Cu" "B.Cu")
		(net "NCT7904_D2+")
	)
	(via
		(at 31.496 -316.8904)
		(size 0.7112)
		(drill 0.3556)
		(layers "F.Cu" "B.Cu")
		(net "NCT7904_D2+")
	)
	(segment
		(start 35.83305 -159.202882)
		(end 28.86837 -152.238202)
		(width 0.1397)
		(layer "B.Cu")
		(net "NCT7904_D2+")
	)
	(segment
		(start 41.6306 -246.0244)
		(end 41.6306 -216.23655)
		(width 0.1397)
		(layer "B.Cu")
		(net "NCT7904_D2+")
	)
	(segment
		(start 30.226 -319.015872)
		(end 31.496 -317.745872)
		(width 0.1397)
		(layer "B.Cu")
		(net "NCT7904_D2+")
	)
	(segment
		(start 34.0106 -272.96364)
		(end 34.010854 -272.963386)
		(width 0.1397)
		(layer "B.Cu")
		(net "NCT7904_D2+")
	)
	(segment
		(start 34.010854 -259.322316)
		(end 34.45637 -258.8768)
		(width 0.1397)
		(layer "B.Cu")
		(net "NCT7904_D2+")
	)
	(segment
		(start 36.56965 -173.76775)
		(end 36.56965 -170.777154)
		(width 0.1397)
		(layer "B.Cu")
		(net "NCT7904_D2+")
	)
	(segment
		(start 34.0106 -274.594828)
		(end 34.0106 -272.96364)
		(width 0.1397)
		(layer "B.Cu")
		(net "NCT7904_D2+")
	)
	(segment
		(start 35.311842 -169.519346)
		(end 35.311842 -168.624758)
		(width 0.1397)
		(layer "B.Cu")
		(net "NCT7904_D2+")
	)
	(segment
		(start 36.060126 -174.277274)
		(end 36.56965 -173.76775)
		(width 0.1397)
		(layer "B.Cu")
		(net "NCT7904_D2+")
	)
	(segment
		(start 35.311842 -168.624758)
		(end 35.83305 -168.10355)
		(width 0.1397)
		(layer "B.Cu")
		(net "NCT7904_D2+")
	)
	(segment
		(start 40.8686 -250.0884)
		(end 40.8686 -246.7864)
		(width 0.1397)
		(layer "B.Cu")
		(net "NCT7904_D2+")
	)
	(segment
		(start 34.010854 -275.488146)
		(end 34.010854 -274.595082)
		(width 0.1397)
		(layer "B.Cu")
		(net "NCT7904_D2+")
	)
	(segment
		(start 31.496 -278.003)
		(end 34.010854 -275.488146)
		(width 0.1397)
		(layer "B.Cu")
		(net "NCT7904_D2+")
	)
	(segment
		(start 39.51605 -214.122)
		(end 39.50843 -214.122)
		(width 0.1397)
		(layer "B.Cu")
		(net "NCT7904_D2+")
	)
	(segment
		(start 34.45637 -256.50063)
		(end 40.8686 -250.0884)
		(width 0.1397)
		(layer "B.Cu")
		(net "NCT7904_D2+")
	)
	(segment
		(start 31.496 -316.8904)
		(end 31.496 -278.003)
		(width 0.1397)
		(layer "B.Cu")
		(net "NCT7904_D2+")
	)
	(segment
		(start 34.010854 -274.595082)
		(end 34.0106 -274.594828)
		(width 0.1397)
		(layer "B.Cu")
		(net "NCT7904_D2+")
	)
	(segment
		(start 36.060126 -210.673696)
		(end 36.060126 -174.277274)
		(width 0.1397)
		(layer "B.Cu")
		(net "NCT7904_D2+")
	)
	(segment
		(start 34.010854 -272.963386)
		(end 34.010854 -259.322316)
		(width 0.1397)
		(layer "B.Cu")
		(net "NCT7904_D2+")
	)
	(segment
		(start 35.83305 -168.10355)
		(end 35.83305 -159.202882)
		(width 0.1397)
		(layer "B.Cu")
		(net "NCT7904_D2+")
	)
	(segment
		(start 36.56965 -170.777154)
		(end 35.311842 -169.519346)
		(width 0.1397)
		(layer "B.Cu")
		(net "NCT7904_D2+")
	)
	(segment
		(start 39.50843 -214.122)
		(end 36.060126 -210.673696)
		(width 0.1397)
		(layer "B.Cu")
		(net "NCT7904_D2+")
	)
	(segment
		(start 41.6306 -216.23655)
		(end 39.51605 -214.122)
		(width 0.1397)
		(layer "B.Cu")
		(net "NCT7904_D2+")
	)
	(segment
		(start 40.8686 -246.7864)
		(end 41.6306 -246.0244)
		(width 0.1397)
		(layer "B.Cu")
		(net "NCT7904_D2+")
	)
	(segment
		(start 34.45637 -258.8768)
		(end 34.45637 -256.50063)
		(width 0.1397)
		(layer "B.Cu")
		(net "NCT7904_D2+")
	)
	(segment
		(start 31.496 -317.745872)
		(end 31.496 -316.8904)
		(width 0.1397)
		(layer "B.Cu")
		(net "NCT7904_D2+")
	)
	(segment
		(start 29.61132 -153.32202)
		(end 29.5783 -153.289)
		(width 0.1397)
		(layer "F.Cu")
		(net "NCT7904_D2-")
	)
	(segment
		(start 29.61132 -155.607766)
		(end 29.61132 -153.32202)
		(width 0.1397)
		(layer "F.Cu")
		(net "NCT7904_D2-")
	)
	(segment
		(start 28.452572 -320.984372)
		(end 29.662628 -320.984372)
		(width 0.1397)
		(layer "F.Cu")
		(net "NCT7904_D2-")
	)
	(segment
		(start 29.5783 -151.7269)
		(end 29.464 -151.6126)
		(width 0.1397)
		(layer "F.Cu")
		(net "NCT7904_D2-")
	)
	(segment
		(start 29.5783 -153.289)
		(end 29.5783 -151.7269)
		(width 0.1397)
		(layer "F.Cu")
		(net "NCT7904_D2-")
	)
	(segment
		(start 29.662628 -320.984372)
		(end 30.353 -320.294)
		(width 0.1397)
		(layer "F.Cu")
		(net "NCT7904_D2-")
	)
	(via
		(at 29.464 -151.6126)
		(size 0.5588)
		(drill 0.3048)
		(layers "F.Cu" "B.Cu")
		(net "NCT7904_D2-")
	)
	(via
		(at 30.353 -320.294)
		(size 0.5588)
		(drill 0.3048)
		(layers "F.Cu" "B.Cu")
		(net "NCT7904_D2-")
	)
	(via
		(at 31.163768 -319.483232)
		(size 0.7112)
		(drill 0.3556)
		(layers "F.Cu" "B.Cu")
		(net "NCT7904_D2-")
	)
	(segment
		(start 34.4551 -274.410678)
		(end 34.4551 -273.14779)
		(width 0.1397)
		(layer "B.Cu")
		(net "NCT7904_D2-")
	)
	(segment
		(start 42.1132 -250.317)
		(end 42.1132 -216.0905)
		(width 0.1397)
		(layer "B.Cu")
		(net "NCT7904_D2-")
	)
	(segment
		(start 36.504626 -210.489546)
		(end 36.504626 -174.575724)
		(width 0.1397)
		(layer "B.Cu")
		(net "NCT7904_D2-")
	)
	(segment
		(start 30.353 -320.294)
		(end 31.163768 -319.483232)
		(width 0.1397)
		(layer "B.Cu")
		(net "NCT7904_D2-")
	)
	(segment
		(start 39.6875 -213.6648)
		(end 39.67988 -213.6648)
		(width 0.1397)
		(layer "B.Cu")
		(net "NCT7904_D2-")
	)
	(segment
		(start 34.925 -259.0546)
		(end 34.925 -256.794)
		(width 0.1397)
		(layer "B.Cu")
		(net "NCT7904_D2-")
	)
	(segment
		(start 34.455354 -274.410932)
		(end 34.4551 -274.410678)
		(width 0.1397)
		(layer "B.Cu")
		(net "NCT7904_D2-")
	)
	(segment
		(start 42.1132 -216.0905)
		(end 39.6875 -213.6648)
		(width 0.1397)
		(layer "B.Cu")
		(net "NCT7904_D2-")
	)
	(segment
		(start 34.455354 -273.147536)
		(end 34.455354 -259.524246)
		(width 0.1397)
		(layer "B.Cu")
		(net "NCT7904_D2-")
	)
	(segment
		(start 40.8432 -250.8758)
		(end 41.5544 -250.8758)
		(width 0.1397)
		(layer "B.Cu")
		(net "NCT7904_D2-")
	)
	(segment
		(start 34.925 -256.794)
		(end 40.8432 -250.8758)
		(width 0.1397)
		(layer "B.Cu")
		(net "NCT7904_D2-")
	)
	(segment
		(start 36.27755 -168.29405)
		(end 36.27755 -158.42615)
		(width 0.1397)
		(layer "B.Cu")
		(net "NCT7904_D2-")
	)
	(segment
		(start 36.504626 -174.575724)
		(end 37.01415 -174.0662)
		(width 0.1397)
		(layer "B.Cu")
		(net "NCT7904_D2-")
	)
	(segment
		(start 35.756342 -168.815258)
		(end 36.27755 -168.29405)
		(width 0.1397)
		(layer "B.Cu")
		(net "NCT7904_D2-")
	)
	(segment
		(start 41.5544 -250.8758)
		(end 42.1132 -250.317)
		(width 0.1397)
		(layer "B.Cu")
		(net "NCT7904_D2-")
	)
	(segment
		(start 32.131 -278.257)
		(end 34.455354 -275.932646)
		(width 0.1397)
		(layer "B.Cu")
		(net "NCT7904_D2-")
	)
	(segment
		(start 36.27755 -158.42615)
		(end 29.464 -151.6126)
		(width 0.1397)
		(layer "B.Cu")
		(net "NCT7904_D2-")
	)
	(segment
		(start 34.4551 -273.14779)
		(end 34.455354 -273.147536)
		(width 0.1397)
		(layer "B.Cu")
		(net "NCT7904_D2-")
	)
	(segment
		(start 39.67988 -213.6648)
		(end 36.504626 -210.489546)
		(width 0.1397)
		(layer "B.Cu")
		(net "NCT7904_D2-")
	)
	(segment
		(start 35.756342 -169.233342)
		(end 35.756342 -168.815258)
		(width 0.1397)
		(layer "B.Cu")
		(net "NCT7904_D2-")
	)
	(segment
		(start 34.455354 -275.932646)
		(end 34.455354 -274.410932)
		(width 0.1397)
		(layer "B.Cu")
		(net "NCT7904_D2-")
	)
	(segment
		(start 37.01415 -170.49115)
		(end 35.756342 -169.233342)
		(width 0.1397)
		(layer "B.Cu")
		(net "NCT7904_D2-")
	)
	(segment
		(start 37.01415 -174.0662)
		(end 37.01415 -170.49115)
		(width 0.1397)
		(layer "B.Cu")
		(net "NCT7904_D2-")
	)
	(segment
		(start 31.163768 -319.483232)
		(end 32.131 -318.516)
		(width 0.1397)
		(layer "B.Cu")
		(net "NCT7904_D2-")
	)
	(segment
		(start 32.131 -318.516)
		(end 32.131 -278.257)
		(width 0.1397)
		(layer "B.Cu")
		(net "NCT7904_D2-")
	)
	(segment
		(start 34.455354 -259.524246)
		(end 34.925 -259.0546)
		(width 0.1397)
		(layer "B.Cu")
		(net "NCT7904_D2-")
	)
	(segment
		(start 28.452572 -144.015714)
		(end 27.531822 -144.015714)
		(width 0.1397)
		(layer "F.Cu")
		(net "NCT7904_D1+")
	)
	(segment
		(start 27.0256 -148.6916)
		(end 27.0256 -147.461732)
		(width 0.1397)
		(layer "F.Cu")
		(net "NCT7904_D1+")
	)
	(segment
		(start 28.11145 -155.607766)
		(end 28.11145 -154.672538)
		(width 0.1397)
		(layer "F.Cu")
		(net "NCT7904_D1+")
	)
	(segment
		(start 27.531822 -144.015714)
		(end 26.547572 -144.999964)
		(width 0.1397)
		(layer "F.Cu")
		(net "NCT7904_D1+")
	)
	(segment
		(start 26.547572 -144.999964)
		(end 27.009852 -145.462244)
		(width 0.1397)
		(layer "F.Cu")
		(net "NCT7904_D1+")
	)
	(segment
		(start 27.0256 -147.461732)
		(end 27.009852 -147.445984)
		(width 0.1397)
		(layer "F.Cu")
		(net "NCT7904_D1+")
	)
	(segment
		(start 27.3431 -150.7998)
		(end 27.559 -150.5839)
		(width 0.1397)
		(layer "F.Cu")
		(net "NCT7904_D1+")
	)
	(segment
		(start 28.11145 -154.672538)
		(end 27.5463 -154.107388)
		(width 0.1397)
		(layer "F.Cu")
		(net "NCT7904_D1+")
	)
	(segment
		(start 27.5463 -151.003)
		(end 27.3431 -150.7998)
		(width 0.1397)
		(layer "F.Cu")
		(net "NCT7904_D1+")
	)
	(segment
		(start 27.009852 -145.462244)
		(end 27.009852 -147.445984)
		(width 0.1397)
		(layer "F.Cu")
		(net "NCT7904_D1+")
	)
	(segment
		(start 27.559 -149.225)
		(end 27.0256 -148.6916)
		(width 0.1397)
		(layer "F.Cu")
		(net "NCT7904_D1+")
	)
	(segment
		(start 27.559 -150.5839)
		(end 27.559 -149.225)
		(width 0.1397)
		(layer "F.Cu")
		(net "NCT7904_D1+")
	)
	(segment
		(start 27.5463 -154.107388)
		(end 27.5463 -151.003)
		(width 0.1397)
		(layer "F.Cu")
		(net "NCT7904_D1+")
	)
	(via
		(at 27.009852 -147.445984)
		(size 0.7112)
		(drill 0.3556)
		(layers "F.Cu" "B.Cu")
		(net "NCT7904_D1+")
	)
	(segment
		(start 28.452572 -145.984214)
		(end 28.452572 -148.5646)
		(width 0.1397)
		(layer "F.Cu")
		(net "NCT7904_D1-")
	)
	(segment
		(start 28.61183 -155.607766)
		(end 28.61183 -154.544268)
		(width 0.1397)
		(layer "F.Cu")
		(net "NCT7904_D1-")
	)
	(segment
		(start 28.067 -148.950172)
		(end 28.452572 -148.5646)
		(width 0.1397)
		(layer "F.Cu")
		(net "NCT7904_D1-")
	)
	(segment
		(start 27.9908 -151.0411)
		(end 28.2321 -150.7998)
		(width 0.1397)
		(layer "F.Cu")
		(net "NCT7904_D1-")
	)
	(segment
		(start 28.2321 -150.7998)
		(end 28.067 -150.6347)
		(width 0.1397)
		(layer "F.Cu")
		(net "NCT7904_D1-")
	)
	(segment
		(start 28.61183 -154.544268)
		(end 27.9908 -153.923238)
		(width 0.1397)
		(layer "F.Cu")
		(net "NCT7904_D1-")
	)
	(segment
		(start 27.9908 -153.923238)
		(end 27.9908 -151.0411)
		(width 0.1397)
		(layer "F.Cu")
		(net "NCT7904_D1-")
	)
	(segment
		(start 28.067 -150.6347)
		(end 28.067 -148.950172)
		(width 0.1397)
		(layer "F.Cu")
		(net "NCT7904_D1-")
	)
	(via
		(at 28.452572 -148.5646)
		(size 0.7112)
		(drill 0.3556)
		(layers "F.Cu" "B.Cu")
		(net "NCT7904_D1-")
	)
	(segment
		(start 29.59608 -252.984)
		(end 29.59608 -250.2408)
		(width 0.1397)
		(layer "F.Cu")
		(net "EEPROM_WP")
	)
	(segment
		(start 29.1592 -253.4539)
		(end 29.1592 -253.42088)
		(width 0.1397)
		(layer "F.Cu")
		(net "EEPROM_WP")
	)
	(segment
		(start 29.1592 -253.42088)
		(end 29.59608 -252.984)
		(width 0.1397)
		(layer "F.Cu")
		(net "EEPROM_WP")
	)
	(segment
		(start 28.0416 -253.4539)
		(end 29.1592 -253.4539)
		(width 0.1397)
		(layer "F.Cu")
		(net "EEPROM_WP")
	)
	(via
		(at 28.0416 -253.4539)
		(size 0.7112)
		(drill 0.3556)
		(layers "F.Cu" "B.Cu")
		(net "EEPROM_WP")
	)
	(segment
		(start 8.509 -63.4365)
		(end 9.4488 -64.3763)
		(width 0.1397)
		(layer "F.Cu")
		(net "LED_DR_LED5_K")
	)
	(segment
		(start 8.509 -61.3918)
		(end 8.509 -63.4365)
		(width 0.1397)
		(layer "F.Cu")
		(net "LED_DR_LED5_K")
	)
	(segment
		(start 7.323836 -56.099964)
		(end 6.477 -56.9468)
		(width 0.1397)
		(layer "F.Cu")
		(net "LED_DR_LED5_K")
	)
	(segment
		(start 6.477 -56.9468)
		(end 6.477 -59.3598)
		(width 0.1397)
		(layer "F.Cu")
		(net "LED_DR_LED5_K")
	)
	(segment
		(start 6.477 -59.3598)
		(end 8.509 -61.3918)
		(width 0.1397)
		(layer "F.Cu")
		(net "LED_DR_LED5_K")
	)
	(segment
		(start 7.949946 -56.099964)
		(end 7.323836 -56.099964)
		(width 0.1397)
		(layer "F.Cu")
		(net "LED_DR_LED5_K")
	)
	(segment
		(start 8.580628 -232.7656)
		(end 11.5189 -232.7656)
		(width 0.1397)
		(layer "F.Cu")
		(net "LED_DR_LED3_K")
	)
	(segment
		(start 7.949946 -232.134918)
		(end 8.580628 -232.7656)
		(width 0.1397)
		(layer "F.Cu")
		(net "LED_DR_LED3_K")
	)
	(segment
		(start 6.1976 -268.8082)
		(end 6.1976 -272.986246)
		(width 0.1397)
		(layer "F.Cu")
		(net "LED_DR_LED2_K")
	)
	(segment
		(start 7.949946 -267.865098)
		(end 7.140702 -267.865098)
		(width 0.1397)
		(layer "F.Cu")
		(net "LED_DR_LED2_K")
	)
	(segment
		(start 6.1976 -272.986246)
		(end 7.6327 -274.421346)
		(width 0.1397)
		(layer "F.Cu")
		(net "LED_DR_LED2_K")
	)
	(segment
		(start 7.140702 -267.865098)
		(end 6.1976 -268.8082)
		(width 0.1397)
		(layer "F.Cu")
		(net "LED_DR_LED2_K")
	)
	(segment
		(start 7.6327 -274.421346)
		(end 7.6327 -275.2344)
		(width 0.1397)
		(layer "F.Cu")
		(net "LED_DR_LED2_K")
	)
	(segment
		(start 7.949946 -411.465014)
		(end 6.4262 -412.98876)
		(width 0.1397)
		(layer "F.Cu")
		(net "LED_DR_LED1_K")
	)
	(segment
		(start 6.4262 -415.7853)
		(end 5.6007 -416.6108)
		(width 0.1397)
		(layer "F.Cu")
		(net "LED_DR_LED1_K")
	)
	(segment
		(start 6.4262 -412.98876)
		(end 6.4262 -415.7853)
		(width 0.1397)
		(layer "F.Cu")
		(net "LED_DR_LED1_K")
	)
	(segment
		(start 28.59405 -365.252)
		(end 29.068014 -365.725964)
		(width 0.1397)
		(layer "F.Cu")
		(net "ADM1276_ADR")
	)
	(segment
		(start 24.5999 -360.7435)
		(end 24.2824 -360.7435)
		(width 0.1397)
		(layer "F.Cu")
		(net "ADM1276_ADR")
	)
	(segment
		(start 24.9174 -361.061)
		(end 24.5999 -360.7435)
		(width 0.1397)
		(layer "F.Cu")
		(net "ADM1276_ADR")
	)
	(segment
		(start 25.019 -362.8136)
		(end 24.9174 -362.712)
		(width 0.1397)
		(layer "F.Cu")
		(net "ADM1276_ADR")
	)
	(segment
		(start 24.2824 -360.7435)
		(end 23.241 -360.7435)
		(width 0.1397)
		(layer "F.Cu")
		(net "ADM1276_ADR")
	)
	(segment
		(start 29.068014 -365.725964)
		(end 29.068014 -366.3696)
		(width 0.1397)
		(layer "F.Cu")
		(net "ADM1276_ADR")
	)
	(segment
		(start 27.813 -365.252)
		(end 28.59405 -365.252)
		(width 0.1397)
		(layer "F.Cu")
		(net "ADM1276_ADR")
	)
	(segment
		(start 24.9174 -362.712)
		(end 24.9174 -361.061)
		(width 0.1397)
		(layer "F.Cu")
		(net "ADM1276_ADR")
	)
	(via
		(at 25.8064 -363.474)
		(size 0.7112)
		(drill 0.3556)
		(layers "F.Cu" "B.Cu")
		(net "ADM1276_ADR")
	)
	(via
		(at 27.813 -365.252)
		(size 0.7112)
		(drill 0.4064)
		(layers "F.Cu" "B.Cu")
		(net "ADM1276_ADR")
	)
	(via
		(at 25.019 -362.8136)
		(size 0.7112)
		(drill 0.4064)
		(layers "F.Cu" "B.Cu")
		(net "ADM1276_ADR")
	)
	(segment
		(start 25.019 -362.8136)
		(end 25.146 -362.8136)
		(width 0.1397)
		(layer "B.Cu")
		(net "ADM1276_ADR")
	)
	(segment
		(start 26.0604 -363.728)
		(end 25.8064 -363.474)
		(width 0.1397)
		(layer "B.Cu")
		(net "ADM1276_ADR")
	)
	(segment
		(start 26.289 -363.728)
		(end 26.0604 -363.728)
		(width 0.1397)
		(layer "B.Cu")
		(net "ADM1276_ADR")
	)
	(segment
		(start 25.146 -362.8136)
		(end 25.8064 -363.474)
		(width 0.1397)
		(layer "B.Cu")
		(net "ADM1276_ADR")
	)
	(segment
		(start 27.813 -365.252)
		(end 26.289 -363.728)
		(width 0.1397)
		(layer "B.Cu")
		(net "ADM1276_ADR")
	)
	(segment
		(start 7.949946 -443.900052)
		(end 6.5786 -442.528706)
		(width 0.1397)
		(layer "F.Cu")
		(net "LED_DR_LED0_K")
	)
	(segment
		(start 6.5786 -442.528706)
		(end 6.5786 -438.1881)
		(width 0.1397)
		(layer "F.Cu")
		(net "LED_DR_LED0_K")
	)
	(segment
		(start 37.5666 -252.7046)
		(end 37.4904 -252.6284)
		(width 0.1397)
		(layer "F.Cu")
		(net "LED_DR_LED7_RESERVE")
	)
	(segment
		(start 37.48532 -252.62332)
		(end 37.4904 -252.6284)
		(width 0.1397)
		(layer "F.Cu")
		(net "LED_DR_LED7_RESERVE")
	)
	(segment
		(start 37.48532 -249.3518)
		(end 37.48532 -252.62332)
		(width 0.1397)
		(layer "F.Cu")
		(net "LED_DR_LED7_RESERVE")
	)
	(segment
		(start 37.5666 -253.9111)
		(end 37.5666 -252.7046)
		(width 0.1397)
		(layer "F.Cu")
		(net "LED_DR_LED7_RESERVE")
	)
	(segment
		(start 21.7805 -18.161)
		(end 20.701 -18.161)
		(width 0.1397)
		(layer "F.Cu")
		(net "FANIN_12")
	)
	(segment
		(start 30.1117 -165.5953)
		(end 29.8196 -165.8874)
		(width 0.1397)
		(layer "F.Cu")
		(net "FANIN_12")
	)
	(segment
		(start 20.701 -19.177)
		(end 20.701 -18.161)
		(width 0.1397)
		(layer "F.Cu")
		(net "FANIN_12")
	)
	(segment
		(start 30.1117 -164.091366)
		(end 30.1117 -165.5953)
		(width 0.1397)
		(layer "F.Cu")
		(net "FANIN_12")
	)
	(via
		(at 20.701 -19.177)
		(size 0.5588)
		(drill 0.3048)
		(layers "F.Cu" "B.Cu")
		(net "FANIN_12")
	)
	(via
		(at 29.8196 -165.8874)
		(size 0.5588)
		(drill 0.3048)
		(layers "F.Cu" "B.Cu")
		(net "FANIN_12")
	)
	(via
		(at 14.922246 -25.692354)
		(size 0.7112)
		(drill 0.3556)
		(layers "F.Cu" "B.Cu")
		(net "FANIN_12")
	)
	(segment
		(start 14.186154 -46.665134)
		(end 12.64285 -48.208438)
		(width 0.1397)
		(layer "B.Cu")
		(net "FANIN_12")
	)
	(segment
		(start 12.64285 -48.208438)
		(end 12.64285 -52.11445)
		(width 0.1397)
		(layer "B.Cu")
		(net "FANIN_12")
	)
	(segment
		(start 9.271 -124.244354)
		(end 9.271 -133.2992)
		(width 0.1397)
		(layer "B.Cu")
		(net "FANIN_12")
	)
	(segment
		(start 9.245092 -111.84255)
		(end 9.245346 -111.842804)
		(width 0.1397)
		(layer "B.Cu")
		(net "FANIN_12")
	)
	(segment
		(start 9.245346 -92.1512)
		(end 9.245346 -110.000796)
		(width 0.1397)
		(layer "B.Cu")
		(net "FANIN_12")
	)
	(segment
		(start 16.453104 -148.6154)
		(end 19.05 -151.212296)
		(width 0.1397)
		(layer "B.Cu")
		(net "FANIN_12")
	)
	(segment
		(start 13.10005 -53.765958)
		(end 12.65555 -54.210458)
		(width 0.1397)
		(layer "B.Cu")
		(net "FANIN_12")
	)
	(segment
		(start 10.514584 -113.130584)
		(end 10.514584 -122.263662)
		(width 0.1397)
		(layer "B.Cu")
		(net "FANIN_12")
	)
	(segment
		(start 12.65555 -54.210458)
		(end 12.65555 -60.217558)
		(width 0.1397)
		(layer "B.Cu")
		(net "FANIN_12")
	)
	(segment
		(start 9.245092 -110.00105)
		(end 9.245092 -111.84255)
		(width 0.1397)
		(layer "B.Cu")
		(net "FANIN_12")
	)
	(segment
		(start 9.245346 -111.842804)
		(end 9.245346 -111.861346)
		(width 0.1397)
		(layer "B.Cu")
		(net "FANIN_12")
	)
	(segment
		(start 9.270492 -123.507754)
		(end 9.270492 -123.876054)
		(width 0.1397)
		(layer "B.Cu")
		(net "FANIN_12")
	)
	(segment
		(start 15.0114 -147.885658)
		(end 15.741142 -148.6154)
		(width 0.1397)
		(layer "B.Cu")
		(net "FANIN_12")
	)
	(segment
		(start 20.701 -19.177)
		(end 20.701 -19.9136)
		(width 0.1397)
		(layer "B.Cu")
		(net "FANIN_12")
	)
	(segment
		(start 14.922246 -25.692354)
		(end 14.186154 -26.428446)
		(width 0.1397)
		(layer "B.Cu")
		(net "FANIN_12")
	)
	(segment
		(start 9.7028 -68.072)
		(end 9.7028 -91.693238)
		(width 0.1397)
		(layer "B.Cu")
		(net "FANIN_12")
	)
	(segment
		(start 14.186154 -26.428446)
		(end 14.186154 -46.665134)
		(width 0.1397)
		(layer "B.Cu")
		(net "FANIN_12")
	)
	(segment
		(start 10.514584 -122.263662)
		(end 9.270492 -123.507754)
		(width 0.1397)
		(layer "B.Cu")
		(net "FANIN_12")
	)
	(segment
		(start 15.0114 -145.6944)
		(end 15.0114 -147.885658)
		(width 0.1397)
		(layer "B.Cu")
		(net "FANIN_12")
	)
	(segment
		(start 13.10005 -52.57165)
		(end 13.10005 -53.765958)
		(width 0.1397)
		(layer "B.Cu")
		(net "FANIN_12")
	)
	(segment
		(start 9.245346 -111.861346)
		(end 10.514584 -113.130584)
		(width 0.1397)
		(layer "B.Cu")
		(net "FANIN_12")
	)
	(segment
		(start 19.05 -154.844496)
		(end 29.8196 -165.614096)
		(width 0.1397)
		(layer "B.Cu")
		(net "FANIN_12")
	)
	(segment
		(start 9.271 -133.2992)
		(end 12.3444 -136.3726)
		(width 0.1397)
		(layer "B.Cu")
		(net "FANIN_12")
	)
	(segment
		(start 15.741142 -148.6154)
		(end 16.453104 -148.6154)
		(width 0.1397)
		(layer "B.Cu")
		(net "FANIN_12")
	)
	(segment
		(start 9.245346 -110.000796)
		(end 9.245092 -110.00105)
		(width 0.1397)
		(layer "B.Cu")
		(net "FANIN_12")
	)
	(segment
		(start 12.79525 -60.357258)
		(end 12.79525 -64.97955)
		(width 0.1397)
		(layer "B.Cu")
		(net "FANIN_12")
	)
	(segment
		(start 9.270746 -124.2441)
		(end 9.271 -124.244354)
		(width 0.1397)
		(layer "B.Cu")
		(net "FANIN_12")
	)
	(segment
		(start 20.701 -19.9136)
		(end 14.922246 -25.692354)
		(width 0.1397)
		(layer "B.Cu")
		(net "FANIN_12")
	)
	(segment
		(start 9.270492 -123.876054)
		(end 9.270746 -123.876308)
		(width 0.1397)
		(layer "B.Cu")
		(net "FANIN_12")
	)
	(segment
		(start 12.3444 -136.3726)
		(end 12.3444 -143.0274)
		(width 0.1397)
		(layer "B.Cu")
		(net "FANIN_12")
	)
	(segment
		(start 9.2456 -92.150946)
		(end 9.245346 -92.1512)
		(width 0.1397)
		(layer "B.Cu")
		(net "FANIN_12")
	)
	(segment
		(start 29.8196 -165.614096)
		(end 29.8196 -165.8874)
		(width 0.1397)
		(layer "B.Cu")
		(net "FANIN_12")
	)
	(segment
		(start 9.2456 -92.150438)
		(end 9.2456 -92.150946)
		(width 0.1397)
		(layer "B.Cu")
		(net "FANIN_12")
	)
	(segment
		(start 12.79525 -64.97955)
		(end 9.7028 -68.072)
		(width 0.1397)
		(layer "B.Cu")
		(net "FANIN_12")
	)
	(segment
		(start 12.3444 -143.0274)
		(end 15.0114 -145.6944)
		(width 0.1397)
		(layer "B.Cu")
		(net "FANIN_12")
	)
	(segment
		(start 19.05 -151.212296)
		(end 19.05 -154.844496)
		(width 0.1397)
		(layer "B.Cu")
		(net "FANIN_12")
	)
	(segment
		(start 12.64285 -52.11445)
		(end 13.10005 -52.57165)
		(width 0.1397)
		(layer "B.Cu")
		(net "FANIN_12")
	)
	(segment
		(start 9.270746 -123.876308)
		(end 9.270746 -124.2441)
		(width 0.1397)
		(layer "B.Cu")
		(net "FANIN_12")
	)
	(segment
		(start 9.7028 -91.693238)
		(end 9.2456 -92.150438)
		(width 0.1397)
		(layer "B.Cu")
		(net "FANIN_12")
	)
	(segment
		(start 12.65555 -60.217558)
		(end 12.79525 -60.357258)
		(width 0.1397)
		(layer "B.Cu")
		(net "FANIN_12")
	)
	(segment
		(start 31.115 -166.0271)
		(end 31.11246 -166.02456)
		(width 0.1397)
		(layer "F.Cu")
		(net "FANIN_11")
	)
	(segment
		(start 21.347938 -15.595092)
		(end 22.389846 -15.595092)
		(width 0.1397)
		(layer "F.Cu")
		(net "FANIN_11")
	)
	(segment
		(start 22.389846 -15.595092)
		(end 22.416262 -15.621508)
		(width 0.1397)
		(layer "F.Cu")
		(net "FANIN_11")
	)
	(segment
		(start 22.416262 -15.621508)
		(end 22.416262 -16.637)
		(width 0.1397)
		(layer "F.Cu")
		(net "FANIN_11")
	)
	(segment
		(start 31.11246 -166.02456)
		(end 31.11246 -164.091366)
		(width 0.1397)
		(layer "F.Cu")
		(net "FANIN_11")
	)
	(via
		(at 19.9136 -21.8694)
		(size 0.7112)
		(drill 0.3556)
		(layers "F.Cu" "B.Cu")
		(net "FANIN_11")
	)
	(via
		(at 22.416262 -16.637)
		(size 0.5588)
		(drill 0.3048)
		(layers "F.Cu" "B.Cu")
		(net "FANIN_11")
	)
	(via
		(at 31.115 -166.0271)
		(size 0.5588)
		(drill 0.3048)
		(layers "F.Cu" "B.Cu")
		(net "FANIN_11")
	)
	(segment
		(start 9.6901 -92.334588)
		(end 10.1473 -91.877388)
		(width 0.1397)
		(layer "B.Cu")
		(net "FANIN_11")
	)
	(segment
		(start 13.08735 -48.392842)
		(end 14.6304 -46.849792)
		(width 0.1397)
		(layer "B.Cu")
		(net "FANIN_11")
	)
	(segment
		(start 14.6304 -46.849792)
		(end 14.6304 -46.849538)
		(width 0.1397)
		(layer "B.Cu")
		(net "FANIN_11")
	)
	(segment
		(start 15.4686 -145.5166)
		(end 12.7889 -142.8369)
		(width 0.1397)
		(layer "B.Cu")
		(net "FANIN_11")
	)
	(segment
		(start 10.959084 -112.927892)
		(end 9.689592 -111.6584)
		(width 0.1397)
		(layer "B.Cu")
		(net "FANIN_11")
	)
	(segment
		(start 15.912592 -148.1582)
		(end 15.4686 -147.714208)
		(width 0.1397)
		(layer "B.Cu")
		(net "FANIN_11")
	)
	(segment
		(start 9.7155 -133.0833)
		(end 9.7155 -124.060204)
		(width 0.1397)
		(layer "B.Cu")
		(net "FANIN_11")
	)
	(segment
		(start 15.4686 -147.714208)
		(end 15.4686 -145.5166)
		(width 0.1397)
		(layer "B.Cu")
		(net "FANIN_11")
	)
	(segment
		(start 10.959084 -122.448066)
		(end 10.959084 -112.927892)
		(width 0.1397)
		(layer "B.Cu")
		(net "FANIN_11")
	)
	(segment
		(start 9.689846 -108.908088)
		(end 9.6901 -108.907834)
		(width 0.1397)
		(layer "B.Cu")
		(net "FANIN_11")
	)
	(segment
		(start 14.6304 -46.849538)
		(end 14.630654 -46.849284)
		(width 0.1397)
		(layer "B.Cu")
		(net "FANIN_11")
	)
	(segment
		(start 9.7155 -124.060204)
		(end 9.715246 -124.05995)
		(width 0.1397)
		(layer "B.Cu")
		(net "FANIN_11")
	)
	(segment
		(start 19.9136 -21.8694)
		(end 21.463 -20.32)
		(width 0.1397)
		(layer "B.Cu")
		(net "FANIN_11")
	)
	(segment
		(start 19.8882 -21.8694)
		(end 19.9136 -21.8694)
		(width 0.1397)
		(layer "B.Cu")
		(net "FANIN_11")
	)
	(segment
		(start 9.689846 -110.184946)
		(end 9.689846 -108.908088)
		(width 0.1397)
		(layer "B.Cu")
		(net "FANIN_11")
	)
	(segment
		(start 14.24305 -53.77815)
		(end 14.24305 -52.330858)
		(width 0.1397)
		(layer "B.Cu")
		(net "FANIN_11")
	)
	(segment
		(start 12.7889 -142.8369)
		(end 12.7889 -136.1567)
		(width 0.1397)
		(layer "B.Cu")
		(net "FANIN_11")
	)
	(segment
		(start 13.81125 -64.598804)
		(end 13.81125 -58.69305)
		(width 0.1397)
		(layer "B.Cu")
		(net "FANIN_11")
	)
	(segment
		(start 19.5072 -154.4193)
		(end 19.5072 -151.040846)
		(width 0.1397)
		(layer "B.Cu")
		(net "FANIN_11")
	)
	(segment
		(start 14.630654 -46.849284)
		(end 14.630654 -27.126946)
		(width 0.1397)
		(layer "B.Cu")
		(net "FANIN_11")
	)
	(segment
		(start 9.689592 -110.1852)
		(end 9.689846 -110.184946)
		(width 0.1397)
		(layer "B.Cu")
		(net "FANIN_11")
	)
	(segment
		(start 10.1473 -68.262754)
		(end 13.81125 -64.598804)
		(width 0.1397)
		(layer "B.Cu")
		(net "FANIN_11")
	)
	(segment
		(start 14.24305 -52.330858)
		(end 13.08735 -51.175158)
		(width 0.1397)
		(layer "B.Cu")
		(net "FANIN_11")
	)
	(segment
		(start 13.18895 -54.83225)
		(end 14.24305 -53.77815)
		(width 0.1397)
		(layer "B.Cu")
		(net "FANIN_11")
	)
	(segment
		(start 21.463 -17.590262)
		(end 22.416262 -16.637)
		(width 0.1397)
		(layer "B.Cu")
		(net "FANIN_11")
	)
	(segment
		(start 16.624554 -148.1582)
		(end 15.912592 -148.1582)
		(width 0.1397)
		(layer "B.Cu")
		(net "FANIN_11")
	)
	(segment
		(start 21.463 -20.32)
		(end 21.463 -17.590262)
		(width 0.1397)
		(layer "B.Cu")
		(net "FANIN_11")
	)
	(segment
		(start 9.715246 -124.05995)
		(end 9.715246 -123.691904)
		(width 0.1397)
		(layer "B.Cu")
		(net "FANIN_11")
	)
	(segment
		(start 14.630654 -27.126946)
		(end 19.8882 -21.8694)
		(width 0.1397)
		(layer "B.Cu")
		(net "FANIN_11")
	)
	(segment
		(start 9.715246 -123.691904)
		(end 10.959084 -122.448066)
		(width 0.1397)
		(layer "B.Cu")
		(net "FANIN_11")
	)
	(segment
		(start 13.81125 -58.69305)
		(end 13.18895 -58.07075)
		(width 0.1397)
		(layer "B.Cu")
		(net "FANIN_11")
	)
	(segment
		(start 9.689592 -111.6584)
		(end 9.689592 -110.1852)
		(width 0.1397)
		(layer "B.Cu")
		(net "FANIN_11")
	)
	(segment
		(start 10.1473 -91.877388)
		(end 10.1473 -68.262754)
		(width 0.1397)
		(layer "B.Cu")
		(net "FANIN_11")
	)
	(segment
		(start 12.7889 -136.1567)
		(end 9.7155 -133.0833)
		(width 0.1397)
		(layer "B.Cu")
		(net "FANIN_11")
	)
	(segment
		(start 13.08735 -51.175158)
		(end 13.08735 -48.392842)
		(width 0.1397)
		(layer "B.Cu")
		(net "FANIN_11")
	)
	(segment
		(start 31.115 -166.0271)
		(end 19.5072 -154.4193)
		(width 0.1397)
		(layer "B.Cu")
		(net "FANIN_11")
	)
	(segment
		(start 13.18895 -58.07075)
		(end 13.18895 -54.83225)
		(width 0.1397)
		(layer "B.Cu")
		(net "FANIN_11")
	)
	(segment
		(start 9.6901 -108.907834)
		(end 9.6901 -92.334588)
		(width 0.1397)
		(layer "B.Cu")
		(net "FANIN_11")
	)
	(segment
		(start 19.5072 -151.040846)
		(end 16.624554 -148.1582)
		(width 0.1397)
		(layer "B.Cu")
		(net "FANIN_11")
	)
	(segment
		(start 25.1206 -209.0166)
		(end 18.3896 -209.0166)
		(width 0.1397)
		(layer "F.Cu")
		(net "PWM_OUT")
	)
	(segment
		(start 25.4508 -168.6306)
		(end 25.781 -168.9608)
		(width 0.1397)
		(layer "F.Cu")
		(net "PWM_OUT")
	)
	(segment
		(start 25.781 -222.0722)
		(end 25.781 -222.0468)
		(width 0.1397)
		(layer "F.Cu")
		(net "PWM_OUT")
	)
	(segment
		(start 28.1559 -169.8244)
		(end 28.6639 -170.3324)
		(width 0.1397)
		(layer "F.Cu")
		(net "PWM_OUT")
	)
	(segment
		(start 25.0698 -222.7834)
		(end 25.781 -222.0722)
		(width 0.1397)
		(layer "F.Cu")
		(net "PWM_OUT")
	)
	(segment
		(start 25.781 -168.9608)
		(end 26.5176 -168.9608)
		(width 0.1397)
		(layer "F.Cu")
		(net "PWM_OUT")
	)
	(segment
		(start 22.328886 -173.33341)
		(end 21.995638 -173.000162)
		(width 0.1397)
		(layer "F.Cu")
		(net "PWM_OUT")
	)
	(segment
		(start 27.3812 -169.8244)
		(end 28.1559 -169.8244)
		(width 0.1397)
		(layer "F.Cu")
		(net "PWM_OUT")
	)
	(segment
		(start 26.5176 -168.9608)
		(end 27.3812 -169.8244)
		(width 0.1397)
		(layer "F.Cu")
		(net "PWM_OUT")
	)
	(segment
		(start 23.674324 -173.33341)
		(end 22.328886 -173.33341)
		(width 0.1397)
		(layer "F.Cu")
		(net "PWM_OUT")
	)
	(via
		(at 25.4508 -168.6306)
		(size 0.5588)
		(drill 0.3048)
		(layers "F.Cu" "B.Cu")
		(net "PWM_OUT")
	)
	(via
		(at 25.781 -222.0468)
		(size 0.5588)
		(drill 0.3048)
		(layers "F.Cu" "B.Cu")
		(net "PWM_OUT")
	)
	(via
		(at 21.995638 -173.000162)
		(size 0.5588)
		(drill 0.3048)
		(layers "F.Cu" "B.Cu")
		(net "PWM_OUT")
	)
	(via
		(at 25.0698 -222.7834)
		(size 0.7112)
		(drill 0.3556)
		(layers "F.Cu" "B.Cu")
		(net "PWM_OUT")
	)
	(via
		(at 25.1206 -209.0166)
		(size 0.5588)
		(drill 0.3048)
		(layers "F.Cu" "B.Cu")
		(net "PWM_OUT")
	)
	(via
		(at 18.3896 -209.0166)
		(size 0.5588)
		(drill 0.3048)
		(layers "F.Cu" "B.Cu")
		(net "PWM_OUT")
	)
	(segment
		(start 24.99995 -221.26575)
		(end 25.781 -222.0468)
		(width 0.1397)
		(layer "B.Cu")
		(net "PWM_OUT")
	)
	(segment
		(start 23.583646 -170.4086)
		(end 23.583646 -171.412154)
		(width 0.1397)
		(layer "B.Cu")
		(net "PWM_OUT")
	)
	(segment
		(start 18.3896 -209.0166)
		(end 18.3896 -194.57035)
		(width 0.1397)
		(layer "B.Cu")
		(net "PWM_OUT")
	)
	(segment
		(start 21.06295 -191.897)
		(end 21.06295 -175.759618)
		(width 0.1397)
		(layer "B.Cu")
		(net "PWM_OUT")
	)
	(segment
		(start 21.06295 -175.759618)
		(end 21.995638 -174.82693)
		(width 0.1397)
		(layer "B.Cu")
		(net "PWM_OUT")
	)
	(segment
		(start 25.4508 -168.6306)
		(end 25.361646 -168.6306)
		(width 0.1397)
		(layer "B.Cu")
		(net "PWM_OUT")
	)
	(segment
		(start 25.361646 -168.6306)
		(end 23.583646 -170.4086)
		(width 0.1397)
		(layer "B.Cu")
		(net "PWM_OUT")
	)
	(segment
		(start 21.995638 -174.82693)
		(end 21.995638 -173.000162)
		(width 0.1397)
		(layer "B.Cu")
		(net "PWM_OUT")
	)
	(segment
		(start 24.99995 -212.21065)
		(end 24.99995 -221.26575)
		(width 0.1397)
		(layer "B.Cu")
		(net "PWM_OUT")
	)
	(segment
		(start 25.1206 -209.0166)
		(end 25.1206 -212.09)
		(width 0.1397)
		(layer "B.Cu")
		(net "PWM_OUT")
	)
	(segment
		(start 25.1206 -212.09)
		(end 24.99995 -212.21065)
		(width 0.1397)
		(layer "B.Cu")
		(net "PWM_OUT")
	)
	(segment
		(start 18.3896 -194.57035)
		(end 21.06295 -191.897)
		(width 0.1397)
		(layer "B.Cu")
		(net "PWM_OUT")
	)
	(segment
		(start 23.583646 -171.412154)
		(end 21.995638 -173.000162)
		(width 0.1397)
		(layer "B.Cu")
		(net "PWM_OUT")
	)
	(segment
		(start 21.3741 -174.7647)
		(end 21.844 -175.2346)
		(width 0.1397)
		(layer "F.Cu")
		(net "THERMHOT#")
	)
	(segment
		(start 21.3741 -174.3456)
		(end 21.3741 -174.7647)
		(width 0.1397)
		(layer "F.Cu")
		(net "THERMHOT#")
	)
	(segment
		(start 23.674324 -174.60341)
		(end 22.47519 -174.60341)
		(width 0.1397)
		(layer "F.Cu")
		(net "THERMHOT#")
	)
	(segment
		(start 22.47519 -174.60341)
		(end 21.844 -175.2346)
		(width 0.1397)
		(layer "F.Cu")
		(net "THERMHOT#")
	)
	(segment
		(start 21.3741 -174.3456)
		(end 21.3741 -173.4566)
		(width 0.1397)
		(layer "F.Cu")
		(net "THERMHOT#")
	)
	(segment
		(start 21.3741 -173.4566)
		(end 21.1963 -173.2788)
		(width 0.1397)
		(layer "F.Cu")
		(net "THERMHOT#")
	)
	(via
		(at 21.844 -175.2346)
		(size 0.7112)
		(drill 0.3556)
		(layers "F.Cu" "B.Cu")
		(net "THERMHOT#")
	)
	(segment
		(start 24.1554 -367.411)
		(end 24.520398 -367.775998)
		(width 0.508)
		(layer "F.Cu")
		(net "ADM1276_ISET")
	)
	(segment
		(start 25.3238 -368.4778)
		(end 25.654 -368.808)
		(width 0.381)
		(layer "F.Cu")
		(net "ADM1276_ISET")
	)
	(segment
		(start 25.2476 -368.4778)
		(end 25.3238 -368.4778)
		(width 0.508)
		(layer "F.Cu")
		(net "ADM1276_ISET")
	)
	(segment
		(start 24.0665 -365.506)
		(end 24.0665 -366.4712)
		(width 0.508)
		(layer "F.Cu")
		(net "ADM1276_ISET")
	)
	(segment
		(start 24.0665 -366.4712)
		(end 24.0665 -367.411)
		(width 0.508)
		(layer "F.Cu")
		(net "ADM1276_ISET")
	)
	(segment
		(start 24.545798 -367.775998)
		(end 25.2476 -368.4778)
		(width 0.508)
		(layer "F.Cu")
		(net "ADM1276_ISET")
	)
	(segment
		(start 24.0665 -367.411)
		(end 24.1554 -367.411)
		(width 0.508)
		(layer "F.Cu")
		(net "ADM1276_ISET")
	)
	(segment
		(start 24.520398 -367.775998)
		(end 24.545798 -367.775998)
		(width 0.508)
		(layer "F.Cu")
		(net "ADM1276_ISET")
	)
	(segment
		(start 25.654 -368.808)
		(end 27.2796 -368.808)
		(width 0.381)
		(layer "F.Cu")
		(net "ADM1276_ISET")
	)
	(via
		(at 25.3238 -368.4778)
		(size 0.7112)
		(drill 0.3556)
		(layers "F.Cu" "B.Cu")
		(net "ADM1276_ISET")
	)
	(segment
		(start 9.071864 -233.553)
		(end 14.8844 -233.553)
		(width 0.1397)
		(layer "F.Cu")
		(net "LED_DR_LED3")
	)
	(segment
		(start 39.059104 -241.928396)
		(end 39.878 -241.1095)
		(width 0.1397)
		(layer "F.Cu")
		(net "LED_DR_LED3")
	)
	(segment
		(start 38.7858 -241.940334)
		(end 38.797738 -241.928396)
		(width 0.1397)
		(layer "F.Cu")
		(net "LED_DR_LED3")
	)
	(segment
		(start 38.797738 -241.928396)
		(end 39.059104 -241.928396)
		(width 0.1397)
		(layer "F.Cu")
		(net "LED_DR_LED3")
	)
	(segment
		(start 14.8844 -233.553)
		(end 16.2814 -232.156)
		(width 0.1397)
		(layer "F.Cu")
		(net "LED_DR_LED3")
	)
	(segment
		(start 16.2814 -232.156)
		(end 16.2814 -231.8639)
		(width 0.1397)
		(layer "F.Cu")
		(net "LED_DR_LED3")
	)
	(segment
		(start 37.211 -228.473)
		(end 19.685 -228.473)
		(width 0.1397)
		(layer "F.Cu")
		(net "LED_DR_LED3")
	)
	(segment
		(start 16.2814 -231.8639)
		(end 16.2941 -231.8639)
		(width 0.1397)
		(layer "F.Cu")
		(net "LED_DR_LED3")
	)
	(segment
		(start 19.685 -228.473)
		(end 19.431 -228.727)
		(width 0.1397)
		(layer "F.Cu")
		(net "LED_DR_LED3")
	)
	(segment
		(start 16.2941 -231.8639)
		(end 19.431 -228.727)
		(width 0.1397)
		(layer "F.Cu")
		(net "LED_DR_LED3")
	)
	(segment
		(start 7.949946 -234.674918)
		(end 9.071864 -233.553)
		(width 0.1397)
		(layer "F.Cu")
		(net "LED_DR_LED3")
	)
	(segment
		(start 38.7858 -243.713)
		(end 38.7858 -241.940334)
		(width 0.1397)
		(layer "F.Cu")
		(net "LED_DR_LED3")
	)
	(segment
		(start 37.465 -228.727)
		(end 37.211 -228.473)
		(width 0.1397)
		(layer "F.Cu")
		(net "LED_DR_LED3")
	)
	(via
		(at 37.465 -228.727)
		(size 0.5588)
		(drill 0.3048)
		(layers "F.Cu" "B.Cu")
		(net "LED_DR_LED3")
	)
	(via
		(at 19.431 -228.727)
		(size 0.7112)
		(drill 0.3556)
		(layers "F.Cu" "B.Cu")
		(net "LED_DR_LED3")
	)
	(via
		(at 38.797738 -241.928396)
		(size 0.5588)
		(drill 0.3048)
		(layers "F.Cu" "B.Cu")
		(net "LED_DR_LED3")
	)
	(segment
		(start 37.49675 -240.06175)
		(end 38.862 -241.427)
		(width 0.1397)
		(layer "B.Cu")
		(net "LED_DR_LED3")
	)
	(segment
		(start 37.465 -228.727)
		(end 37.49675 -228.75875)
		(width 0.1397)
		(layer "B.Cu")
		(net "LED_DR_LED3")
	)
	(segment
		(start 38.862 -241.8588)
		(end 38.797738 -241.923062)
		(width 0.1397)
		(layer "B.Cu")
		(net "LED_DR_LED3")
	)
	(segment
		(start 37.49675 -228.75875)
		(end 37.49675 -240.06175)
		(width 0.1397)
		(layer "B.Cu")
		(net "LED_DR_LED3")
	)
	(segment
		(start 38.797738 -241.923062)
		(end 38.797738 -241.928396)
		(width 0.1397)
		(layer "B.Cu")
		(net "LED_DR_LED3")
	)
	(segment
		(start 38.862 -241.427)
		(end 38.862 -241.8588)
		(width 0.1397)
		(layer "B.Cu")
		(net "LED_DR_LED3")
	)
	(segment
		(start 34.1376 -369.4938)
		(end 34.1376 -369.3922)
		(width 0.381)
		(layer "F.Cu")
		(net "ADM1276_FLB")
	)
	(segment
		(start 35.6743 -370.4336)
		(end 35.0774 -370.4336)
		(width 0.381)
		(layer "F.Cu")
		(net "ADM1276_FLB")
	)
	(segment
		(start 35.6743 -371.4496)
		(end 35.6743 -370.4336)
		(width 0.381)
		(layer "F.Cu")
		(net "ADM1276_FLB")
	)
	(segment
		(start 32.1564 -368.808)
		(end 33.5788 -368.808)
		(width 0.381)
		(layer "F.Cu")
		(net "ADM1276_FLB")
	)
	(segment
		(start 33.5788 -368.808)
		(end 34.1376 -369.3668)
		(width 0.381)
		(layer "F.Cu")
		(net "ADM1276_FLB")
	)
	(segment
		(start 35.0774 -370.4336)
		(end 34.1376 -369.4938)
		(width 0.381)
		(layer "F.Cu")
		(net "ADM1276_FLB")
	)
	(segment
		(start 34.1376 -369.3668)
		(end 34.1376 -369.3922)
		(width 0.381)
		(layer "F.Cu")
		(net "ADM1276_FLB")
	)
	(via
		(at 34.1376 -369.3922)
		(size 0.7112)
		(drill 0.3556)
		(layers "F.Cu" "B.Cu")
		(net "ADM1276_FLB")
	)
	(segment
		(start 38.13556 -242.526566)
		(end 38.042088 -242.433094)
		(width 0.1397)
		(layer "F.Cu")
		(net "LED_DR_LED2")
	)
	(segment
		(start 38.042088 -242.346734)
		(end 38.042088 -242.294918)
		(width 0.1397)
		(layer "F.Cu")
		(net "LED_DR_LED2")
	)
	(segment
		(start 38.31082 -242.026186)
		(end 38.31082 -241.66068)
		(width 0.1397)
		(layer "F.Cu")
		(net "LED_DR_LED2")
	)
	(segment
		(start 29.7688 -257.8608)
		(end 24.384 -252.476)
		(width 0.1397)
		(layer "F.Cu")
		(net "LED_DR_LED2")
	)
	(segment
		(start 10.5283 -275.4122)
		(end 7.949946 -272.833846)
		(width 0.1397)
		(layer "F.Cu")
		(net "LED_DR_LED2")
	)
	(segment
		(start 38.31082 -241.66068)
		(end 38.862 -241.1095)
		(width 0.1397)
		(layer "F.Cu")
		(net "LED_DR_LED2")
	)
	(segment
		(start 10.5283 -278.6507)
		(end 10.5283 -278.384)
		(width 0.1397)
		(layer "F.Cu")
		(net "LED_DR_LED2")
	)
	(segment
		(start 9.823958 -279.355042)
		(end 10.5283 -278.6507)
		(width 0.1397)
		(layer "F.Cu")
		(net "LED_DR_LED2")
	)
	(segment
		(start 38.042088 -242.433094)
		(end 38.042088 -242.346734)
		(width 0.1397)
		(layer "F.Cu")
		(net "LED_DR_LED2")
	)
	(segment
		(start 10.5283 -278.384)
		(end 10.5283 -275.4122)
		(width 0.1397)
		(layer "F.Cu")
		(net "LED_DR_LED2")
	)
	(segment
		(start 32.3088 -257.8608)
		(end 29.7688 -257.8608)
		(width 0.1397)
		(layer "F.Cu")
		(net "LED_DR_LED2")
	)
	(segment
		(start 9.525 -279.355042)
		(end 9.823958 -279.355042)
		(width 0.1397)
		(layer "F.Cu")
		(net "LED_DR_LED2")
	)
	(segment
		(start 10.1854 -252.476)
		(end 9.5758 -251.8664)
		(width 0.1397)
		(layer "F.Cu")
		(net "LED_DR_LED2")
	)
	(segment
		(start 38.042088 -242.294918)
		(end 38.31082 -242.026186)
		(width 0.1397)
		(layer "F.Cu")
		(net "LED_DR_LED2")
	)
	(segment
		(start 38.13556 -243.713)
		(end 38.13556 -242.526566)
		(width 0.1397)
		(layer "F.Cu")
		(net "LED_DR_LED2")
	)
	(segment
		(start 7.949946 -272.833846)
		(end 7.949946 -270.405098)
		(width 0.1397)
		(layer "F.Cu")
		(net "LED_DR_LED2")
	)
	(segment
		(start 24.384 -252.476)
		(end 10.1854 -252.476)
		(width 0.1397)
		(layer "F.Cu")
		(net "LED_DR_LED2")
	)
	(via
		(at 9.525 -253.492)
		(size 0.7112)
		(drill 0.3556)
		(layers "F.Cu" "B.Cu")
		(net "LED_DR_LED2")
	)
	(via
		(at 32.3088 -257.8608)
		(size 0.5588)
		(drill 0.3048)
		(layers "F.Cu" "B.Cu")
		(net "LED_DR_LED2")
	)
	(via
		(at 9.525 -279.355042)
		(size 0.5588)
		(drill 0.3048)
		(layers "F.Cu" "B.Cu")
		(net "LED_DR_LED2")
	)
	(via
		(at 9.5758 -251.8664)
		(size 0.7112)
		(drill 0.4064)
		(layers "F.Cu" "B.Cu")
		(net "LED_DR_LED2")
	)
	(via
		(at 38.042088 -242.346734)
		(size 0.5588)
		(drill 0.3048)
		(layers "F.Cu" "B.Cu")
		(net "LED_DR_LED2")
	)
	(segment
		(start 9.525 -251.9172)
		(end 9.525 -253.492)
		(width 0.1397)
		(layer "B.Cu")
		(net "LED_DR_LED2")
	)
	(segment
		(start 37.338 -243.116608)
		(end 37.338 -250.8758)
		(width 0.1397)
		(layer "B.Cu")
		(net "LED_DR_LED2")
	)
	(segment
		(start 37.338 -250.8758)
		(end 32.385 -255.8288)
		(width 0.1397)
		(layer "B.Cu")
		(net "LED_DR_LED2")
	)
	(segment
		(start 32.385 -255.8288)
		(end 32.385 -257.7846)
		(width 0.1397)
		(layer "B.Cu")
		(net "LED_DR_LED2")
	)
	(segment
		(start 38.042088 -242.41252)
		(end 37.338 -243.116608)
		(width 0.1397)
		(layer "B.Cu")
		(net "LED_DR_LED2")
	)
	(segment
		(start 9.525 -253.492)
		(end 9.525 -279.355042)
		(width 0.1397)
		(layer "B.Cu")
		(net "LED_DR_LED2")
	)
	(segment
		(start 38.042088 -242.346734)
		(end 38.042088 -242.41252)
		(width 0.1397)
		(layer "B.Cu")
		(net "LED_DR_LED2")
	)
	(segment
		(start 32.385 -257.7846)
		(end 32.3088 -257.8608)
		(width 0.1397)
		(layer "B.Cu")
		(net "LED_DR_LED2")
	)
	(segment
		(start 9.5758 -251.8664)
		(end 9.525 -251.9172)
		(width 0.1397)
		(layer "B.Cu")
		(net "LED_DR_LED2")
	)
	(segment
		(start 29.972 -363.0168)
		(end 29.972 -361.7595)
		(width 0.1397)
		(layer "F.Cu")
		(net "ADM1276_GPIO2")
	)
	(segment
		(start 29.7434 -363.2454)
		(end 29.972 -363.0168)
		(width 0.1397)
		(layer "F.Cu")
		(net "ADM1276_GPIO2")
	)
	(segment
		(start 30.367986 -366.3696)
		(end 30.367986 -363.869986)
		(width 0.1397)
		(layer "F.Cu")
		(net "ADM1276_GPIO2")
	)
	(segment
		(start 30.367986 -363.869986)
		(end 29.7434 -363.2454)
		(width 0.1397)
		(layer "F.Cu")
		(net "ADM1276_GPIO2")
	)
	(segment
		(start 37.48532 -243.713)
		(end 37.48532 -242.34394)
		(width 0.1397)
		(layer "F.Cu")
		(net "LED_DR_LED1")
	)
	(segment
		(start 37.211 -241.7445)
		(end 37.846 -241.1095)
		(width 0.1397)
		(layer "F.Cu")
		(net "LED_DR_LED1")
	)
	(segment
		(start 9.652 -421.4241)
		(end 8.3566 -422.7195)
		(width 0.1397)
		(layer "F.Cu")
		(net "LED_DR_LED1")
	)
	(segment
		(start 5.1816 -422.7195)
		(end 4.8895 -422.4274)
		(width 0.1397)
		(layer "F.Cu")
		(net "LED_DR_LED1")
	)
	(segment
		(start 37.211 -242.06962)
		(end 37.211 -241.7445)
		(width 0.1397)
		(layer "F.Cu")
		(net "LED_DR_LED1")
	)
	(segment
		(start 9.652 -416.687)
		(end 9.652 -421.4241)
		(width 0.1397)
		(layer "F.Cu")
		(net "LED_DR_LED1")
	)
	(segment
		(start 7.949946 -414.005014)
		(end 7.949946 -414.984946)
		(width 0.1397)
		(layer "F.Cu")
		(net "LED_DR_LED1")
	)
	(segment
		(start 8.3566 -422.7195)
		(end 5.1816 -422.7195)
		(width 0.1397)
		(layer "F.Cu")
		(net "LED_DR_LED1")
	)
	(segment
		(start 7.949946 -414.984946)
		(end 9.652 -416.687)
		(width 0.1397)
		(layer "F.Cu")
		(net "LED_DR_LED1")
	)
	(segment
		(start 37.48532 -242.34394)
		(end 37.211 -242.06962)
		(width 0.1397)
		(layer "F.Cu")
		(net "LED_DR_LED1")
	)
	(via
		(at 4.8895 -422.4274)
		(size 0.7112)
		(drill 0.4064)
		(layers "F.Cu" "B.Cu")
		(net "LED_DR_LED1")
	)
	(via
		(at 37.211 -242.06962)
		(size 0.5588)
		(drill 0.3048)
		(layers "F.Cu" "B.Cu")
		(net "LED_DR_LED1")
	)
	(via
		(at 31.2166 -255.8796)
		(size 0.7112)
		(drill 0.3556)
		(layers "F.Cu" "B.Cu")
		(net "LED_DR_LED1")
	)
	(segment
		(start 35.84575 -241.87277)
		(end 35.84575 -250.78309)
		(width 0.1397)
		(layer "B.Cu")
		(net "LED_DR_LED1")
	)
	(segment
		(start 5.951474 -377.903486)
		(end 5.951474 -364.524798)
		(width 0.1397)
		(layer "B.Cu")
		(net "LED_DR_LED1")
	)
	(segment
		(start 36.735258 -241.593878)
		(end 36.124642 -241.593878)
		(width 0.1397)
		(layer "B.Cu")
		(net "LED_DR_LED1")
	)
	(segment
		(start 20.447 -288.671)
		(end 20.447 -285.75)
		(width 0.1397)
		(layer "B.Cu")
		(net "LED_DR_LED1")
	)
	(segment
		(start 37.211 -242.06962)
		(end 36.735258 -241.593878)
		(width 0.1397)
		(layer "B.Cu")
		(net "LED_DR_LED1")
	)
	(segment
		(start 5.951474 -364.524798)
		(end 4.977384 -363.550708)
		(width 0.1397)
		(layer "B.Cu")
		(net "LED_DR_LED1")
	)
	(segment
		(start 4.977384 -363.550708)
		(end 4.977384 -352.654616)
		(width 0.1397)
		(layer "B.Cu")
		(net "LED_DR_LED1")
	)
	(segment
		(start 36.124642 -241.593878)
		(end 35.84575 -241.87277)
		(width 0.1397)
		(layer "B.Cu")
		(net "LED_DR_LED1")
	)
	(segment
		(start 31.2166 -255.41224)
		(end 31.2166 -255.8796)
		(width 0.1397)
		(layer "B.Cu")
		(net "LED_DR_LED1")
	)
	(segment
		(start 31.2166 -274.9804)
		(end 31.2166 -255.8796)
		(width 0.1397)
		(layer "B.Cu")
		(net "LED_DR_LED1")
	)
	(segment
		(start 18.889218 -293.158418)
		(end 18.889218 -290.228782)
		(width 0.1397)
		(layer "B.Cu")
		(net "LED_DR_LED1")
	)
	(segment
		(start 4.8895 -416.92195)
		(end 4.088384 -416.120834)
		(width 0.1397)
		(layer "B.Cu")
		(net "LED_DR_LED1")
	)
	(segment
		(start 4.088384 -416.120834)
		(end 4.088384 -379.766576)
		(width 0.1397)
		(layer "B.Cu")
		(net "LED_DR_LED1")
	)
	(segment
		(start 19.618452 -293.887652)
		(end 18.889218 -293.158418)
		(width 0.1397)
		(layer "B.Cu")
		(net "LED_DR_LED1")
	)
	(segment
		(start 4.8895 -422.4274)
		(end 4.8895 -416.92195)
		(width 0.1397)
		(layer "B.Cu")
		(net "LED_DR_LED1")
	)
	(segment
		(start 35.84575 -250.78309)
		(end 31.2166 -255.41224)
		(width 0.1397)
		(layer "B.Cu")
		(net "LED_DR_LED1")
	)
	(segment
		(start 4.088384 -379.766576)
		(end 5.951474 -377.903486)
		(width 0.1397)
		(layer "B.Cu")
		(net "LED_DR_LED1")
	)
	(segment
		(start 20.447 -285.75)
		(end 31.2166 -274.9804)
		(width 0.1397)
		(layer "B.Cu")
		(net "LED_DR_LED1")
	)
	(segment
		(start 19.618452 -338.013548)
		(end 19.618452 -293.887652)
		(width 0.1397)
		(layer "B.Cu")
		(net "LED_DR_LED1")
	)
	(segment
		(start 18.889218 -290.228782)
		(end 20.447 -288.671)
		(width 0.1397)
		(layer "B.Cu")
		(net "LED_DR_LED1")
	)
	(segment
		(start 4.977384 -352.654616)
		(end 19.618452 -338.013548)
		(width 0.1397)
		(layer "B.Cu")
		(net "LED_DR_LED1")
	)
	(segment
		(start 36.322 -242.070128)
		(end 36.322 -242.19535)
		(width 0.1397)
		(layer "F.Cu")
		(net "LED_DR_LED0")
	)
	(segment
		(start 4.2418 -436.085742)
		(end 4.2418 -434.213)
		(width 0.1397)
		(layer "F.Cu")
		(net "LED_DR_LED0")
	)
	(segment
		(start 36.322 -241.6175)
		(end 36.83 -241.1095)
		(width 0.1397)
		(layer "F.Cu")
		(net "LED_DR_LED0")
	)
	(segment
		(start 36.322 -242.070128)
		(end 36.322 -241.6175)
		(width 0.1397)
		(layer "F.Cu")
		(net "LED_DR_LED0")
	)
	(segment
		(start 4.6609 -436.504842)
		(end 4.2418 -436.085742)
		(width 0.1397)
		(layer "F.Cu")
		(net "LED_DR_LED0")
	)
	(segment
		(start 4.2418 -434.213)
		(end 4.8768 -433.578)
		(width 0.1397)
		(layer "F.Cu")
		(net "LED_DR_LED0")
	)
	(segment
		(start 36.322 -242.19535)
		(end 36.83508 -242.70843)
		(width 0.1397)
		(layer "F.Cu")
		(net "LED_DR_LED0")
	)
	(segment
		(start 4.6609 -443.151006)
		(end 7.949946 -446.440052)
		(width 0.1397)
		(layer "F.Cu")
		(net "LED_DR_LED0")
	)
	(segment
		(start 4.6609 -437.0578)
		(end 4.6609 -443.151006)
		(width 0.1397)
		(layer "F.Cu")
		(net "LED_DR_LED0")
	)
	(segment
		(start 36.83508 -242.70843)
		(end 36.83508 -243.713)
		(width 0.1397)
		(layer "F.Cu")
		(net "LED_DR_LED0")
	)
	(segment
		(start 4.6609 -437.0578)
		(end 4.6609 -436.504842)
		(width 0.1397)
		(layer "F.Cu")
		(net "LED_DR_LED0")
	)
	(via
		(at 36.322 -242.070128)
		(size 0.5588)
		(drill 0.3048)
		(layers "F.Cu" "B.Cu")
		(net "LED_DR_LED0")
	)
	(via
		(at 4.8768 -433.578)
		(size 0.5588)
		(drill 0.3048)
		(layers "F.Cu" "B.Cu")
		(net "LED_DR_LED0")
	)
	(segment
		(start 20.062952 -293.697152)
		(end 19.333718 -292.967918)
		(width 0.1397)
		(layer "B.Cu")
		(net "LED_DR_LED0")
	)
	(segment
		(start 5.421884 -352.845116)
		(end 20.062952 -338.204048)
		(width 0.1397)
		(layer "B.Cu")
		(net "LED_DR_LED0")
	)
	(segment
		(start 19.333718 -290.566602)
		(end 20.955 -288.94532)
		(width 0.1397)
		(layer "B.Cu")
		(net "LED_DR_LED0")
	)
	(segment
		(start 4.532884 -379.950726)
		(end 6.395974 -378.087636)
		(width 0.1397)
		(layer "B.Cu")
		(net "LED_DR_LED0")
	)
	(segment
		(start 19.333718 -292.967918)
		(end 19.333718 -290.566602)
		(width 0.1397)
		(layer "B.Cu")
		(net "LED_DR_LED0")
	)
	(segment
		(start 5.44195 -416.84575)
		(end 4.532884 -415.936684)
		(width 0.1397)
		(layer "B.Cu")
		(net "LED_DR_LED0")
	)
	(segment
		(start 4.532884 -415.936684)
		(end 4.532884 -379.950726)
		(width 0.1397)
		(layer "B.Cu")
		(net "LED_DR_LED0")
	)
	(segment
		(start 31.8262 -255.7018)
		(end 36.322 -251.206)
		(width 0.1397)
		(layer "B.Cu")
		(net "LED_DR_LED0")
	)
	(segment
		(start 20.955 -285.877)
		(end 31.8262 -275.0058)
		(width 0.1397)
		(layer "B.Cu")
		(net "LED_DR_LED0")
	)
	(segment
		(start 31.8262 -275.0058)
		(end 31.8262 -255.7018)
		(width 0.1397)
		(layer "B.Cu")
		(net "LED_DR_LED0")
	)
	(segment
		(start 20.955 -288.94532)
		(end 20.955 -285.877)
		(width 0.1397)
		(layer "B.Cu")
		(net "LED_DR_LED0")
	)
	(segment
		(start 6.395974 -364.307374)
		(end 5.421884 -363.333284)
		(width 0.1397)
		(layer "B.Cu")
		(net "LED_DR_LED0")
	)
	(segment
		(start 36.322 -251.206)
		(end 36.322 -242.070128)
		(width 0.1397)
		(layer "B.Cu")
		(net "LED_DR_LED0")
	)
	(segment
		(start 4.8768 -433.578)
		(end 5.44195 -433.01285)
		(width 0.1397)
		(layer "B.Cu")
		(net "LED_DR_LED0")
	)
	(segment
		(start 20.062952 -338.204048)
		(end 20.062952 -293.697152)
		(width 0.1397)
		(layer "B.Cu")
		(net "LED_DR_LED0")
	)
	(segment
		(start 6.395974 -378.087636)
		(end 6.395974 -364.307374)
		(width 0.1397)
		(layer "B.Cu")
		(net "LED_DR_LED0")
	)
	(segment
		(start 5.44195 -433.01285)
		(end 5.44195 -416.84575)
		(width 0.1397)
		(layer "B.Cu")
		(net "LED_DR_LED0")
	)
	(segment
		(start 5.421884 -363.333284)
		(end 5.421884 -352.845116)
		(width 0.1397)
		(layer "B.Cu")
		(net "LED_DR_LED0")
	)
	(segment
		(start 39.43604 -247.58904)
		(end 39.37 -247.523)
		(width 0.1397)
		(layer "F.Cu")
		(net "LED_DR_LED4")
	)
	(segment
		(start 18.415 -227.965)
		(end 15.8242 -225.3742)
		(width 0.1397)
		(layer "F.Cu")
		(net "LED_DR_LED4")
	)
	(segment
		(start 7.695438 -78.613)
		(end 5.21081 -78.613)
		(width 0.1397)
		(layer "F.Cu")
		(net "LED_DR_LED4")
	)
	(segment
		(start 14.6812 -225.3742)
		(end 14.224 -224.917)
		(width 0.1397)
		(layer "F.Cu")
		(net "LED_DR_LED4")
	)
	(segment
		(start 39.43604 -249.3518)
		(end 39.43604 -250.51004)
		(width 0.1397)
		(layer "F.Cu")
		(net "LED_DR_LED4")
	)
	(segment
		(start 39.43604 -250.51004)
		(end 41.4655 -252.5395)
		(width 0.1397)
		(layer "F.Cu")
		(net "LED_DR_LED4")
	)
	(segment
		(start 11.049 -81.966562)
		(end 7.695438 -78.613)
		(width 0.1397)
		(layer "F.Cu")
		(net "LED_DR_LED4")
	)
	(segment
		(start 40.0812 -228.092)
		(end 39.9542 -227.965)
		(width 0.1397)
		(layer "F.Cu")
		(net "LED_DR_LED4")
	)
	(segment
		(start 8.359902 -91.075002)
		(end 11.049 -88.385904)
		(width 0.1397)
		(layer "F.Cu")
		(net "LED_DR_LED4")
	)
	(segment
		(start 39.9542 -227.965)
		(end 18.415 -227.965)
		(width 0.1397)
		(layer "F.Cu")
		(net "LED_DR_LED4")
	)
	(segment
		(start 5.21081 -78.613)
		(end 4.897882 -78.925928)
		(width 0.1397)
		(layer "F.Cu")
		(net "LED_DR_LED4")
	)
	(segment
		(start 41.4655 -252.5395)
		(end 41.529 -252.5395)
		(width 0.1397)
		(layer "F.Cu")
		(net "LED_DR_LED4")
	)
	(segment
		(start 15.8242 -225.3742)
		(end 14.6812 -225.3742)
		(width 0.1397)
		(layer "F.Cu")
		(net "LED_DR_LED4")
	)
	(segment
		(start 39.43604 -249.3518)
		(end 39.43604 -247.58904)
		(width 0.1397)
		(layer "F.Cu")
		(net "LED_DR_LED4")
	)
	(segment
		(start 11.049 -88.385904)
		(end 11.049 -81.966562)
		(width 0.1397)
		(layer "F.Cu")
		(net "LED_DR_LED4")
	)
	(segment
		(start 7.949946 -91.075002)
		(end 8.359902 -91.075002)
		(width 0.1397)
		(layer "F.Cu")
		(net "LED_DR_LED4")
	)
	(via
		(at 14.224 -224.917)
		(size 0.5588)
		(drill 0.3048)
		(layers "F.Cu" "B.Cu")
		(net "LED_DR_LED4")
	)
	(via
		(at 39.37 -247.523)
		(size 0.5588)
		(drill 0.3048)
		(layers "F.Cu" "B.Cu")
		(net "LED_DR_LED4")
	)
	(via
		(at 40.0812 -228.092)
		(size 0.5588)
		(drill 0.3048)
		(layers "F.Cu" "B.Cu")
		(net "LED_DR_LED4")
	)
	(via
		(at 14.683486 -216.535)
		(size 0.7112)
		(drill 0.3556)
		(layers "F.Cu" "B.Cu")
		(net "LED_DR_LED4")
	)
	(segment
		(start 5.392166 -117.685566)
		(end 8.3312 -120.6246)
		(width 0.1397)
		(layer "B.Cu")
		(net "LED_DR_LED4")
	)
	(segment
		(start 8.24865 -112.40135)
		(end 5.392166 -115.257834)
		(width 0.1397)
		(layer "B.Cu")
		(net "LED_DR_LED4")
	)
	(segment
		(start 8.3312 -120.6246)
		(end 8.3312 -133.6294)
		(width 0.1397)
		(layer "B.Cu")
		(net "LED_DR_LED4")
	)
	(segment
		(start 39.37 -247.523)
		(end 39.37 -245.5926)
		(width 0.1397)
		(layer "B.Cu")
		(net "LED_DR_LED4")
	)
	(segment
		(start 7.949946 -91.075002)
		(end 8.24865 -91.373706)
		(width 0.1397)
		(layer "B.Cu")
		(net "LED_DR_LED4")
	)
	(segment
		(start 11.43 -136.7282)
		(end 11.43 -146.431)
		(width 0.1397)
		(layer "B.Cu")
		(net "LED_DR_LED4")
	)
	(segment
		(start 5.392166 -115.257834)
		(end 5.392166 -117.685566)
		(width 0.1397)
		(layer "B.Cu")
		(net "LED_DR_LED4")
	)
	(segment
		(start 14.224 -224.141792)
		(end 14.683486 -223.682306)
		(width 0.1397)
		(layer "B.Cu")
		(net "LED_DR_LED4")
	)
	(segment
		(start 16.44015 -214.19185)
		(end 14.683486 -215.948514)
		(width 0.1397)
		(layer "B.Cu")
		(net "LED_DR_LED4")
	)
	(segment
		(start 14.224 -224.917)
		(end 14.224 -224.141792)
		(width 0.1397)
		(layer "B.Cu")
		(net "LED_DR_LED4")
	)
	(segment
		(start 18.23085 -168.635426)
		(end 17.653 -169.213276)
		(width 0.1397)
		(layer "B.Cu")
		(net "LED_DR_LED4")
	)
	(segment
		(start 18.23085 -156.91485)
		(end 18.23085 -168.635426)
		(width 0.1397)
		(layer "B.Cu")
		(net "LED_DR_LED4")
	)
	(segment
		(start 16.891 -155.575)
		(end 18.23085 -156.91485)
		(width 0.1397)
		(layer "B.Cu")
		(net "LED_DR_LED4")
	)
	(segment
		(start 8.3312 -133.6294)
		(end 11.43 -136.7282)
		(width 0.1397)
		(layer "B.Cu")
		(net "LED_DR_LED4")
	)
	(segment
		(start 16.44015 -173.437296)
		(end 16.44015 -214.19185)
		(width 0.1397)
		(layer "B.Cu")
		(net "LED_DR_LED4")
	)
	(segment
		(start 40.259 -244.7036)
		(end 40.259 -228.2698)
		(width 0.1397)
		(layer "B.Cu")
		(net "LED_DR_LED4")
	)
	(segment
		(start 14.683486 -223.682306)
		(end 14.683486 -216.535)
		(width 0.1397)
		(layer "B.Cu")
		(net "LED_DR_LED4")
	)
	(segment
		(start 39.37 -245.5926)
		(end 40.259 -244.7036)
		(width 0.1397)
		(layer "B.Cu")
		(net "LED_DR_LED4")
	)
	(segment
		(start 16.891 -151.892)
		(end 16.891 -155.575)
		(width 0.1397)
		(layer "B.Cu")
		(net "LED_DR_LED4")
	)
	(segment
		(start 8.24865 -91.373706)
		(end 8.24865 -112.40135)
		(width 0.1397)
		(layer "B.Cu")
		(net "LED_DR_LED4")
	)
	(segment
		(start 17.653 -169.213276)
		(end 17.653 -172.224446)
		(width 0.1397)
		(layer "B.Cu")
		(net "LED_DR_LED4")
	)
	(segment
		(start 40.259 -228.2698)
		(end 40.0812 -228.092)
		(width 0.1397)
		(layer "B.Cu")
		(net "LED_DR_LED4")
	)
	(segment
		(start 14.683486 -215.948514)
		(end 14.683486 -216.535)
		(width 0.1397)
		(layer "B.Cu")
		(net "LED_DR_LED4")
	)
	(segment
		(start 11.43 -146.431)
		(end 16.891 -151.892)
		(width 0.1397)
		(layer "B.Cu")
		(net "LED_DR_LED4")
	)
	(segment
		(start 17.653 -172.224446)
		(end 16.44015 -173.437296)
		(width 0.1397)
		(layer "B.Cu")
		(net "LED_DR_LED4")
	)
	(segment
		(start 10.521696 -67.06235)
		(end 11.3538 -66.230246)
		(width 0.1397)
		(layer "F.Cu")
		(net "LED_DR_LED5")
	)
	(segment
		(start 13.716 -69.7738)
		(end 12.192 -68.2498)
		(width 0.1397)
		(layer "F.Cu")
		(net "LED_DR_LED5")
	)
	(segment
		(start 13.716 -70.0024)
		(end 13.716 -69.7738)
		(width 0.1397)
		(layer "F.Cu")
		(net "LED_DR_LED5")
	)
	(segment
		(start 9.226296 -67.06235)
		(end 10.521696 -67.06235)
		(width 0.1397)
		(layer "F.Cu")
		(net "LED_DR_LED5")
	)
	(segment
		(start 38.7858 -248.5898)
		(end 38.227 -248.031)
		(width 0.1397)
		(layer "F.Cu")
		(net "LED_DR_LED5")
	)
	(segment
		(start 12.192 -68.2498)
		(end 10.31621 -68.2498)
		(width 0.1397)
		(layer "F.Cu")
		(net "LED_DR_LED5")
	)
	(segment
		(start 11.3538 -66.230246)
		(end 11.3538 -62.043818)
		(width 0.1397)
		(layer "F.Cu")
		(net "LED_DR_LED5")
	)
	(segment
		(start 38.7858 -249.3518)
		(end 38.7858 -248.5898)
		(width 0.1397)
		(layer "F.Cu")
		(net "LED_DR_LED5")
	)
	(segment
		(start 38.7858 -249.3518)
		(end 38.7858 -250.8123)
		(width 0.1397)
		(layer "F.Cu")
		(net "LED_DR_LED5")
	)
	(segment
		(start 11.3538 -62.043818)
		(end 7.949946 -58.639964)
		(width 0.1397)
		(layer "F.Cu")
		(net "LED_DR_LED5")
	)
	(segment
		(start 10.31621 -68.2498)
		(end 9.177528 -67.111118)
		(width 0.1397)
		(layer "F.Cu")
		(net "LED_DR_LED5")
	)
	(segment
		(start 38.7858 -250.8123)
		(end 40.513 -252.5395)
		(width 0.1397)
		(layer "F.Cu")
		(net "LED_DR_LED5")
	)
	(segment
		(start 9.177528 -67.111118)
		(end 9.226296 -67.06235)
		(width 0.1397)
		(layer "F.Cu")
		(net "LED_DR_LED5")
	)
	(via
		(at 32.6644 -170.053)
		(size 0.7112)
		(drill 0.3556)
		(layers "F.Cu" "B.Cu")
		(net "LED_DR_LED5")
	)
	(via
		(at 13.716 -70.0024)
		(size 0.5588)
		(drill 0.3048)
		(layers "F.Cu" "B.Cu")
		(net "LED_DR_LED5")
	)
	(via
		(at 38.227 -248.031)
		(size 0.5588)
		(drill 0.3048)
		(layers "F.Cu" "B.Cu")
		(net "LED_DR_LED5")
	)
	(segment
		(start 22.46757 -151.942038)
		(end 23.08225 -151.327358)
		(width 0.1397)
		(layer "B.Cu")
		(net "LED_DR_LED5")
	)
	(segment
		(start 33.92805 -173.45533)
		(end 33.92805 -211.09305)
		(width 0.1397)
		(layer "B.Cu")
		(net "LED_DR_LED5")
	)
	(segment
		(start 12.3571 -93.44025)
		(end 12.8143 -92.98305)
		(width 0.1397)
		(layer "B.Cu")
		(net "LED_DR_LED5")
	)
	(segment
		(start 15.9004 -124.333)
		(end 13.6398 -122.0724)
		(width 0.1397)
		(layer "B.Cu")
		(net "LED_DR_LED5")
	)
	(segment
		(start 12.3571 -110.5535)
		(end 12.3571 -93.44025)
		(width 0.1397)
		(layer "B.Cu")
		(net "LED_DR_LED5")
	)
	(segment
		(start 32.6644 -168.5036)
		(end 33.81375 -167.35425)
		(width 0.1397)
		(layer "B.Cu")
		(net "LED_DR_LED5")
	)
	(segment
		(start 13.9192 -70.2056)
		(end 13.716 -70.0024)
		(width 0.1397)
		(layer "B.Cu")
		(net "LED_DR_LED5")
	)
	(segment
		(start 37.94125 -239.376458)
		(end 39.3065 -240.741708)
		(width 0.1397)
		(layer "B.Cu")
		(net "LED_DR_LED5")
	)
	(segment
		(start 13.6398 -122.0724)
		(end 13.6398 -111.8362)
		(width 0.1397)
		(layer "B.Cu")
		(net "LED_DR_LED5")
	)
	(segment
		(start 39.3065 -240.741708)
		(end 39.3065 -242.93195)
		(width 0.1397)
		(layer "B.Cu")
		(net "LED_DR_LED5")
	)
	(segment
		(start 33.81375 -167.35425)
		(end 33.81375 -164.908992)
		(width 0.1397)
		(layer "B.Cu")
		(net "LED_DR_LED5")
	)
	(segment
		(start 12.8143 -92.98305)
		(end 12.8143 -73.7235)
		(width 0.1397)
		(layer "B.Cu")
		(net "LED_DR_LED5")
	)
	(segment
		(start 39.3065 -242.93195)
		(end 38.227 -244.01145)
		(width 0.1397)
		(layer "B.Cu")
		(net "LED_DR_LED5")
	)
	(segment
		(start 33.92805 -211.09305)
		(end 37.94125 -215.10625)
		(width 0.1397)
		(layer "B.Cu")
		(net "LED_DR_LED5")
	)
	(segment
		(start 22.46757 -153.562812)
		(end 22.46757 -151.942038)
		(width 0.1397)
		(layer "B.Cu")
		(net "LED_DR_LED5")
	)
	(segment
		(start 12.8143 -73.7235)
		(end 13.9192 -72.6186)
		(width 0.1397)
		(layer "B.Cu")
		(net "LED_DR_LED5")
	)
	(segment
		(start 13.9192 -72.6186)
		(end 13.9192 -70.2056)
		(width 0.1397)
		(layer "B.Cu")
		(net "LED_DR_LED5")
	)
	(segment
		(start 23.08225 -151.327358)
		(end 23.08225 -147.59305)
		(width 0.1397)
		(layer "B.Cu")
		(net "LED_DR_LED5")
	)
	(segment
		(start 13.6398 -111.8362)
		(end 12.3571 -110.5535)
		(width 0.1397)
		(layer "B.Cu")
		(net "LED_DR_LED5")
	)
	(segment
		(start 37.94125 -215.10625)
		(end 37.94125 -239.376458)
		(width 0.1397)
		(layer "B.Cu")
		(net "LED_DR_LED5")
	)
	(segment
		(start 32.6644 -170.053)
		(end 32.6644 -168.5036)
		(width 0.1397)
		(layer "B.Cu")
		(net "LED_DR_LED5")
	)
	(segment
		(start 22.098 -143.9672)
		(end 15.9004 -137.7696)
		(width 0.1397)
		(layer "B.Cu")
		(net "LED_DR_LED5")
	)
	(segment
		(start 38.227 -244.01145)
		(end 38.227 -248.031)
		(width 0.1397)
		(layer "B.Cu")
		(net "LED_DR_LED5")
	)
	(segment
		(start 15.9004 -137.7696)
		(end 15.9004 -124.333)
		(width 0.1397)
		(layer "B.Cu")
		(net "LED_DR_LED5")
	)
	(segment
		(start 33.81375 -164.908992)
		(end 22.46757 -153.562812)
		(width 0.1397)
		(layer "B.Cu")
		(net "LED_DR_LED5")
	)
	(segment
		(start 32.6644 -170.053)
		(end 32.6644 -172.19168)
		(width 0.1397)
		(layer "B.Cu")
		(net "LED_DR_LED5")
	)
	(segment
		(start 23.08225 -147.59305)
		(end 22.098 -146.6088)
		(width 0.1397)
		(layer "B.Cu")
		(net "LED_DR_LED5")
	)
	(segment
		(start 22.098 -146.6088)
		(end 22.098 -143.9672)
		(width 0.1397)
		(layer "B.Cu")
		(net "LED_DR_LED5")
	)
	(segment
		(start 32.6644 -172.19168)
		(end 33.92805 -173.45533)
		(width 0.1397)
		(layer "B.Cu")
		(net "LED_DR_LED5")
	)
	(segment
		(start 24.7396 -369.697)
		(end 24.765 -369.7224)
		(width 0.508)
		(layer "F.Cu")
		(net "ADM1276_VCAP")
	)
	(segment
		(start 24.765 -369.7224)
		(end 25.3492 -369.7224)
		(width 0.508)
		(layer "F.Cu")
		(net "ADM1276_VCAP")
	)
	(segment
		(start 22.606 -362.2675)
		(end 23.241 -361.6325)
		(width 0.508)
		(layer "F.Cu")
		(net "ADM1276_VCAP")
	)
	(segment
		(start 24.13 -369.697)
		(end 24.7396 -369.697)
		(width 0.508)
		(layer "F.Cu")
		(net "ADM1276_VCAP")
	)
	(segment
		(start 24.0665 -368.554)
		(end 24.13 -368.6175)
		(width 0.508)
		(layer "F.Cu")
		(net "ADM1276_VCAP")
	)
	(segment
		(start 24.13 -368.6175)
		(end 24.13 -369.697)
		(width 0.508)
		(layer "F.Cu")
		(net "ADM1276_VCAP")
	)
	(segment
		(start 23.1775 -365.506)
		(end 22.4028 -365.506)
		(width 0.508)
		(layer "F.Cu")
		(net "ADM1276_VCAP")
	)
	(segment
		(start 25.613614 -369.457986)
		(end 27.2796 -369.457986)
		(width 0.381)
		(layer "F.Cu")
		(net "ADM1276_VCAP")
	)
	(segment
		(start 25.3492 -369.7224)
		(end 25.613614 -369.457986)
		(width 0.381)
		(layer "F.Cu")
		(net "ADM1276_VCAP")
	)
	(segment
		(start 22.4028 -365.506)
		(end 22.1488 -365.76)
		(width 0.508)
		(layer "F.Cu")
		(net "ADM1276_VCAP")
	)
	(segment
		(start 22.606 -362.755434)
		(end 22.606 -362.2675)
		(width 0.508)
		(layer "F.Cu")
		(net "ADM1276_VCAP")
	)
	(via
		(at 22.606 -362.755434)
		(size 0.5588)
		(drill 0.3048)
		(layers "F.Cu" "B.Cu")
		(net "ADM1276_VCAP")
	)
	(via
		(at 25.3492 -369.7224)
		(size 0.7112)
		(drill 0.4064)
		(layers "F.Cu" "B.Cu")
		(net "ADM1276_VCAP")
	)
	(via
		(at 22.1488 -365.76)
		(size 0.7112)
		(drill 0.4064)
		(layers "F.Cu" "B.Cu")
		(net "ADM1276_VCAP")
	)
	(via
		(at 24.348186 -367.883186)
		(size 0.7112)
		(drill 0.3556)
		(layers "F.Cu" "B.Cu")
		(net "ADM1276_VCAP")
	)
	(segment
		(start 25.3492 -369.7224)
		(end 25.3492 -368.8842)
		(width 0.508)
		(layer "B.Cu")
		(net "ADM1276_VCAP")
	)
	(segment
		(start 22.1488 -365.76)
		(end 22.3266 -365.76)
		(width 0.508)
		(layer "B.Cu")
		(net "ADM1276_VCAP")
	)
	(segment
		(start 23.2156 -366.8268)
		(end 23.2918 -366.8268)
		(width 0.508)
		(layer "B.Cu")
		(net "ADM1276_VCAP")
	)
	(segment
		(start 23.1902 -364.8964)
		(end 23.1902 -363.2962)
		(width 0.508)
		(layer "B.Cu")
		(net "ADM1276_VCAP")
	)
	(segment
		(start 22.1488 -365.76)
		(end 23.2156 -366.8268)
		(width 0.508)
		(layer "B.Cu")
		(net "ADM1276_VCAP")
	)
	(segment
		(start 22.748494 -362.86948)
		(end 22.634448 -362.755434)
		(width 0.508)
		(layer "B.Cu")
		(net "ADM1276_VCAP")
	)
	(segment
		(start 25.3492 -368.8842)
		(end 24.348186 -367.883186)
		(width 0.508)
		(layer "B.Cu")
		(net "ADM1276_VCAP")
	)
	(segment
		(start 22.634448 -362.755434)
		(end 22.606 -362.755434)
		(width 0.508)
		(layer "B.Cu")
		(net "ADM1276_VCAP")
	)
	(segment
		(start 22.76348 -362.86948)
		(end 22.748494 -362.86948)
		(width 0.508)
		(layer "B.Cu")
		(net "ADM1276_VCAP")
	)
	(segment
		(start 23.2918 -366.8268)
		(end 24.348186 -367.883186)
		(width 0.508)
		(layer "B.Cu")
		(net "ADM1276_VCAP")
	)
	(segment
		(start 22.3266 -365.76)
		(end 23.1902 -364.8964)
		(width 0.508)
		(layer "B.Cu")
		(net "ADM1276_VCAP")
	)
	(segment
		(start 23.1902 -363.2962)
		(end 22.76348 -362.86948)
		(width 0.508)
		(layer "B.Cu")
		(net "ADM1276_VCAP")
	)
	(segment
		(start 37.2872 -369.1382)
		(end 36.4871 -369.1382)
		(width 0.508)
		(layer "F.Cu")
		(net "P12V_AUX")
	)
	(segment
		(start 38.735 -369.824)
		(end 38.354 -369.443)
		(width 0.508)
		(layer "F.Cu")
		(net "P12V_AUX")
	)
	(segment
		(start 22.047454 -378.917454)
		(end 21.59 -378.46)
		(width 0.508)
		(layer "F.Cu")
		(net "P12V_AUX")
	)
	(segment
		(start 27.305 -378.5235)
		(end 26.911046 -378.917454)
		(width 0.508)
		(layer "F.Cu")
		(net "P12V_AUX")
	)
	(segment
		(start 38.354 -369.443)
		(end 37.592 -369.443)
		(width 0.508)
		(layer "F.Cu")
		(net "P12V_AUX")
	)
	(segment
		(start 21.59 -378.46)
		(end 21.3995 -378.2695)
		(width 0.508)
		(layer "F.Cu")
		(net "P12V_AUX")
	)
	(segment
		(start 38.391084 -359.1814)
		(end 38.619684 -359.41)
		(width 0.508)
		(layer "F.Cu")
		(net "P12V_AUX")
	)
	(segment
		(start 31.7246 -185.0136)
		(end 33.9725 -185.0136)
		(width 0.508)
		(layer "F.Cu")
		(net "P12V_AUX")
	)
	(segment
		(start 45.1485 -158.810452)
		(end 44.397168 -159.561784)
		(width 0.508)
		(layer "F.Cu")
		(net "P12V_AUX")
	)
	(segment
		(start 24.500078 -443.95009)
		(end 24.500078 -449.068698)
		(width 0.635)
		(layer "F.Cu")
		(net "P12V_AUX")
	)
	(segment
		(start 38.6207 -361.5436)
		(end 38.6207 -362.5469)
		(width 0.508)
		(layer "F.Cu")
		(net "P12V_AUX")
	)
	(segment
		(start 34.3916 -186.989212)
		(end 34.3916 -185.4327)
		(width 0.508)
		(layer "F.Cu")
		(net "P12V_AUX")
	)
	(segment
		(start 44.397168 -159.561784)
		(end 44.245784 -159.561784)
		(width 0.508)
		(layer "F.Cu")
		(net "P12V_AUX")
	)
	(segment
		(start 42.418 -372.1862)
		(end 42.1132 -372.491)
		(width 0.508)
		(layer "F.Cu")
		(net "P12V_AUX")
	)
	(segment
		(start 35.7886 -359.1814)
		(end 38.391084 -359.1814)
		(width 0.508)
		(layer "F.Cu")
		(net "P12V_AUX")
	)
	(segment
		(start 35.5346 -359.4354)
		(end 35.7886 -359.1814)
		(width 0.508)
		(layer "F.Cu")
		(net "P12V_AUX")
	)
	(segment
		(start 42.1132 -372.491)
		(end 40.259 -372.491)
		(width 0.508)
		(layer "F.Cu")
		(net "P12V_AUX")
	)
	(segment
		(start 40.2844 -191.1604)
		(end 38.562788 -191.1604)
		(width 0.508)
		(layer "F.Cu")
		(net "P12V_AUX")
	)
	(segment
		(start 21.3995 -378.2695)
		(end 21.3995 -376.936)
		(width 0.508)
		(layer "F.Cu")
		(net "P12V_AUX")
	)
	(segment
		(start 38.619684 -360.4768)
		(end 38.619684 -359.41)
		(width 0.508)
		(layer "F.Cu")
		(net "P12V_AUX")
	)
	(segment
		(start 27.559 -378.7775)
		(end 27.305 -378.5235)
		(width 0.508)
		(layer "F.Cu")
		(net "P12V_AUX")
	)
	(segment
		(start 24.500078 -443.95009)
		(end 29.618686 -443.95009)
		(width 0.635)
		(layer "F.Cu")
		(net "P12V_AUX")
	)
	(segment
		(start 37.592 -369.443)
		(end 37.2872 -369.1382)
		(width 0.508)
		(layer "F.Cu")
		(net "P12V_AUX")
	)
	(segment
		(start 38.6207 -362.5469)
		(end 38.692074 -362.618274)
		(width 0.508)
		(layer "F.Cu")
		(net "P12V_AUX")
	)
	(segment
		(start 45.1485 -158.5722)
		(end 45.1485 -158.810452)
		(width 0.508)
		(layer "F.Cu")
		(net "P12V_AUX")
	)
	(segment
		(start 26.911046 -378.917454)
		(end 22.047454 -378.917454)
		(width 0.508)
		(layer "F.Cu")
		(net "P12V_AUX")
	)
	(segment
		(start 19.38147 -463.049874)
		(end 24.500078 -463.049874)
		(width 0.635)
		(layer "F.Cu")
		(net "P12V_AUX")
	)
	(segment
		(start 24.500078 -463.049874)
		(end 29.618686 -463.049874)
		(width 0.635)
		(layer "F.Cu")
		(net "P12V_AUX")
	)
	(segment
		(start 38.619684 -361.542584)
		(end 38.6207 -361.5436)
		(width 0.508)
		(layer "F.Cu")
		(net "P12V_AUX")
	)
	(segment
		(start 24.500078 -463.049874)
		(end 24.500078 -468.168482)
		(width 0.635)
		(layer "F.Cu")
		(net "P12V_AUX")
	)
	(segment
		(start 28.6385 -378.7775)
		(end 27.559 -378.7775)
		(width 0.508)
		(layer "F.Cu")
		(net "P12V_AUX")
	)
	(segment
		(start 19.38147 -443.95009)
		(end 24.500078 -443.95009)
		(width 0.635)
		(layer "F.Cu")
		(net "P12V_AUX")
	)
	(segment
		(start 24.500078 -457.931266)
		(end 24.500078 -463.049874)
		(width 0.635)
		(layer "F.Cu")
		(net "P12V_AUX")
	)
	(segment
		(start 24.500078 -438.831482)
		(end 24.500078 -443.95009)
		(width 0.635)
		(layer "F.Cu")
		(net "P12V_AUX")
	)
	(segment
		(start 38.562788 -191.1604)
		(end 34.3916 -186.989212)
		(width 0.508)
		(layer "F.Cu")
		(net "P12V_AUX")
	)
	(segment
		(start 21.209 -372.1735)
		(end 21.209 -373.253)
		(width 0.508)
		(layer "F.Cu")
		(net "P12V_AUX")
	)
	(segment
		(start 33.9725 -185.0136)
		(end 34.3916 -185.4327)
		(width 0.508)
		(layer "F.Cu")
		(net "P12V_AUX")
	)
	(segment
		(start 38.619684 -360.4768)
		(end 38.619684 -361.542584)
		(width 0.508)
		(layer "F.Cu")
		(net "P12V_AUX")
	)
	(via
		(at 16.129 -471.424)
		(size 0.7112)
		(drill 0.4064)
		(layers "F.Cu" "B.Cu")
		(net "P12V_AUX")
	)
	(via
		(at 18.415 -431.546)
		(size 0.7112)
		(drill 0.4064)
		(layers "F.Cu" "B.Cu")
		(net "P12V_AUX")
	)
	(via
		(at 13.716 -418.211)
		(size 0.7112)
		(drill 0.4064)
		(layers "F.Cu" "B.Cu")
		(net "P12V_AUX")
	)
	(via
		(at 27.432 -418.084)
		(size 0.7112)
		(drill 0.4064)
		(layers "F.Cu" "B.Cu")
		(net "P12V_AUX")
	)
	(via
		(at 34.671 -419.354)
		(size 0.7112)
		(drill 0.3556)
		(layers "F.Cu" "B.Cu")
		(net "P12V_AUX")
	)
	(via
		(at 24.765 -426.593)
		(size 0.7112)
		(drill 0.4064)
		(layers "F.Cu" "B.Cu")
		(net "P12V_AUX")
	)
	(via
		(at 44.704 -418.084)
		(size 0.7112)
		(drill 0.4064)
		(layers "F.Cu" "B.Cu")
		(net "P12V_AUX")
	)
	(via
		(at 23.114 -427.99)
		(size 0.7112)
		(drill 0.4064)
		(layers "F.Cu" "B.Cu")
		(net "P12V_AUX")
	)
	(via
		(at 28.956 -468.249)
		(size 0.7112)
		(drill 0.4064)
		(layers "F.Cu" "B.Cu")
		(net "P12V_AUX")
	)
	(via
		(at 19.304 -415.036)
		(size 0.7112)
		(drill 0.4064)
		(layers "F.Cu" "B.Cu")
		(net "P12V_AUX")
	)
	(via
		(at 18.415 -440.182)
		(size 0.7112)
		(drill 0.4064)
		(layers "F.Cu" "B.Cu")
		(net "P12V_AUX")
	)
	(via
		(at 40.386 -421.513)
		(size 0.7112)
		(drill 0.4064)
		(layers "F.Cu" "B.Cu")
		(net "P12V_AUX")
	)
	(via
		(at 19.177 -426.466)
		(size 0.7112)
		(drill 0.4064)
		(layers "F.Cu" "B.Cu")
		(net "P12V_AUX")
	)
	(via
		(at 20.447 -427.863)
		(size 0.7112)
		(drill 0.4064)
		(layers "F.Cu" "B.Cu")
		(net "P12V_AUX")
	)
	(via
		(at 15.8242 -416.8902)
		(size 0.7112)
		(drill 0.3556)
		(layers "F.Cu" "B.Cu")
		(net "P12V_AUX")
	)
	(via
		(at 43.18 -421.513)
		(size 0.7112)
		(drill 0.4064)
		(layers "F.Cu" "B.Cu")
		(net "P12V_AUX")
	)
	(via
		(at 19.177 -466.979)
		(size 0.7112)
		(drill 0.4064)
		(layers "F.Cu" "B.Cu")
		(net "P12V_AUX")
	)
	(via
		(at 34.925 -421.513)
		(size 0.7112)
		(drill 0.4064)
		(layers "F.Cu" "B.Cu")
		(net "P12V_AUX")
	)
	(via
		(at 29.845 -423.926)
		(size 0.7112)
		(drill 0.4064)
		(layers "F.Cu" "B.Cu")
		(net "P12V_AUX")
	)
	(via
		(at 14.605 -415.163)
		(size 0.7112)
		(drill 0.4064)
		(layers "F.Cu" "B.Cu")
		(net "P12V_AUX")
	)
	(via
		(at 30.988 -428.117)
		(size 0.7112)
		(drill 0.4064)
		(layers "F.Cu" "B.Cu")
		(net "P12V_AUX")
	)
	(via
		(at 42.545 -414.655)
		(size 0.7112)
		(drill 0.4064)
		(layers "F.Cu" "B.Cu")
		(net "P12V_AUX")
	)
	(via
		(at 30.353 -434.36794)
		(size 0.7112)
		(drill 0.4064)
		(layers "F.Cu" "B.Cu")
		(net "P12V_AUX")
	)
	(via
		(at 21.971 -438.404)
		(size 0.7112)
		(drill 0.4064)
		(layers "F.Cu" "B.Cu")
		(net "P12V_AUX")
	)
	(via
		(at 25.019 -430.911)
		(size 0.7112)
		(drill 0.4064)
		(layers "F.Cu" "B.Cu")
		(net "P12V_AUX")
	)
	(via
		(at 42.164 -418.084)
		(size 0.7112)
		(drill 0.4064)
		(layers "F.Cu" "B.Cu")
		(net "P12V_AUX")
	)
	(via
		(at 14.224 -430.53)
		(size 0.7112)
		(drill 0.4064)
		(layers "F.Cu" "B.Cu")
		(net "P12V_AUX")
	)
	(via
		(at 22.098 -450.62394)
		(size 0.7112)
		(drill 0.4064)
		(layers "F.Cu" "B.Cu")
		(net "P12V_AUX")
	)
	(via
		(at 30.353 -438.17794)
		(size 0.7112)
		(drill 0.4064)
		(layers "F.Cu" "B.Cu")
		(net "P12V_AUX")
	)
	(via
		(at 24.892 -453.644)
		(size 0.7112)
		(drill 0.4064)
		(layers "F.Cu" "B.Cu")
		(net "P12V_AUX")
	)
	(via
		(at 21.6154 -468.503)
		(size 0.7112)
		(drill 0.4064)
		(layers "F.Cu" "B.Cu")
		(net "P12V_AUX")
	)
	(via
		(at 24.765 -456.184)
		(size 0.7112)
		(drill 0.4064)
		(layers "F.Cu" "B.Cu")
		(net "P12V_AUX")
	)
	(via
		(at 14.224 -434.975)
		(size 0.7112)
		(drill 0.4064)
		(layers "F.Cu" "B.Cu")
		(net "P12V_AUX")
	)
	(via
		(at 21.59 -378.46)
		(size 0.7112)
		(drill 0.4064)
		(layers "F.Cu" "B.Cu")
		(net "P12V_AUX")
	)
	(via
		(at 30.353 -430.93894)
		(size 0.7112)
		(drill 0.4064)
		(layers "F.Cu" "B.Cu")
		(net "P12V_AUX")
	)
	(via
		(at 44.704 -414.528)
		(size 0.7112)
		(drill 0.4064)
		(layers "F.Cu" "B.Cu")
		(net "P12V_AUX")
	)
	(via
		(at 40.386 -414.655)
		(size 0.7112)
		(drill 0.4064)
		(layers "F.Cu" "B.Cu")
		(net "P12V_AUX")
	)
	(via
		(at 21.844 -415.036)
		(size 0.7112)
		(drill 0.4064)
		(layers "F.Cu" "B.Cu")
		(net "P12V_AUX")
	)
	(via
		(at 30.353 -447.04)
		(size 0.7112)
		(drill 0.4064)
		(layers "F.Cu" "B.Cu")
		(net "P12V_AUX")
	)
	(via
		(at 16.383 -446.659)
		(size 0.7112)
		(drill 0.4064)
		(layers "F.Cu" "B.Cu")
		(net "P12V_AUX")
	)
	(via
		(at 29.845 -439.928)
		(size 0.7112)
		(drill 0.4064)
		(layers "F.Cu" "B.Cu")
		(net "P12V_AUX")
	)
	(via
		(at 16.256 -468.503)
		(size 0.7112)
		(drill 0.4064)
		(layers "F.Cu" "B.Cu")
		(net "P12V_AUX")
	)
	(via
		(at 32.258 -418.084)
		(size 0.7112)
		(drill 0.4064)
		(layers "F.Cu" "B.Cu")
		(net "P12V_AUX")
	)
	(via
		(at 27.500072 -451.4342)
		(size 0.7112)
		(drill 0.4064)
		(layers "F.Cu" "B.Cu")
		(net "P12V_AUX")
	)
	(via
		(at 16.383 -462.661)
		(size 0.7112)
		(drill 0.4064)
		(layers "F.Cu" "B.Cu")
		(net "P12V_AUX")
	)
	(via
		(at 24.511 -415.036)
		(size 0.7112)
		(drill 0.4064)
		(layers "F.Cu" "B.Cu")
		(net "P12V_AUX")
	)
	(via
		(at 27.373072 -454.43394)
		(size 0.7112)
		(drill 0.4064)
		(layers "F.Cu" "B.Cu")
		(net "P12V_AUX")
	)
	(via
		(at 19.431 -380.619)
		(size 0.7112)
		(drill 0.3556)
		(layers "F.Cu" "B.Cu")
		(net "P12V_AUX")
	)
	(via
		(at 25.146 -433.578)
		(size 0.7112)
		(drill 0.4064)
		(layers "F.Cu" "B.Cu")
		(net "P12V_AUX")
	)
	(via
		(at 29.972 -418.084)
		(size 0.7112)
		(drill 0.4064)
		(layers "F.Cu" "B.Cu")
		(net "P12V_AUX")
	)
	(via
		(at 27.559 -470.30894)
		(size 0.7112)
		(drill 0.4064)
		(layers "F.Cu" "B.Cu")
		(net "P12V_AUX")
	)
	(via
		(at 35.052 -415.036)
		(size 0.7112)
		(drill 0.4064)
		(layers "F.Cu" "B.Cu")
		(net "P12V_AUX")
	)
	(via
		(at 15.113 -423.418)
		(size 0.7112)
		(drill 0.4064)
		(layers "F.Cu" "B.Cu")
		(net "P12V_AUX")
	)
	(via
		(at 18.415 -464.82)
		(size 0.7112)
		(drill 0.4064)
		(layers "F.Cu" "B.Cu")
		(net "P12V_AUX")
	)
	(via
		(at 16.51 -449.072)
		(size 0.7112)
		(drill 0.4064)
		(layers "F.Cu" "B.Cu")
		(net "P12V_AUX")
	)
	(via
		(at 15.621 -435.991)
		(size 0.7112)
		(drill 0.3556)
		(layers "F.Cu" "B.Cu")
		(net "P12V_AUX")
	)
	(via
		(at 29.845 -421.513)
		(size 0.7112)
		(drill 0.4064)
		(layers "F.Cu" "B.Cu")
		(net "P12V_AUX")
	)
	(via
		(at 21.844 -421.513)
		(size 0.7112)
		(drill 0.4064)
		(layers "F.Cu" "B.Cu")
		(net "P12V_AUX")
	)
	(via
		(at 40.2844 -191.1604)
		(size 0.5588)
		(drill 0.3048)
		(layers "F.Cu" "B.Cu")
		(net "P12V_AUX")
	)
	(via
		(at 21.844 -426.466)
		(size 0.7112)
		(drill 0.4064)
		(layers "F.Cu" "B.Cu")
		(net "P12V_AUX")
	)
	(via
		(at 25.273 -473.075)
		(size 0.7112)
		(drill 0.4064)
		(layers "F.Cu" "B.Cu")
		(net "P12V_AUX")
	)
	(via
		(at 14.097 -440.817)
		(size 0.7112)
		(drill 0.4064)
		(layers "F.Cu" "B.Cu")
		(net "P12V_AUX")
	)
	(via
		(at 18.161 -447.04)
		(size 0.7112)
		(drill 0.4064)
		(layers "F.Cu" "B.Cu")
		(net "P12V_AUX")
	)
	(via
		(at 21.844 -423.926)
		(size 0.7112)
		(drill 0.4064)
		(layers "F.Cu" "B.Cu")
		(net "P12V_AUX")
	)
	(via
		(at 18.542 -469.138)
		(size 0.7112)
		(drill 0.4064)
		(layers "F.Cu" "B.Cu")
		(net "P12V_AUX")
	)
	(via
		(at 16.256 -465.836)
		(size 0.7112)
		(drill 0.4064)
		(layers "F.Cu" "B.Cu")
		(net "P12V_AUX")
	)
	(via
		(at 16.256 -415.036)
		(size 0.7112)
		(drill 0.4064)
		(layers "F.Cu" "B.Cu")
		(net "P12V_AUX")
	)
	(via
		(at 16.51 -454.66)
		(size 0.7112)
		(drill 0.4064)
		(layers "F.Cu" "B.Cu")
		(net "P12V_AUX")
	)
	(via
		(at 27.813 -436.753)
		(size 0.7112)
		(drill 0.4064)
		(layers "F.Cu" "B.Cu")
		(net "P12V_AUX")
	)
	(via
		(at 19.304 -418.084)
		(size 0.7112)
		(drill 0.4064)
		(layers "F.Cu" "B.Cu")
		(net "P12V_AUX")
	)
	(via
		(at 27.051 -473.075)
		(size 0.7112)
		(drill 0.4064)
		(layers "F.Cu" "B.Cu")
		(net "P12V_AUX")
	)
	(via
		(at 30.353 -456.311)
		(size 0.7112)
		(drill 0.4064)
		(layers "F.Cu" "B.Cu")
		(net "P12V_AUX")
	)
	(via
		(at 16.383 -460.248)
		(size 0.7112)
		(drill 0.4064)
		(layers "F.Cu" "B.Cu")
		(net "P12V_AUX")
	)
	(via
		(at 21.336 -474.8784)
		(size 0.7112)
		(drill 0.3556)
		(layers "F.Cu" "B.Cu")
		(net "P12V_AUX")
	)
	(via
		(at 20.066 -448.691)
		(size 0.7112)
		(drill 0.4064)
		(layers "F.Cu" "B.Cu")
		(net "P12V_AUX")
	)
	(via
		(at 24.384 -418.084)
		(size 0.7112)
		(drill 0.4064)
		(layers "F.Cu" "B.Cu")
		(net "P12V_AUX")
	)
	(via
		(at 21.971 -435.25694)
		(size 0.7112)
		(drill 0.4064)
		(layers "F.Cu" "B.Cu")
		(net "P12V_AUX")
	)
	(via
		(at 28.321 -449.199)
		(size 0.7112)
		(drill 0.4064)
		(layers "F.Cu" "B.Cu")
		(net "P12V_AUX")
	)
	(via
		(at 37.719 -421.64)
		(size 0.7112)
		(drill 0.4064)
		(layers "F.Cu" "B.Cu")
		(net "P12V_AUX")
	)
	(via
		(at 16.383 -421.259)
		(size 0.7112)
		(drill 0.4064)
		(layers "F.Cu" "B.Cu")
		(net "P12V_AUX")
	)
	(via
		(at 14.097 -437.769)
		(size 0.7112)
		(drill 0.4064)
		(layers "F.Cu" "B.Cu")
		(net "P12V_AUX")
	)
	(via
		(at 25.019 -436.118)
		(size 0.7112)
		(drill 0.4064)
		(layers "F.Cu" "B.Cu")
		(net "P12V_AUX")
	)
	(via
		(at 16.51 -442.595)
		(size 0.7112)
		(drill 0.4064)
		(layers "F.Cu" "B.Cu")
		(net "P12V_AUX")
	)
	(via
		(at 37.592 -418.084)
		(size 0.7112)
		(drill 0.4064)
		(layers "F.Cu" "B.Cu")
		(net "P12V_AUX")
	)
	(via
		(at 29.083 -473.075)
		(size 0.7112)
		(drill 0.4064)
		(layers "F.Cu" "B.Cu")
		(net "P12V_AUX")
	)
	(via
		(at 28.067 -457.454)
		(size 0.7112)
		(drill 0.4064)
		(layers "F.Cu" "B.Cu")
		(net "P12V_AUX")
	)
	(via
		(at 32.385 -421.513)
		(size 0.7112)
		(drill 0.4064)
		(layers "F.Cu" "B.Cu")
		(net "P12V_AUX")
	)
	(via
		(at 21.844 -418.084)
		(size 0.7112)
		(drill 0.4064)
		(layers "F.Cu" "B.Cu")
		(net "P12V_AUX")
	)
	(via
		(at 35.052 -418.084)
		(size 0.7112)
		(drill 0.4064)
		(layers "F.Cu" "B.Cu")
		(net "P12V_AUX")
	)
	(via
		(at 29.718 -414.909)
		(size 0.7112)
		(drill 0.4064)
		(layers "F.Cu" "B.Cu")
		(net "P12V_AUX")
	)
	(via
		(at 16.383 -418.084)
		(size 0.7112)
		(drill 0.4064)
		(layers "F.Cu" "B.Cu")
		(net "P12V_AUX")
	)
	(via
		(at 45.212 -421.513)
		(size 0.7112)
		(drill 0.4064)
		(layers "F.Cu" "B.Cu")
		(net "P12V_AUX")
	)
	(via
		(at 30.48 -460.121)
		(size 0.7112)
		(drill 0.4064)
		(layers "F.Cu" "B.Cu")
		(net "P12V_AUX")
	)
	(via
		(at 24.638 -423.926)
		(size 0.7112)
		(drill 0.4064)
		(layers "F.Cu" "B.Cu")
		(net "P12V_AUX")
	)
	(via
		(at 14.224 -432.943)
		(size 0.7112)
		(drill 0.4064)
		(layers "F.Cu" "B.Cu")
		(net "P12V_AUX")
	)
	(via
		(at 27.178 -423.926)
		(size 0.7112)
		(drill 0.4064)
		(layers "F.Cu" "B.Cu")
		(net "P12V_AUX")
	)
	(via
		(at 31.115 -473.075)
		(size 0.7112)
		(drill 0.4064)
		(layers "F.Cu" "B.Cu")
		(net "P12V_AUX")
	)
	(via
		(at 40.132 -418.084)
		(size 0.7112)
		(drill 0.4064)
		(layers "F.Cu" "B.Cu")
		(net "P12V_AUX")
	)
	(via
		(at 26.162 -427.99)
		(size 0.7112)
		(drill 0.4064)
		(layers "F.Cu" "B.Cu")
		(net "P12V_AUX")
	)
	(via
		(at 15.875 -434.086)
		(size 0.7112)
		(drill 0.4064)
		(layers "F.Cu" "B.Cu")
		(net "P12V_AUX")
	)
	(via
		(at 18.415 -436.118)
		(size 0.7112)
		(drill 0.4064)
		(layers "F.Cu" "B.Cu")
		(net "P12V_AUX")
	)
	(via
		(at 44.245784 -159.561784)
		(size 0.5588)
		(drill 0.3048)
		(layers "F.Cu" "B.Cu")
		(net "P12V_AUX")
	)
	(via
		(at 30.607 -470.027)
		(size 0.7112)
		(drill 0.4064)
		(layers "F.Cu" "B.Cu")
		(net "P12V_AUX")
	)
	(via
		(at 24.638 -421.513)
		(size 0.7112)
		(drill 0.4064)
		(layers "F.Cu" "B.Cu")
		(net "P12V_AUX")
	)
	(via
		(at 40.259 -372.491)
		(size 0.5588)
		(drill 0.3048)
		(layers "F.Cu" "B.Cu")
		(net "P12V_AUX")
	)
	(via
		(at 19.177 -421.513)
		(size 0.7112)
		(drill 0.4064)
		(layers "F.Cu" "B.Cu")
		(net "P12V_AUX")
	)
	(via
		(at 15.113 -413.385)
		(size 0.7112)
		(drill 0.3556)
		(layers "F.Cu" "B.Cu")
		(net "P12V_AUX")
	)
	(via
		(at 26.924 -415.036)
		(size 0.7112)
		(drill 0.4064)
		(layers "F.Cu" "B.Cu")
		(net "P12V_AUX")
	)
	(via
		(at 22.479 -453.39)
		(size 0.7112)
		(drill 0.4064)
		(layers "F.Cu" "B.Cu")
		(net "P12V_AUX")
	)
	(via
		(at 32.385 -423.926)
		(size 0.7112)
		(drill 0.4064)
		(layers "F.Cu" "B.Cu")
		(net "P12V_AUX")
	)
	(via
		(at 15.875 -429.641)
		(size 0.7112)
		(drill 0.4064)
		(layers "F.Cu" "B.Cu")
		(net "P12V_AUX")
	)
	(via
		(at 16.51 -444.246)
		(size 0.7112)
		(drill 0.4064)
		(layers "F.Cu" "B.Cu")
		(net "P12V_AUX")
	)
	(via
		(at 27.178 -421.513)
		(size 0.7112)
		(drill 0.4064)
		(layers "F.Cu" "B.Cu")
		(net "P12V_AUX")
	)
	(via
		(at 24.638 -470.027)
		(size 0.7112)
		(drill 0.4064)
		(layers "F.Cu" "B.Cu")
		(net "P12V_AUX")
	)
	(via
		(at 21.7678 -470.4842)
		(size 0.7112)
		(drill 0.4064)
		(layers "F.Cu" "B.Cu")
		(net "P12V_AUX")
	)
	(via
		(at 31.75 -426.466)
		(size 0.7112)
		(drill 0.4064)
		(layers "F.Cu" "B.Cu")
		(net "P12V_AUX")
	)
	(via
		(at 13.589 -421.386)
		(size 0.7112)
		(drill 0.4064)
		(layers "F.Cu" "B.Cu")
		(net "P12V_AUX")
	)
	(via
		(at 18.034 -473.583)
		(size 0.7112)
		(drill 0.3556)
		(layers "F.Cu" "B.Cu")
		(net "P12V_AUX")
	)
	(via
		(at 20.574 -457.708)
		(size 0.7112)
		(drill 0.4064)
		(layers "F.Cu" "B.Cu")
		(net "P12V_AUX")
	)
	(via
		(at 30.607 -466.471)
		(size 0.7112)
		(drill 0.4064)
		(layers "F.Cu" "B.Cu")
		(net "P12V_AUX")
	)
	(via
		(at 35.5346 -359.4354)
		(size 0.5588)
		(drill 0.3048)
		(layers "F.Cu" "B.Cu")
		(net "P12V_AUX")
	)
	(via
		(at 16.129 -473.202)
		(size 0.7112)
		(drill 0.4064)
		(layers "F.Cu" "B.Cu")
		(net "P12V_AUX")
	)
	(via
		(at 21.209 -373.253)
		(size 0.7112)
		(drill 0.4064)
		(layers "F.Cu" "B.Cu")
		(net "P12V_AUX")
	)
	(via
		(at 28.6385 -378.7775)
		(size 0.5588)
		(drill 0.3048)
		(layers "F.Cu" "B.Cu")
		(net "P12V_AUX")
	)
	(via
		(at 18.542 -460.502)
		(size 0.7112)
		(drill 0.4064)
		(layers "F.Cu" "B.Cu")
		(net "P12V_AUX")
	)
	(via
		(at 27.813 -431.546)
		(size 0.7112)
		(drill 0.4064)
		(layers "F.Cu" "B.Cu")
		(net "P12V_AUX")
	)
	(via
		(at 16.383 -457.581)
		(size 0.7112)
		(drill 0.4064)
		(layers "F.Cu" "B.Cu")
		(net "P12V_AUX")
	)
	(via
		(at 15.24 -439.42)
		(size 0.7112)
		(drill 0.4064)
		(layers "F.Cu" "B.Cu")
		(net "P12V_AUX")
	)
	(via
		(at 16.51 -437.896)
		(size 0.7112)
		(drill 0.4064)
		(layers "F.Cu" "B.Cu")
		(net "P12V_AUX")
	)
	(via
		(at 38.735 -369.824)
		(size 0.7112)
		(drill 0.4064)
		(layers "F.Cu" "B.Cu")
		(net "P12V_AUX")
	)
	(via
		(at 27.94 -434.213)
		(size 0.7112)
		(drill 0.4064)
		(layers "F.Cu" "B.Cu")
		(net "P12V_AUX")
	)
	(via
		(at 32.385 -414.782)
		(size 0.7112)
		(drill 0.4064)
		(layers "F.Cu" "B.Cu")
		(net "P12V_AUX")
	)
	(via
		(at 18.288 -456.692)
		(size 0.7112)
		(drill 0.4064)
		(layers "F.Cu" "B.Cu")
		(net "P12V_AUX")
	)
	(via
		(at 17.526 -427.863)
		(size 0.7112)
		(drill 0.4064)
		(layers "F.Cu" "B.Cu")
		(net "P12V_AUX")
	)
	(via
		(at 28.575 -427.99)
		(size 0.7112)
		(drill 0.4064)
		(layers "F.Cu" "B.Cu")
		(net "P12V_AUX")
	)
	(via
		(at 16.51 -440.69)
		(size 0.7112)
		(drill 0.4064)
		(layers "F.Cu" "B.Cu")
		(net "P12V_AUX")
	)
	(via
		(at 21.971 -431.82794)
		(size 0.7112)
		(drill 0.4064)
		(layers "F.Cu" "B.Cu")
		(net "P12V_AUX")
	)
	(via
		(at 21.971 -455.44994)
		(size 0.7112)
		(drill 0.4064)
		(layers "F.Cu" "B.Cu")
		(net "P12V_AUX")
	)
	(via
		(at 15.875 -431.8)
		(size 0.7112)
		(drill 0.4064)
		(layers "F.Cu" "B.Cu")
		(net "P12V_AUX")
	)
	(via
		(at 24.765 -450.977)
		(size 0.7112)
		(drill 0.4064)
		(layers "F.Cu" "B.Cu")
		(net "P12V_AUX")
	)
	(via
		(at 27.305 -426.466)
		(size 0.7112)
		(drill 0.4064)
		(layers "F.Cu" "B.Cu")
		(net "P12V_AUX")
	)
	(via
		(at 17.78 -423.672)
		(size 0.7112)
		(drill 0.4064)
		(layers "F.Cu" "B.Cu")
		(net "P12V_AUX")
	)
	(via
		(at 29.845 -426.466)
		(size 0.7112)
		(drill 0.4064)
		(layers "F.Cu" "B.Cu")
		(net "P12V_AUX")
	)
	(via
		(at 27.559 -438.658)
		(size 0.7112)
		(drill 0.4064)
		(layers "F.Cu" "B.Cu")
		(net "P12V_AUX")
	)
	(via
		(at 37.846 -414.655)
		(size 0.7112)
		(drill 0.4064)
		(layers "F.Cu" "B.Cu")
		(net "P12V_AUX")
	)
	(via
		(at 30.353 -443.76594)
		(size 0.7112)
		(drill 0.4064)
		(layers "F.Cu" "B.Cu")
		(net "P12V_AUX")
	)
	(segment
		(start 19.431 -380.619)
		(end 16.1036 -383.9464)
		(width 1.016)
		(layer "B.Cu")
		(net "P12V_AUX")
	)
	(segment
		(start 24.500078 -463.049874)
		(end 24.500078 -468.168482)
		(width 0.635)
		(layer "B.Cu")
		(net "P12V_AUX")
	)
	(segment
		(start 37.7698 -369.824)
		(end 36.7538 -370.84)
		(width 0.508)
		(layer "B.Cu")
		(net "P12V_AUX")
	)
	(segment
		(start 35.5346 -359.4354)
		(end 35.306 -359.2068)
		(width 0.508)
		(layer "B.Cu")
		(net "P12V_AUX")
	)
	(segment
		(start 37.211 -277.622)
		(end 37.211 -260.883908)
		(width 0.508)
		(layer "B.Cu")
		(net "P12V_AUX")
	)
	(segment
		(start 44.87545 -214.57285)
		(end 40.2844 -209.9818)
		(width 0.508)
		(layer "B.Cu")
		(net "P12V_AUX")
	)
	(segment
		(start 38.735 -370.560092)
		(end 40.259 -372.084092)
		(width 0.508)
		(layer "B.Cu")
		(net "P12V_AUX")
	)
	(segment
		(start 36.7538 -370.84)
		(end 36.7538 -370.840508)
		(width 0.508)
		(layer "B.Cu")
		(net "P12V_AUX")
	)
	(segment
		(start 21.59 -378.46)
		(end 19.431 -380.619)
		(width 1.016)
		(layer "B.Cu")
		(net "P12V_AUX")
	)
	(segment
		(start 24.500078 -443.95009)
		(end 29.618686 -443.95009)
		(width 0.635)
		(layer "B.Cu")
		(net "P12V_AUX")
	)
	(segment
		(start 41.275 -186.2836)
		(end 41.275 -178.1048)
		(width 0.508)
		(layer "B.Cu")
		(net "P12V_AUX")
	)
	(segment
		(start 24.500078 -443.95009)
		(end 24.500078 -449.068698)
		(width 0.635)
		(layer "B.Cu")
		(net "P12V_AUX")
	)
	(segment
		(start 21.4122 -378.2822)
		(end 21.4122 -373.4562)
		(width 1.016)
		(layer "B.Cu")
		(net "P12V_AUX")
	)
	(segment
		(start 43.9674 -175.4124)
		(end 43.9674 -159.840168)
		(width 0.508)
		(layer "B.Cu")
		(net "P12V_AUX")
	)
	(segment
		(start 16.1036 -412.6738)
		(end 14.605 -414.1724)
		(width 1.016)
		(layer "B.Cu")
		(net "P12V_AUX")
	)
	(segment
		(start 24.500078 -457.931266)
		(end 24.500078 -463.049874)
		(width 0.635)
		(layer "B.Cu")
		(net "P12V_AUX")
	)
	(segment
		(start 21.4122 -373.4562)
		(end 21.209 -373.253)
		(width 1.016)
		(layer "B.Cu")
		(net "P12V_AUX")
	)
	(segment
		(start 44.87545 -253.219458)
		(end 44.87545 -214.57285)
		(width 0.508)
		(layer "B.Cu")
		(net "P12V_AUX")
	)
	(segment
		(start 19.38147 -443.95009)
		(end 24.500078 -443.95009)
		(width 0.635)
		(layer "B.Cu")
		(net "P12V_AUX")
	)
	(segment
		(start 35.5346 -359.4354)
		(end 35.5346 -366.364012)
		(width 0.508)
		(layer "B.Cu")
		(net "P12V_AUX")
	)
	(segment
		(start 43.9674 -159.840168)
		(end 44.245784 -159.561784)
		(width 0.508)
		(layer "B.Cu")
		(net "P12V_AUX")
	)
	(segment
		(start 35.306 -359.2068)
		(end 35.306 -279.527)
		(width 0.508)
		(layer "B.Cu")
		(net "P12V_AUX")
	)
	(segment
		(start 24.500078 -438.831482)
		(end 24.500078 -443.95009)
		(width 0.635)
		(layer "B.Cu")
		(net "P12V_AUX")
	)
	(segment
		(start 36.7538 -370.840508)
		(end 28.816808 -378.7775)
		(width 0.508)
		(layer "B.Cu")
		(net "P12V_AUX")
	)
	(segment
		(start 28.816808 -378.7775)
		(end 28.6385 -378.7775)
		(width 0.508)
		(layer "B.Cu")
		(net "P12V_AUX")
	)
	(segment
		(start 40.259 -372.084092)
		(end 40.259 -372.491)
		(width 0.508)
		(layer "B.Cu")
		(net "P12V_AUX")
	)
	(segment
		(start 35.5346 -366.364012)
		(end 38.735 -369.564412)
		(width 0.508)
		(layer "B.Cu")
		(net "P12V_AUX")
	)
	(segment
		(start 40.2844 -187.2742)
		(end 41.275 -186.2836)
		(width 0.508)
		(layer "B.Cu")
		(net "P12V_AUX")
	)
	(segment
		(start 38.735 -369.824)
		(end 37.7698 -369.824)
		(width 0.508)
		(layer "B.Cu")
		(net "P12V_AUX")
	)
	(segment
		(start 19.38147 -463.049874)
		(end 24.500078 -463.049874)
		(width 0.635)
		(layer "B.Cu")
		(net "P12V_AUX")
	)
	(segment
		(start 16.1036 -383.9464)
		(end 16.1036 -412.6738)
		(width 1.016)
		(layer "B.Cu")
		(net "P12V_AUX")
	)
	(segment
		(start 38.735 -369.564412)
		(end 38.735 -369.824)
		(width 0.508)
		(layer "B.Cu")
		(net "P12V_AUX")
	)
	(segment
		(start 35.306 -279.527)
		(end 37.211 -277.622)
		(width 0.508)
		(layer "B.Cu")
		(net "P12V_AUX")
	)
	(segment
		(start 21.59 -378.46)
		(end 21.4122 -378.2822)
		(width 1.016)
		(layer "B.Cu")
		(net "P12V_AUX")
	)
	(segment
		(start 41.275 -178.1048)
		(end 43.9674 -175.4124)
		(width 0.508)
		(layer "B.Cu")
		(net "P12V_AUX")
	)
	(segment
		(start 40.2844 -209.9818)
		(end 40.2844 -191.1604)
		(width 0.508)
		(layer "B.Cu")
		(net "P12V_AUX")
	)
	(segment
		(start 38.735 -369.824)
		(end 38.735 -370.560092)
		(width 0.508)
		(layer "B.Cu")
		(net "P12V_AUX")
	)
	(segment
		(start 14.605 -414.1724)
		(end 14.605 -415.163)
		(width 1.016)
		(layer "B.Cu")
		(net "P12V_AUX")
	)
	(segment
		(start 37.211 -260.883908)
		(end 44.87545 -253.219458)
		(width 0.508)
		(layer "B.Cu")
		(net "P12V_AUX")
	)
	(segment
		(start 40.2844 -191.1604)
		(end 40.2844 -187.2742)
		(width 0.508)
		(layer "B.Cu")
		(net "P12V_AUX")
	)
	(segment
		(start 24.500078 -463.049874)
		(end 29.618686 -463.049874)
		(width 0.635)
		(layer "B.Cu")
		(net "P12V_AUX")
	)
	(segment
		(start 25.4508 -364.9218)
		(end 25.4508 -364.1852)
		(width 0.254)
		(layer "F.Cu")
		(net "ADM1276_TIMER")
	)
	(segment
		(start 24.8666 -363.601)
		(end 24.0665 -363.601)
		(width 0.254)
		(layer "F.Cu")
		(net "ADM1276_TIMER")
	)
	(segment
		(start 27.2796 -367.508028)
		(end 27.2796 -366.7506)
		(width 0.254)
		(layer "F.Cu")
		(net "ADM1276_TIMER")
	)
	(segment
		(start 25.4508 -364.1852)
		(end 24.8666 -363.601)
		(width 0.254)
		(layer "F.Cu")
		(net "ADM1276_TIMER")
	)
	(segment
		(start 27.2796 -366.7506)
		(end 25.4508 -364.9218)
		(width 0.254)
		(layer "F.Cu")
		(net "ADM1276_TIMER")
	)
	(via
		(at 25.4508 -364.1852)
		(size 0.7112)
		(drill 0.3556)
		(layers "F.Cu" "B.Cu")
		(net "ADM1276_TIMER")
	)
	(segment
		(start 34.5694 -371.1702)
		(end 33.5026 -370.1034)
		(width 0.508)
		(layer "F.Cu")
		(net "ADM1276_VOUT")
	)
	(segment
		(start 33.111186 -369.457986)
		(end 32.1564 -369.457986)
		(width 0.381)
		(layer "F.Cu")
		(net "ADM1276_VOUT")
	)
	(segment
		(start 33.5026 -369.8494)
		(end 33.111186 -369.457986)
		(width 0.381)
		(layer "F.Cu")
		(net "ADM1276_VOUT")
	)
	(segment
		(start 34.5694 -371.8306)
		(end 34.5694 -371.1702)
		(width 0.508)
		(layer "F.Cu")
		(net "ADM1276_VOUT")
	)
	(segment
		(start 35.2044 -372.4656)
		(end 34.5694 -371.8306)
		(width 0.508)
		(layer "F.Cu")
		(net "ADM1276_VOUT")
	)
	(segment
		(start 35.6743 -372.4656)
		(end 35.2044 -372.4656)
		(width 0.508)
		(layer "F.Cu")
		(net "ADM1276_VOUT")
	)
	(segment
		(start 33.5026 -370.1034)
		(end 33.5026 -369.8494)
		(width 0.381)
		(layer "F.Cu")
		(net "ADM1276_VOUT")
	)
	(via
		(at 34.5694 -371.8306)
		(size 0.7112)
		(drill 0.3556)
		(layers "F.Cu" "B.Cu")
		(net "ADM1276_VOUT")
	)
	(segment
		(start 20.826476 -175.381158)
		(end 20.826476 -176.43729)
		(width 0.1397)
		(layer "F.Cu")
		(net "NCT7368S_SEL")
	)
	(segment
		(start 22.0726 -175.87341)
		(end 23.674324 -175.87341)
		(width 0.1397)
		(layer "F.Cu")
		(net "NCT7368S_SEL")
	)
	(segment
		(start 20.826476 -176.43729)
		(end 21.71573 -176.43729)
		(width 0.1397)
		(layer "F.Cu")
		(net "NCT7368S_SEL")
	)
	(segment
		(start 21.85924 -176.5808)
		(end 21.85924 -176.08677)
		(width 0.1397)
		(layer "F.Cu")
		(net "NCT7368S_SEL")
	)
	(segment
		(start 20.829524 -175.37811)
		(end 20.826476 -175.381158)
		(width 0.1397)
		(layer "F.Cu")
		(net "NCT7368S_SEL")
	)
	(segment
		(start 21.85924 -176.08677)
		(end 22.0726 -175.87341)
		(width 0.1397)
		(layer "F.Cu")
		(net "NCT7368S_SEL")
	)
	(segment
		(start 21.71573 -176.43729)
		(end 21.85924 -176.5808)
		(width 0.1397)
		(layer "F.Cu")
		(net "NCT7368S_SEL")
	)
	(via
		(at 21.85924 -176.5808)
		(size 0.7112)
		(drill 0.3556)
		(layers "F.Cu" "B.Cu")
		(net "NCT7368S_SEL")
	)
	(segment
		(start 27.94889 -157.74289)
		(end 27.94889 -157.768544)
		(width 0.1397)
		(layer "F.Cu")
		(net "NCT7904_3VSB")
	)
	(segment
		(start 26.12009 -157.100016)
		(end 26.12009 -153.677112)
		(width 0.1397)
		(layer "F.Cu")
		(net "NCT7904_3VSB")
	)
	(segment
		(start 37.1348 -156.504386)
		(end 38.105842 -155.533344)
		(width 0.1397)
		(layer "F.Cu")
		(net "NCT7904_3VSB")
	)
	(segment
		(start 41.17975 -155.20035)
		(end 41.17975 -155.200096)
		(width 0.1397)
		(layer "F.Cu")
		(net "NCT7904_3VSB")
	)
	(segment
		(start 28.804362 -158.599378)
		(end 28.80487 -158.599886)
		(width 0.1397)
		(layer "F.Cu")
		(net "NCT7904_3VSB")
	)
	(segment
		(start 34.60369 -158.599886)
		(end 35.744404 -158.599886)
		(width 0.1397)
		(layer "F.Cu")
		(net "NCT7904_3VSB")
	)
	(segment
		(start 41.54805 -154.83205)
		(end 41.8084 -154.5717)
		(width 0.1397)
		(layer "F.Cu")
		(net "NCT7904_3VSB")
	)
	(segment
		(start 43.2054 -154.3304)
		(end 44.51731 -154.3304)
		(width 0.1397)
		(layer "F.Cu")
		(net "NCT7904_3VSB")
	)
	(segment
		(start 41.17975 -155.200096)
		(end 41.547796 -154.83205)
		(width 0.1397)
		(layer "F.Cu")
		(net "NCT7904_3VSB")
	)
	(segment
		(start 25.68067 -151.856694)
		(end 24.70531 -150.881334)
		(width 0.1397)
		(layer "F.Cu")
		(net "NCT7904_3VSB")
	)
	(segment
		(start 28.779724 -158.599378)
		(end 28.804362 -158.599378)
		(width 0.1397)
		(layer "F.Cu")
		(net "NCT7904_3VSB")
	)
	(segment
		(start 42.0497 -154.3304)
		(end 41.8084 -154.5717)
		(width 0.1397)
		(layer "F.Cu")
		(net "NCT7904_3VSB")
	)
	(segment
		(start 26.12009 -157.100016)
		(end 27.306016 -157.100016)
		(width 0.1397)
		(layer "F.Cu")
		(net "NCT7904_3VSB")
	)
	(segment
		(start 44.760134 -155.83789)
		(end 44.760134 -154.613356)
		(width 0.1397)
		(layer "F.Cu")
		(net "NCT7904_3VSB")
	)
	(segment
		(start 28.80487 -158.599886)
		(end 34.60369 -158.599886)
		(width 0.1397)
		(layer "F.Cu")
		(net "NCT7904_3VSB")
	)
	(segment
		(start 27.306016 -157.100016)
		(end 27.94889 -157.74289)
		(width 0.1397)
		(layer "F.Cu")
		(net "NCT7904_3VSB")
	)
	(segment
		(start 44.760134 -154.613356)
		(end 44.7802 -154.59329)
		(width 0.1397)
		(layer "F.Cu")
		(net "NCT7904_3VSB")
	)
	(segment
		(start 35.744404 -158.599886)
		(end 37.1348 -157.20949)
		(width 0.1397)
		(layer "F.Cu")
		(net "NCT7904_3VSB")
	)
	(segment
		(start 40.846756 -155.533344)
		(end 41.17975 -155.20035)
		(width 0.1397)
		(layer "F.Cu")
		(net "NCT7904_3VSB")
	)
	(segment
		(start 25.68067 -153.237692)
		(end 25.68067 -151.856694)
		(width 0.1397)
		(layer "F.Cu")
		(net "NCT7904_3VSB")
	)
	(segment
		(start 41.547796 -154.83205)
		(end 41.54805 -154.83205)
		(width 0.1397)
		(layer "F.Cu")
		(net "NCT7904_3VSB")
	)
	(segment
		(start 27.94889 -157.768544)
		(end 28.779724 -158.599378)
		(width 0.1397)
		(layer "F.Cu")
		(net "NCT7904_3VSB")
	)
	(segment
		(start 43.2054 -154.3304)
		(end 42.0497 -154.3304)
		(width 0.1397)
		(layer "F.Cu")
		(net "NCT7904_3VSB")
	)
	(segment
		(start 44.51731 -154.3304)
		(end 44.7802 -154.59329)
		(width 0.1397)
		(layer "F.Cu")
		(net "NCT7904_3VSB")
	)
	(segment
		(start 37.1348 -157.20949)
		(end 37.1348 -156.504386)
		(width 0.1397)
		(layer "F.Cu")
		(net "NCT7904_3VSB")
	)
	(segment
		(start 38.105842 -155.533344)
		(end 40.846756 -155.533344)
		(width 0.1397)
		(layer "F.Cu")
		(net "NCT7904_3VSB")
	)
	(segment
		(start 26.12009 -153.677112)
		(end 25.68067 -153.237692)
		(width 0.1397)
		(layer "F.Cu")
		(net "NCT7904_3VSB")
	)
	(via
		(at 44.7802 -154.59329)
		(size 0.7112)
		(drill 0.3556)
		(layers "F.Cu" "B.Cu")
		(net "NCT7904_3VSB")
	)
	(segment
		(start 23.9268 -373.2022)
		(end 24.257 -372.872)
		(width 0.508)
		(layer "F.Cu")
		(net "GND")
	)
	(segment
		(start 14.4526 -259.2324)
		(end 14.224 -259.461)
		(width 0.508)
		(layer "F.Cu")
		(net "GND")
	)
	(segment
		(start 36.0934 -147.6756)
		(end 36.3093 -147.8915)
		(width 0.508)
		(layer "F.Cu")
		(net "GND")
	)
	(segment
		(start 29.791914 -179.524914)
		(end 29.21 -178.943)
		(width 0.508)
		(layer "F.Cu")
		(net "GND")
	)
	(segment
		(start 40.005 -140.5382)
		(end 39.7002 -140.2334)
		(width 0.508)
		(layer "F.Cu")
		(net "GND")
	)
	(segment
		(start 37.999924 -43.659806)
		(end 39.079932 -43.659806)
		(width 0.635)
		(layer "F.Cu")
		(net "GND")
	)
	(segment
		(start 16.256 -167.0304)
		(end 16.256 -166.5478)
		(width 0.508)
		(layer "F.Cu")
		(net "GND")
	)
	(segment
		(start 40.539924 -43.659806)
		(end 40.539924 -44.739814)
		(width 0.635)
		(layer "F.Cu")
		(net "GND")
	)
	(segment
		(start 36.919916 -46.199806)
		(end 37.999924 -46.199806)
		(width 0.635)
		(layer "F.Cu")
		(net "GND")
	)
	(segment
		(start 36.576 -121.031)
		(end 36.068 -121.539)
		(width 0.508)
		(layer "F.Cu")
		(net "GND")
	)
	(segment
		(start 45.619924 -47.659798)
		(end 45.619924 -48.739806)
		(width 0.635)
		(layer "F.Cu")
		(net "GND")
	)
	(segment
		(start 28.9052 -354.7872)
		(end 28.194 -354.076)
		(width 0.4064)
		(layer "F.Cu")
		(net "GND")
	)
	(segment
		(start 41.3385 -159.2072)
		(end 41.3131 -159.1818)
		(width 0.508)
		(layer "F.Cu")
		(net "GND")
	)
	(segment
		(start 13.5128 -43.5102)
		(end 13.462 -43.561)
		(width 0.508)
		(layer "F.Cu")
		(net "GND")
	)
	(segment
		(start 2.972816 -311.740042)
		(end 4.040124 -311.740042)
		(width 0.635)
		(layer "F.Cu")
		(net "GND")
	)
	(segment
		(start 20.359624 -290.322)
		(end 20.077176 -290.604448)
		(width 0.508)
		(layer "F.Cu")
		(net "GND")
	)
	(segment
		(start 16.1798 -278.9428)
		(end 16.383 -279.146)
		(width 0.508)
		(layer "F.Cu")
		(net "GND")
	)
	(segment
		(start 45.619924 -46.199806)
		(end 46.699932 -46.199806)
		(width 0.635)
		(layer "F.Cu")
		(net "GND")
	)
	(segment
		(start 28.9052 -354.87356)
		(end 28.9052 -354.7872)
		(width 0.4064)
		(layer "F.Cu")
		(net "GND")
	)
	(segment
		(start 24.384 -235.839)
		(end 24.384 -236.474)
		(width 0.508)
		(layer "F.Cu")
		(net "GND")
	)
	(segment
		(start 24.4602 -141.605)
		(end 24.3586 -141.605)
		(width 0.508)
		(layer "F.Cu")
		(net "GND")
	)
	(segment
		(start 6.999986 -35.643312)
		(end 6.999986 -39.99992)
		(width 0.635)
		(layer "F.Cu")
		(net "GND")
	)
	(segment
		(start 23.1902 -145.6055)
		(end 23.1902 -146.558)
		(width 0.508)
		(layer "F.Cu")
		(net "GND")
	)
	(segment
		(start 40.6019 -140.5255)
		(end 40.6146 -140.5382)
		(width 0.508)
		(layer "F.Cu")
		(net "GND")
	)
	(segment
		(start 40.999918 -438.831482)
		(end 40.999918 -443.95009)
		(width 0.635)
		(layer "F.Cu")
		(net "GND")
	)
	(segment
		(start 37.211 -354.826316)
		(end 37.580316 -354.457)
		(width 0.508)
		(layer "F.Cu")
		(net "GND")
	)
	(segment
		(start 40.539924 -46.199806)
		(end 40.539924 -47.279814)
		(width 0.635)
		(layer "F.Cu")
		(net "GND")
	)
	(segment
		(start 38.227 -151.384)
		(end 38.67531 -151.83231)
		(width 0.508)
		(layer "F.Cu")
		(net "GND")
	)
	(segment
		(start 41.8084 -156.2989)
		(end 41.8973 -156.3878)
		(width 0.508)
		(layer "F.Cu")
		(net "GND")
	)
	(segment
		(start 22.24913 -147.6248)
		(end 22.24913 -147.6502)
		(width 0.508)
		(layer "F.Cu")
		(net "GND")
	)
	(segment
		(start 19.9136 -149.2377)
		(end 19.9136 -148.2598)
		(width 0.508)
		(layer "F.Cu")
		(net "GND")
	)
	(segment
		(start 15.494 -64.57315)
		(end 15.494 -64.516)
		(width 0.508)
		(layer "F.Cu")
		(net "GND")
	)
	(segment
		(start 45.500036 -290.64331)
		(end 45.500036 -294.999918)
		(width 0.635)
		(layer "F.Cu")
		(net "GND")
	)
	(segment
		(start 19.558 -185.6359)
		(end 18.9611 -185.6359)
		(width 0.508)
		(layer "F.Cu")
		(net "GND")
	)
	(segment
		(start 27.0256 -356.17404)
		(end 25.61844 -356.17404)
		(width 0.4064)
		(layer "F.Cu")
		(net "GND")
	)
	(segment
		(start 37.580316 -354.457)
		(end 37.580316 -354.076)
		(width 0.508)
		(layer "F.Cu")
		(net "GND")
	)
	(segment
		(start 36.919916 -41.119806)
		(end 37.999924 -41.119806)
		(width 0.635)
		(layer "F.Cu")
		(net "GND")
	)
	(segment
		(start 40.6146 -140.5382)
		(end 40.005 -140.5382)
		(width 0.508)
		(layer "F.Cu")
		(net "GND")
	)
	(segment
		(start 4.040124 -198.419974)
		(end 4.845558 -199.225408)
		(width 0.635)
		(layer "F.Cu")
		(net "GND")
	)
	(segment
		(start 13.843 -56.134)
		(end 13.7668 -56.0578)
		(width 0.508)
		(layer "F.Cu")
		(net "GND")
	)
	(segment
		(start 4.040124 -487.780076)
		(end 4.040124 -488.847384)
		(width 0.635)
		(layer "F.Cu")
		(net "GND")
	)
	(segment
		(start 6.999986 -39.99992)
		(end 11.356594 -39.99992)
		(width 0.635)
		(layer "F.Cu")
		(net "GND")
	)
	(segment
		(start 41.143428 -480.000056)
		(end 45.500036 -480.000056)
		(width 0.635)
		(layer "F.Cu")
		(net "GND")
	)
	(segment
		(start 37.338 -187.198)
		(end 37.084 -187.452)
		(width 0.508)
		(layer "F.Cu")
		(net "GND")
	)
	(segment
		(start 4.040124 -377.73991)
		(end 5.107432 -377.73991)
		(width 0.635)
		(layer "F.Cu")
		(net "GND")
	)
	(segment
		(start 21.700744 -163.227766)
		(end 21.3868 -163.54171)
		(width 0.508)
		(layer "F.Cu")
		(net "GND")
	)
	(segment
		(start 30.6832 -147.7518)
		(end 30.734 -147.701)
		(width 0.508)
		(layer "F.Cu")
		(net "GND")
	)
	(segment
		(start 15.3162 -250.0122)
		(end 14.605 -250.0122)
		(width 0.508)
		(layer "F.Cu")
		(net "GND")
	)
	(segment
		(start 15.3289 -39.4462)
		(end 15.3289 -38.5953)
		(width 0.508)
		(layer "F.Cu")
		(net "GND")
	)
	(segment
		(start 37.17671 -153.63571)
		(end 36.957 -153.416)
		(width 0.508)
		(layer "F.Cu")
		(net "GND")
	)
	(segment
		(start 40.539924 -42.579798)
		(end 40.539924 -43.659806)
		(width 0.635)
		(layer "F.Cu")
		(net "GND")
	)
	(segment
		(start 35.6616 -146.3802)
		(end 35.7378 -146.4564)
		(width 0.508)
		(layer "F.Cu")
		(net "GND")
	)
	(segment
		(start 6.999986 -39.99992)
		(end 6.999986 -44.356528)
		(width 0.635)
		(layer "F.Cu")
		(net "GND")
	)
	(segment
		(start 6.999986 -459.999842)
		(end 6.999986 -464.35645)
		(width 0.635)
		(layer "F.Cu")
		(net "GND")
	)
	(segment
		(start 32.9692 -176.9872)
		(end 32.869124 -176.887124)
		(width 0.508)
		(layer "F.Cu")
		(net "GND")
	)
	(segment
		(start 29.791914 -180.467)
		(end 29.791914 -179.524914)
		(width 0.508)
		(layer "F.Cu")
		(net "GND")
	)
	(segment
		(start 14.4399 -43.5102)
		(end 13.5128 -43.5102)
		(width 0.508)
		(layer "F.Cu")
		(net "GND")
	)
	(segment
		(start 22.1488 -363.7026)
		(end 22.2504 -363.601)
		(width 0.508)
		(layer "F.Cu")
		(net "GND")
	)
	(segment
		(start 45.449998 -337.49996)
		(end 50.568606 -337.49996)
		(width 0.635)
		(layer "F.Cu")
		(net "GND")
	)
	(segment
		(start 35.6616 -145.3896)
		(end 35.6616 -145.4404)
		(width 0.508)
		(layer "F.Cu")
		(net "GND")
	)
	(segment
		(start 44.539916 -43.659806)
		(end 45.619924 -43.659806)
		(width 0.635)
		(layer "F.Cu")
		(net "GND")
	)
	(segment
		(start 42.0116 -362.3945)
		(end 42.926 -362.3945)
		(width 0.508)
		(layer "F.Cu")
		(net "GND")
	)
	(segment
		(start 6.92404 -278.627332)
		(end 6.913372 -278.638)
		(width 0.508)
		(layer "F.Cu")
		(net "GND")
	)
	(segment
		(start 37.999924 -42.579798)
		(end 37.999924 -43.659806)
		(width 0.635)
		(layer "F.Cu")
		(net "GND")
	)
	(segment
		(start 37.999924 -46.199806)
		(end 37.999924 -47.279814)
		(width 0.635)
		(layer "F.Cu")
		(net "GND")
	)
	(segment
		(start 43.079924 -48.739806)
		(end 44.159932 -48.739806)
		(width 0.635)
		(layer "F.Cu")
		(net "GND")
	)
	(segment
		(start 24.257 -372.872)
		(end 24.257 -371.9195)
		(width 0.508)
		(layer "F.Cu")
		(net "GND")
	)
	(segment
		(start 37.999924 -46.199806)
		(end 39.079932 -46.199806)
		(width 0.635)
		(layer "F.Cu")
		(net "GND")
	)
	(segment
		(start 29.1592 -254.3429)
		(end 29.1592 -255.27)
		(width 0.508)
		(layer "F.Cu")
		(net "GND")
	)
	(segment
		(start 22.2504 -363.601)
		(end 23.1775 -363.601)
		(width 0.508)
		(layer "F.Cu")
		(net "GND")
	)
	(segment
		(start 36.919916 -48.739806)
		(end 37.999924 -48.739806)
		(width 0.635)
		(layer "F.Cu")
		(net "GND")
	)
	(segment
		(start 22.1996 -146.7231)
		(end 22.1996 -147.57527)
		(width 0.508)
		(layer "F.Cu")
		(net "GND")
	)
	(segment
		(start 24.3586 -141.605)
		(end 23.4188 -140.6652)
		(width 0.508)
		(layer "F.Cu")
		(net "GND")
	)
	(segment
		(start 41.999916 -46.199806)
		(end 43.079924 -46.199806)
		(width 0.635)
		(layer "F.Cu")
		(net "GND")
	)
	(segment
		(start 15.9004 -250.5964)
		(end 15.3162 -250.0122)
		(width 0.508)
		(layer "F.Cu")
		(net "GND")
	)
	(segment
		(start 40.539924 -48.739806)
		(end 41.619932 -48.739806)
		(width 0.635)
		(layer "F.Cu")
		(net "GND")
	)
	(segment
		(start 29.464 -195.3514)
		(end 30.4292 -195.3514)
		(width 0.508)
		(layer "F.Cu")
		(net "GND")
	)
	(segment
		(start 22.352 -247.9802)
		(end 21.209 -247.9802)
		(width 0.508)
		(layer "F.Cu")
		(net "GND")
	)
	(segment
		(start 44.03725 -365.083852)
		(end 44.03725 -363.855)
		(width 0.508)
		(layer "F.Cu")
		(net "GND")
	)
	(segment
		(start 2.643378 -459.999842)
		(end 6.999986 -459.999842)
		(width 0.635)
		(layer "F.Cu")
		(net "GND")
	)
	(segment
		(start 38.989 -144.7927)
		(end 38.989 -145.887186)
		(width 0.508)
		(layer "F.Cu")
		(net "GND")
	)
	(segment
		(start 29.50845 -214.17915)
		(end 30.1498 -213.5378)
		(width 0.254)
		(layer "F.Cu")
		(net "GND")
	)
	(segment
		(start 29.7688 -194.0814)
		(end 30.734 -195.0466)
		(width 0.508)
		(layer "F.Cu")
		(net "GND")
	)
	(segment
		(start 43.079924 -46.199806)
		(end 43.079924 -47.279814)
		(width 0.635)
		(layer "F.Cu")
		(net "GND")
	)
	(segment
		(start 25.7302 -251.6632)
		(end 24.7142 -251.6632)
		(width 0.508)
		(layer "F.Cu")
		(net "GND")
	)
	(segment
		(start 31.7246 -148.629116)
		(end 31.7246 -147.828)
		(width 0.508)
		(layer "F.Cu")
		(net "GND")
	)
	(segment
		(start 32.869124 -176.887124)
		(end 32.869124 -175.80991)
		(width 0.508)
		(layer "F.Cu")
		(net "GND")
	)
	(segment
		(start 42.019982 -175.862488)
		(end 41.4782 -176.40427)
		(width 0.508)
		(layer "F.Cu")
		(net "GND")
	)
	(segment
		(start 37.999924 -48.739806)
		(end 39.079932 -48.739806)
		(width 0.635)
		(layer "F.Cu")
		(net "GND")
	)
	(segment
		(start 19.0373 -187.4393)
		(end 19.1008 -187.4393)
		(width 0.508)
		(layer "F.Cu")
		(net "GND")
	)
	(segment
		(start 25.654 -374.523)
		(end 25.654 -374.142)
		(width 0.508)
		(layer "F.Cu")
		(net "GND")
	)
	(segment
		(start 43.079924 -42.579798)
		(end 43.079924 -43.659806)
		(width 0.635)
		(layer "F.Cu")
		(net "GND")
	)
	(segment
		(start 33.5788 -361.8992)
		(end 33.5788 -361.944412)
		(width 0.508)
		(layer "F.Cu")
		(net "GND")
	)
	(segment
		(start 41.143174 -144.999964)
		(end 45.499782 -144.999964)
		(width 0.635)
		(layer "F.Cu")
		(net "GND")
	)
	(segment
		(start 14.1351 -262.7249)
		(end 13.843 -263.017)
		(width 0.508)
		(layer "F.Cu")
		(net "GND")
	)
	(segment
		(start 40.999918 -463.049874)
		(end 40.999918 -468.168482)
		(width 0.635)
		(layer "F.Cu")
		(net "GND")
	)
	(segment
		(start 45.83811 -159.64789)
		(end 45.847 -159.639)
		(width 0.508)
		(layer "F.Cu")
		(net "GND")
	)
	(segment
		(start 19.9644 -146.7866)
		(end 20.182332 -147.004532)
		(width 0.508)
		(layer "F.Cu")
		(net "GND")
	)
	(segment
		(start 39.56685 -355.969316)
		(end 39.56685 -354.89515)
		(width 0.508)
		(layer "F.Cu")
		(net "GND")
	)
	(segment
		(start 23.876 -362.6612)
		(end 24.2824 -362.2548)
		(width 0.508)
		(layer "F.Cu")
		(net "GND")
	)
	(segment
		(start 32.843724 -174.76851)
		(end 32.843724 -175.65751)
		(width 0.508)
		(layer "F.Cu")
		(net "GND")
	)
	(segment
		(start 45.500036 -15.643352)
		(end 45.500036 -19.99996)
		(width 0.635)
		(layer "F.Cu")
		(net "GND")
	)
	(segment
		(start 40.539924 -47.659798)
		(end 40.539924 -48.739806)
		(width 0.635)
		(layer "F.Cu")
		(net "GND")
	)
	(segment
		(start 7.9756 -418.6428)
		(end 7.7597 -418.8587)
		(width 0.508)
		(layer "F.Cu")
		(net "GND")
	)
	(segment
		(start 2.972816 -377.73991)
		(end 4.040124 -377.73991)
		(width 0.635)
		(layer "F.Cu")
		(net "GND")
	)
	(segment
		(start 42.0624 -160.088326)
		(end 41.85031 -160.088326)
		(width 0.508)
		(layer "F.Cu")
		(net "GND")
	)
	(segment
		(start 8.29945 -77.5589)
		(end 8.29945 -76.073)
		(width 0.508)
		(layer "F.Cu")
		(net "GND")
	)
	(segment
		(start 45.500036 -480.000056)
		(end 49.856644 -480.000056)
		(width 0.635)
		(layer "F.Cu")
		(net "GND")
	)
	(segment
		(start 12.5984 -145.6563)
		(end 13.8557 -145.6563)
		(width 0.508)
		(layer "F.Cu")
		(net "GND")
	)
	(segment
		(start 44.6532 -156.87929)
		(end 43.82389 -156.87929)
		(width 0.508)
		(layer "F.Cu")
		(net "GND")
	)
	(segment
		(start 8.636 -429.641)
		(end 8.219186 -429.224186)
		(width 0.508)
		(layer "F.Cu")
		(net "GND")
	)
	(segment
		(start 40.539924 -43.659806)
		(end 41.619932 -43.659806)
		(width 0.635)
		(layer "F.Cu")
		(net "GND")
	)
	(segment
		(start 17.91589 -176.302924)
		(end 17.91589 -176.54651)
		(width 0.508)
		(layer "F.Cu")
		(net "GND")
	)
	(segment
		(start 38.227 -178.4985)
		(end 37.4015 -178.4985)
		(width 0.508)
		(layer "F.Cu")
		(net "GND")
	)
	(segment
		(start 40.999918 -443.95009)
		(end 46.118526 -443.95009)
		(width 0.635)
		(layer "F.Cu")
		(net "GND")
	)
	(segment
		(start 45.499782 -144.999964)
		(end 49.85639 -144.999964)
		(width 0.635)
		(layer "F.Cu")
		(net "GND")
	)
	(segment
		(start 37.5666 -370.4336)
		(end 37.974778 -370.841778)
		(width 0.508)
		(layer "F.Cu")
		(net "GND")
	)
	(segment
		(start 2.643378 -159.999934)
		(end 6.999986 -159.999934)
		(width 0.635)
		(layer "F.Cu")
		(net "GND")
	)
	(segment
		(start 13.97 -145.542)
		(end 13.8684 -145.6436)
		(width 0.508)
		(layer "F.Cu")
		(net "GND")
	)
	(segment
		(start 41.4782 -176.40427)
		(end 41.4782 -176.8602)
		(width 0.508)
		(layer "F.Cu")
		(net "GND")
	)
	(segment
		(start 22.1996 -147.57527)
		(end 22.24913 -147.6248)
		(width 0.508)
		(layer "F.Cu")
		(net "GND")
	)
	(segment
		(start 45.500036 -480.000056)
		(end 45.500036 -484.356664)
		(width 0.635)
		(layer "F.Cu")
		(net "GND")
	)
	(segment
		(start 40.539924 -45.119798)
		(end 40.539924 -46.199806)
		(width 0.635)
		(layer "F.Cu")
		(net "GND")
	)
	(segment
		(start 32.9565 -362.566712)
		(end 32.9565 -362.7882)
		(width 0.508)
		(layer "F.Cu")
		(net "GND")
	)
	(segment
		(start 20.69211 -143.23949)
		(end 20.2438 -143.6878)
		(width 0.3048)
		(layer "F.Cu")
		(net "GND")
	)
	(segment
		(start 32.73425 -356.096316)
		(end 31.914084 -356.096316)
		(width 0.508)
		(layer "F.Cu")
		(net "GND")
	)
	(segment
		(start 37.211 -361.242102)
		(end 37.196776 -361.256326)
		(width 0.508)
		(layer "F.Cu")
		(net "GND")
	)
	(segment
		(start 37.974778 -370.841778)
		(end 38.020244 -370.841778)
		(width 0.508)
		(layer "F.Cu")
		(net "GND")
	)
	(segment
		(start 39.459916 -46.199806)
		(end 40.539924 -46.199806)
		(width 0.635)
		(layer "F.Cu")
		(net "GND")
	)
	(segment
		(start 40.539924 -48.739806)
		(end 40.539924 -49.819814)
		(width 0.635)
		(layer "F.Cu")
		(net "GND")
	)
	(segment
		(start 6.999986 -155.643326)
		(end 6.999986 -159.999934)
		(width 0.635)
		(layer "F.Cu")
		(net "GND")
	)
	(segment
		(start 37.999924 -40.039798)
		(end 37.999924 -41.119806)
		(width 0.635)
		(layer "F.Cu")
		(net "GND")
	)
	(segment
		(start 37.211 -360.075226)
		(end 37.211 -361.242102)
		(width 0.508)
		(layer "F.Cu")
		(net "GND")
	)
	(segment
		(start 25.654 -374.142)
		(end 26.3398 -373.4562)
		(width 0.508)
		(layer "F.Cu")
		(net "GND")
	)
	(segment
		(start 43.079924 -46.199806)
		(end 44.159932 -46.199806)
		(width 0.635)
		(layer "F.Cu")
		(net "GND")
	)
	(segment
		(start 17.1831 -290.703)
		(end 17.1831 -291.5539)
		(width 0.508)
		(layer "F.Cu")
		(net "GND")
	)
	(segment
		(start 37.999924 -45.119798)
		(end 37.999924 -46.199806)
		(width 0.635)
		(layer "F.Cu")
		(net "GND")
	)
	(segment
		(start 37.17671 -154.373834)
		(end 37.17671 -153.63571)
		(width 0.508)
		(layer "F.Cu")
		(net "GND")
	)
	(segment
		(start 31.36011 -170.915076)
		(end 30.329124 -170.915076)
		(width 0.508)
		(layer "F.Cu")
		(net "GND")
	)
	(segment
		(start 37.211 -354.8634)
		(end 37.211 -354.826316)
		(width 0.508)
		(layer "F.Cu")
		(net "GND")
	)
	(segment
		(start 45.500036 -294.999918)
		(end 49.856644 -294.999918)
		(width 0.635)
		(layer "F.Cu")
		(net "GND")
	)
	(segment
		(start 43.079924 -43.659806)
		(end 44.159932 -43.659806)
		(width 0.635)
		(layer "F.Cu")
		(net "GND")
	)
	(segment
		(start 13.5636 -232.7656)
		(end 13.7922 -232.537)
		(width 0.508)
		(layer "F.Cu")
		(net "GND")
	)
	(segment
		(start 30.89656 -244.602)
		(end 30.89656 -244.08384)
		(width 0.4572)
		(layer "F.Cu")
		(net "GND")
	)
	(segment
		(start 26.227024 -173.96841)
		(end 26.227024 -175.415194)
		(width 0.508)
		(layer "F.Cu")
		(net "GND")
	)
	(segment
		(start 4.040124 -198.419974)
		(end 5.107432 -198.419974)
		(width 0.635)
		(layer "F.Cu")
		(net "GND")
	)
	(segment
		(start 18.161 -186.817)
		(end 18.415 -186.817)
		(width 0.508)
		(layer "F.Cu")
		(net "GND")
	)
	(segment
		(start 33.909 -373.634)
		(end 33.909 -372.6434)
		(width 0.508)
		(layer "F.Cu")
		(net "GND")
	)
	(segment
		(start 17.5514 -176.911)
		(end 17.5514 -177.293524)
		(width 0.508)
		(layer "F.Cu")
		(net "GND")
	)
	(segment
		(start 45.619924 -45.119798)
		(end 45.619924 -46.199806)
		(width 0.635)
		(layer "F.Cu")
		(net "GND")
	)
	(segment
		(start 45.500036 -19.99996)
		(end 45.500036 -24.356568)
		(width 0.635)
		(layer "F.Cu")
		(net "GND")
	)
	(segment
		(start 38.481 -370.713)
		(end 38.149022 -370.713)
		(width 0.508)
		(layer "F.Cu")
		(net "GND")
	)
	(segment
		(start 37.999924 -48.739806)
		(end 37.999924 -49.819814)
		(width 0.635)
		(layer "F.Cu")
		(net "GND")
	)
	(segment
		(start 31.75 -355.219)
		(end 31.877 -355.092)
		(width 0.508)
		(layer "F.Cu")
		(net "GND")
	)
	(segment
		(start 7.7597 -418.8587)
		(end 7.01675 -418.8587)
		(width 0.508)
		(layer "F.Cu")
		(net "GND")
	)
	(segment
		(start 39.231062 -282.231338)
		(end 37.846508 -282.231338)
		(width 0.508)
		(layer "F.Cu")
		(net "GND")
	)
	(segment
		(start 12.4079 -232.7656)
		(end 13.5636 -232.7656)
		(width 0.508)
		(layer "F.Cu")
		(net "GND")
	)
	(segment
		(start 41.999916 -41.119806)
		(end 43.079924 -41.119806)
		(width 0.635)
		(layer "F.Cu")
		(net "GND")
	)
	(segment
		(start 40.999918 -457.931266)
		(end 40.999918 -463.049874)
		(width 0.635)
		(layer "F.Cu")
		(net "GND")
	)
	(segment
		(start 37.592 -353.695)
		(end 37.592 -354.064316)
		(width 0.508)
		(layer "F.Cu")
		(net "GND")
	)
	(segment
		(start 33.565084 -355.092)
		(end 34.2138 -355.740716)
		(width 0.508)
		(layer "F.Cu")
		(net "GND")
	)
	(segment
		(start 38.67531 -151.83231)
		(end 38.67531 -152.748234)
		(width 0.508)
		(layer "F.Cu")
		(net "GND")
	)
	(segment
		(start 43.079924 -40.039798)
		(end 43.079924 -41.119806)
		(width 0.635)
		(layer "F.Cu")
		(net "GND")
	)
	(segment
		(start 27.8511 -360.2609)
		(end 27.8511 -361.0864)
		(width 0.508)
		(layer "F.Cu")
		(net "GND")
	)
	(segment
		(start 29.50845 -214.961216)
		(end 29.50845 -214.17915)
		(width 0.254)
		(layer "F.Cu")
		(net "GND")
	)
	(segment
		(start 32.843724 -173.65091)
		(end 32.843724 -174.76851)
		(width 0.508)
		(layer "F.Cu")
		(net "GND")
	)
	(segment
		(start 28.582366 -241.815366)
		(end 27.94 -241.173)
		(width 0.508)
		(layer "F.Cu")
		(net "GND")
	)
	(segment
		(start 44.539916 -46.199806)
		(end 45.619924 -46.199806)
		(width 0.635)
		(layer "F.Cu")
		(net "GND")
	)
	(segment
		(start 40.999918 -443.95009)
		(end 40.999918 -449.068698)
		(width 0.635)
		(layer "F.Cu")
		(net "GND")
	)
	(segment
		(start 4.040124 -311.740042)
		(end 4.040124 -312.80735)
		(width 0.635)
		(layer "F.Cu")
		(net "GND")
	)
	(segment
		(start 43.079924 -43.659806)
		(end 43.079924 -44.739814)
		(width 0.635)
		(layer "F.Cu")
		(net "GND")
	)
	(segment
		(start 41.8084 -155.4607)
		(end 41.8084 -156.2989)
		(width 0.508)
		(layer "F.Cu")
		(net "GND")
	)
	(segment
		(start 8.5217 -275.2344)
		(end 8.5217 -274.3454)
		(width 0.508)
		(layer "F.Cu")
		(net "GND")
	)
	(segment
		(start 15.494 -64.516)
		(end 15.9258 -64.516)
		(width 0.508)
		(layer "F.Cu")
		(net "GND")
	)
	(segment
		(start 7.9121 -148.5519)
		(end 7.493 -148.971)
		(width 0.508)
		(layer "F.Cu")
		(net "GND")
	)
	(segment
		(start 43.82389 -156.87929)
		(end 43.2054 -156.2608)
		(width 0.508)
		(layer "F.Cu")
		(net "GND")
	)
	(segment
		(start 33.653476 -170.915076)
		(end 34.0614 -171.323)
		(width 0.508)
		(layer "F.Cu")
		(net "GND")
	)
	(segment
		(start 37.338 -185.928)
		(end 37.338 -187.198)
		(width 0.508)
		(layer "F.Cu")
		(net "GND")
	)
	(segment
		(start 22.4028 -248.031)
		(end 22.352 -247.9802)
		(width 0.508)
		(layer "F.Cu")
		(net "GND")
	)
	(segment
		(start 45.847 -159.639)
		(end 45.847 -159.453834)
		(width 0.508)
		(layer "F.Cu")
		(net "GND")
	)
	(segment
		(start 28.582366 -241.882676)
		(end 28.582366 -241.815366)
		(width 0.508)
		(layer "F.Cu")
		(net "GND")
	)
	(segment
		(start 9.4488 -65.2653)
		(end 9.4488 -65.833244)
		(width 0.508)
		(layer "F.Cu")
		(net "GND")
	)
	(segment
		(start 30.4292 -195.3514)
		(end 30.734 -195.0466)
		(width 0.508)
		(layer "F.Cu")
		(net "GND")
	)
	(segment
		(start 36.3093 -147.8915)
		(end 36.9062 -147.8915)
		(width 0.508)
		(layer "F.Cu")
		(net "GND")
	)
	(segment
		(start 18.415 -186.817)
		(end 19.0373 -187.4393)
		(width 0.508)
		(layer "F.Cu")
		(net "GND")
	)
	(segment
		(start 45.500036 -475.643448)
		(end 45.500036 -480.000056)
		(width 0.635)
		(layer "F.Cu")
		(net "GND")
	)
	(segment
		(start 22.71649 -163.227766)
		(end 21.700744 -163.227766)
		(width 0.508)
		(layer "F.Cu")
		(net "GND")
	)
	(segment
		(start 36.919916 -43.659806)
		(end 37.999924 -43.659806)
		(width 0.635)
		(layer "F.Cu")
		(net "GND")
	)
	(segment
		(start 27.94 -360.172)
		(end 27.8511 -360.2609)
		(width 0.508)
		(layer "F.Cu")
		(net "GND")
	)
	(segment
		(start 26.227024 -175.415194)
		(end 25.146254 -176.495964)
		(width 0.508)
		(layer "F.Cu")
		(net "GND")
	)
	(segment
		(start 13.7922 -232.537)
		(end 13.7922 -232.0036)
		(width 0.508)
		(layer "F.Cu")
		(net "GND")
	)
	(segment
		(start 31.877 -355.092)
		(end 33.565084 -355.092)
		(width 0.508)
		(layer "F.Cu")
		(net "GND")
	)
	(segment
		(start 12.939268 -231.150668)
		(end 12.939268 -231.106472)
		(width 0.508)
		(layer "F.Cu")
		(net "GND")
	)
	(segment
		(start 24.2824 -362.2548)
		(end 24.2824 -361.6325)
		(width 0.508)
		(layer "F.Cu")
		(net "GND")
	)
	(segment
		(start 20.32 -373.888)
		(end 20.3708 -373.9388)
		(width 0.508)
		(layer "F.Cu")
		(net "GND")
	)
	(segment
		(start 45.619924 -48.739806)
		(end 46.699932 -48.739806)
		(width 0.635)
		(layer "F.Cu")
		(net "GND")
	)
	(segment
		(start 32.843724 -175.65751)
		(end 32.869124 -175.68291)
		(width 0.508)
		(layer "F.Cu")
		(net "GND")
	)
	(segment
		(start 16.256 -166.5478)
		(end 16.8148 -165.989)
		(width 0.508)
		(layer "F.Cu")
		(net "GND")
	)
	(segment
		(start 19.417538 -288.149538)
		(end 18.796 -287.528)
		(width 0.508)
		(layer "F.Cu")
		(net "GND")
	)
	(segment
		(start 14.7574 -262.7249)
		(end 14.1351 -262.7249)
		(width 0.508)
		(layer "F.Cu")
		(net "GND")
	)
	(segment
		(start 6.999986 -459.999842)
		(end 11.356594 -459.999842)
		(width 0.635)
		(layer "F.Cu")
		(net "GND")
	)
	(segment
		(start 45.619924 -43.659806)
		(end 46.699932 -43.659806)
		(width 0.635)
		(layer "F.Cu")
		(net "GND")
	)
	(segment
		(start 40.999918 -463.049874)
		(end 46.118526 -463.049874)
		(width 0.635)
		(layer "F.Cu")
		(net "GND")
	)
	(segment
		(start 18.288 -146.4056)
		(end 17.7292 -145.8468)
		(width 0.508)
		(layer "F.Cu")
		(net "GND")
	)
	(segment
		(start 31.672784 -353.6442)
		(end 31.672784 -355.141784)
		(width 0.508)
		(layer "F.Cu")
		(net "GND")
	)
	(segment
		(start 33.91789 -168.79189)
		(end 33.91789 -168.168066)
		(width 0.508)
		(layer "F.Cu")
		(net "GND")
	)
	(segment
		(start 37.592 -354.064316)
		(end 37.580316 -354.076)
		(width 0.508)
		(layer "F.Cu")
		(net "GND")
	)
	(segment
		(start 31.672784 -355.141784)
		(end 31.75 -355.219)
		(width 0.508)
		(layer "F.Cu")
		(net "GND")
	)
	(segment
		(start 19.558508 -288.149538)
		(end 19.417538 -288.149538)
		(width 0.508)
		(layer "F.Cu")
		(net "GND")
	)
	(segment
		(start 38.862 -352.425)
		(end 37.592 -353.695)
		(width 0.508)
		(layer "F.Cu")
		(net "GND")
	)
	(segment
		(start 15.1257 -259.2324)
		(end 14.4526 -259.2324)
		(width 0.508)
		(layer "F.Cu")
		(net "GND")
	)
	(segment
		(start 4.499864 -335.643474)
		(end 4.499864 -340.000082)
		(width 0.635)
		(layer "F.Cu")
		(net "GND")
	)
	(segment
		(start 32.869124 -175.68291)
		(end 32.869124 -175.80991)
		(width 0.508)
		(layer "F.Cu")
		(net "GND")
	)
	(segment
		(start 18.9611 -185.6359)
		(end 18.669 -185.928)
		(width 0.508)
		(layer "F.Cu")
		(net "GND")
	)
	(segment
		(start 41.999916 -48.739806)
		(end 43.079924 -48.739806)
		(width 0.635)
		(layer "F.Cu")
		(net "GND")
	)
	(segment
		(start 15.4813 -145.542)
		(end 13.97 -145.542)
		(width 0.508)
		(layer "F.Cu")
		(net "GND")
	)
	(segment
		(start 35.88131 -443.95009)
		(end 40.999918 -443.95009)
		(width 0.635)
		(layer "F.Cu")
		(net "GND")
	)
	(segment
		(start 34.1884 -169.0624)
		(end 33.91789 -168.79189)
		(width 0.508)
		(layer "F.Cu")
		(net "GND")
	)
	(segment
		(start 41.143428 -19.99996)
		(end 45.500036 -19.99996)
		(width 0.635)
		(layer "F.Cu")
		(net "GND")
	)
	(segment
		(start 45.500036 -19.99996)
		(end 49.856644 -19.99996)
		(width 0.635)
		(layer "F.Cu")
		(net "GND")
	)
	(segment
		(start 41.3385 -159.576516)
		(end 41.3385 -159.2072)
		(width 0.508)
		(layer "F.Cu")
		(net "GND")
	)
	(segment
		(start 32.9565 -363.728)
		(end 32.9565 -362.7882)
		(width 0.508)
		(layer "F.Cu")
		(net "GND")
	)
	(segment
		(start 26.416 -269.875)
		(end 26.797 -269.494)
		(width 0.508)
		(layer "F.Cu")
		(net "GND")
	)
	(segment
		(start 40.33139 -337.49996)
		(end 45.449998 -337.49996)
		(width 0.635)
		(layer "F.Cu")
		(net "GND")
	)
	(segment
		(start 37.2618 -121.031)
		(end 36.576 -121.031)
		(width 0.508)
		(layer "F.Cu")
		(net "GND")
	)
	(segment
		(start 26.9748 -140.5382)
		(end 25.9461 -140.5382)
		(width 0.508)
		(layer "F.Cu")
		(net "GND")
	)
	(segment
		(start 37.94125 -173.2915)
		(end 37.94125 -172.05325)
		(width 0.508)
		(layer "F.Cu")
		(net "GND")
	)
	(segment
		(start 45.500036 -294.999918)
		(end 45.500036 -299.356526)
		(width 0.635)
		(layer "F.Cu")
		(net "GND")
	)
	(segment
		(start 15.3289 -45.5422)
		(end 16.129 -45.5422)
		(width 0.508)
		(layer "F.Cu")
		(net "GND")
	)
	(segment
		(start 39.459916 -48.739806)
		(end 40.539924 -48.739806)
		(width 0.635)
		(layer "F.Cu")
		(net "GND")
	)
	(segment
		(start 4.040124 -22.37994)
		(end 4.040124 -23.447248)
		(width 0.635)
		(layer "F.Cu")
		(net "GND")
	)
	(segment
		(start 45.499782 -144.999964)
		(end 45.499782 -149.356572)
		(width 0.635)
		(layer "F.Cu")
		(net "GND")
	)
	(segment
		(start 31.332424 -243.647976)
		(end 31.652972 -243.647976)
		(width 0.4572)
		(layer "F.Cu")
		(net "GND")
	)
	(segment
		(start 43.079924 -48.739806)
		(end 43.079924 -49.819814)
		(width 0.635)
		(layer "F.Cu")
		(net "GND")
	)
	(segment
		(start 9.0043 -87.3125)
		(end 9.9568 -87.3125)
		(width 0.508)
		(layer "F.Cu")
		(net "GND")
	)
	(segment
		(start 41.143428 -294.999918)
		(end 45.500036 -294.999918)
		(width 0.635)
		(layer "F.Cu")
		(net "GND")
	)
	(segment
		(start 9.4488 -65.833244)
		(end 9.144 -66.138044)
		(width 0.508)
		(layer "F.Cu")
		(net "GND")
	)
	(segment
		(start 40.539924 -46.199806)
		(end 41.619932 -46.199806)
		(width 0.635)
		(layer "F.Cu")
		(net "GND")
	)
	(segment
		(start 13.7922 -232.0036)
		(end 12.939268 -231.150668)
		(width 0.508)
		(layer "F.Cu")
		(net "GND")
	)
	(segment
		(start 13.8557 -145.6563)
		(end 13.8684 -145.6436)
		(width 0.508)
		(layer "F.Cu")
		(net "GND")
	)
	(segment
		(start 32.78251 -170.915076)
		(end 33.653476 -170.915076)
		(width 0.508)
		(layer "F.Cu")
		(net "GND")
	)
	(segment
		(start 45.449998 -332.381352)
		(end 45.449998 -337.49996)
		(width 0.635)
		(layer "F.Cu")
		(net "GND")
	)
	(segment
		(start 26.289 -149.352)
		(end 26.1874 -149.2504)
		(width 0.508)
		(layer "F.Cu")
		(net "GND")
	)
	(segment
		(start 7.366 -437.2991)
		(end 7.3914 -437.2737)
		(width 0.508)
		(layer "F.Cu")
		(net "GND")
	)
	(segment
		(start 40.5638 -165.608)
		(end 40.5892 -165.5826)
		(width 0.508)
		(layer "F.Cu")
		(net "GND")
	)
	(segment
		(start 36.5633 -370.4336)
		(end 37.5666 -370.4336)
		(width 0.508)
		(layer "F.Cu")
		(net "GND")
	)
	(segment
		(start 14.969744 -65.097406)
		(end 15.494 -64.57315)
		(width 0.508)
		(layer "F.Cu")
		(net "GND")
	)
	(segment
		(start 45.619924 -41.119806)
		(end 45.619924 -42.199814)
		(width 0.635)
		(layer "F.Cu")
		(net "GND")
	)
	(segment
		(start 37.999924 -47.659798)
		(end 37.999924 -48.739806)
		(width 0.635)
		(layer "F.Cu")
		(net "GND")
	)
	(segment
		(start 19.937476 -176.43729)
		(end 19.937476 -177.25009)
		(width 0.508)
		(layer "F.Cu")
		(net "GND")
	)
	(segment
		(start 40.539924 -41.119806)
		(end 40.539924 -42.199814)
		(width 0.635)
		(layer "F.Cu")
		(net "GND")
	)
	(segment
		(start 43.079924 -41.119806)
		(end 43.079924 -42.199814)
		(width 0.635)
		(layer "F.Cu")
		(net "GND")
	)
	(segment
		(start 26.797 -269.494)
		(end 26.797 -268.8336)
		(width 0.508)
		(layer "F.Cu")
		(net "GND")
	)
	(segment
		(start 25.18918 -376.08256)
		(end 25.18918 -377.39066)
		(width 0.508)
		(layer "F.Cu")
		(net "GND")
	)
	(segment
		(start 45.619924 -41.119806)
		(end 46.699932 -41.119806)
		(width 0.635)
		(layer "F.Cu")
		(net "GND")
	)
	(segment
		(start 45.619924 -46.199806)
		(end 45.619924 -47.279814)
		(width 0.635)
		(layer "F.Cu")
		(net "GND")
	)
	(segment
		(start 44.539916 -41.119806)
		(end 45.619924 -41.119806)
		(width 0.635)
		(layer "F.Cu")
		(net "GND")
	)
	(segment
		(start 26.416 -266.573)
		(end 26.797 -266.954)
		(width 0.508)
		(layer "F.Cu")
		(net "GND")
	)
	(segment
		(start 40.6019 -139.5222)
		(end 40.6019 -140.5255)
		(width 0.508)
		(layer "F.Cu")
		(net "GND")
	)
	(segment
		(start 29.852366 -241.882676)
		(end 29.852366 -241.006376)
		(width 0.508)
		(layer "F.Cu")
		(net "GND")
	)
	(segment
		(start 14.6685 -56.134)
		(end 13.843 -56.134)
		(width 0.508)
		(layer "F.Cu")
		(net "GND")
	)
	(segment
		(start 5.009134 -66.688462)
		(end 5.009134 -67.869562)
		(width 0.508)
		(layer "F.Cu")
		(net "GND")
	)
	(segment
		(start 8.89 -148.5519)
		(end 7.9121 -148.5519)
		(width 0.508)
		(layer "F.Cu")
		(net "GND")
	)
	(segment
		(start 6.999986 -455.643234)
		(end 6.999986 -459.999842)
		(width 0.635)
		(layer "F.Cu")
		(net "GND")
	)
	(segment
		(start 44.448984 -180.366416)
		(end 44.4754 -180.34)
		(width 0.3048)
		(layer "F.Cu")
		(net "GND")
	)
	(segment
		(start 20.69211 -142.5067)
		(end 20.69211 -143.23949)
		(width 0.3048)
		(layer "F.Cu")
		(net "GND")
	)
	(segment
		(start 27.0002 -140.5128)
		(end 26.9748 -140.5382)
		(width 0.508)
		(layer "F.Cu")
		(net "GND")
	)
	(segment
		(start 27.4574 -121.3231)
		(end 26.7081 -121.3231)
		(width 0.508)
		(layer "F.Cu")
		(net "GND")
	)
	(segment
		(start 20.3708 -373.9388)
		(end 20.3708 -375.285)
		(width 0.508)
		(layer "F.Cu")
		(net "GND")
	)
	(segment
		(start 25.7302 -250.444)
		(end 25.7302 -251.6632)
		(width 0.508)
		(layer "F.Cu")
		(net "GND")
	)
	(segment
		(start 13.6652 -256.4257)
		(end 13.6652 -255.5748)
		(width 0.508)
		(layer "F.Cu")
		(net "GND")
	)
	(segment
		(start 16.1798 -277.0124)
		(end 16.1798 -278.9428)
		(width 0.508)
		(layer "F.Cu")
		(net "GND")
	)
	(segment
		(start 20.2438 -143.6878)
		(end 20.096988 -143.6878)
		(width 0.3048)
		(layer "F.Cu")
		(net "GND")
	)
	(segment
		(start 6.7945 -454.1012)
		(end 5.588 -454.1012)
		(width 0.508)
		(layer "F.Cu")
		(net "GND")
	)
	(segment
		(start 26.7081 -121.3231)
		(end 26.3906 -121.0056)
		(width 0.508)
		(layer "F.Cu")
		(net "GND")
	)
	(segment
		(start 23.1775 -367.411)
		(end 22.2758 -367.411)
		(width 0.508)
		(layer "F.Cu")
		(net "GND")
	)
	(segment
		(start 35.88131 -463.049874)
		(end 40.999918 -463.049874)
		(width 0.635)
		(layer "F.Cu")
		(net "GND")
	)
	(segment
		(start 40.5892 -165.5826)
		(end 40.5892 -164.043106)
		(width 0.508)
		(layer "F.Cu")
		(net "GND")
	)
	(segment
		(start 4.499864 -340.000082)
		(end 8.856472 -340.000082)
		(width 0.635)
		(layer "F.Cu")
		(net "GND")
	)
	(segment
		(start 22.733 -373.2022)
		(end 23.9268 -373.2022)
		(width 0.508)
		(layer "F.Cu")
		(net "GND")
	)
	(segment
		(start 44.003976 -365.117126)
		(end 44.03725 -365.083852)
		(width 0.508)
		(layer "F.Cu")
		(net "GND")
	)
	(segment
		(start 39.459916 -43.659806)
		(end 40.539924 -43.659806)
		(width 0.635)
		(layer "F.Cu")
		(net "GND")
	)
	(segment
		(start 39.56685 -354.89515)
		(end 39.5986 -354.8634)
		(width 0.508)
		(layer "F.Cu")
		(net "GND")
	)
	(segment
		(start 23.622 -235.077)
		(end 24.384 -235.839)
		(width 0.508)
		(layer "F.Cu")
		(net "GND")
	)
	(segment
		(start 30.89656 -244.08384)
		(end 31.332424 -243.647976)
		(width 0.4572)
		(layer "F.Cu")
		(net "GND")
	)
	(segment
		(start 45.619924 -40.039798)
		(end 45.619924 -41.119806)
		(width 0.635)
		(layer "F.Cu")
		(net "GND")
	)
	(segment
		(start 40.539924 -40.039798)
		(end 40.539924 -41.119806)
		(width 0.635)
		(layer "F.Cu")
		(net "GND")
	)
	(segment
		(start 41.999916 -43.659806)
		(end 43.079924 -43.659806)
		(width 0.635)
		(layer "F.Cu")
		(net "GND")
	)
	(segment
		(start 19.9644 -145.9357)
		(end 19.9644 -146.7866)
		(width 0.508)
		(layer "F.Cu")
		(net "GND")
	)
	(segment
		(start 18.7706 -141.9479)
		(end 17.8689 -141.9479)
		(width 0.508)
		(layer "F.Cu")
		(net "GND")
	)
	(segment
		(start 44.539916 -48.739806)
		(end 45.619924 -48.739806)
		(width 0.635)
		(layer "F.Cu")
		(net "GND")
	)
	(segment
		(start 26.797 -266.954)
		(end 26.797 -267.6398)
		(width 0.508)
		(layer "F.Cu")
		(net "GND")
	)
	(segment
		(start 16.256 -168.2242)
		(end 16.256 -169.3164)
		(width 0.508)
		(layer "F.Cu")
		(net "GND")
	)
	(segment
		(start 21.1963 -290.322)
		(end 20.359624 -290.322)
		(width 0.508)
		(layer "F.Cu")
		(net "GND")
	)
	(segment
		(start 37.999924 -41.119806)
		(end 39.079932 -41.119806)
		(width 0.635)
		(layer "F.Cu")
		(net "GND")
	)
	(segment
		(start 6.999986 -159.999934)
		(end 6.999986 -164.356542)
		(width 0.635)
		(layer "F.Cu")
		(net "GND")
	)
	(segment
		(start 43.079924 -47.659798)
		(end 43.079924 -48.739806)
		(width 0.635)
		(layer "F.Cu")
		(net "GND")
	)
	(segment
		(start 26.289 -150.8633)
		(end 26.289 -149.352)
		(width 0.508)
		(layer "F.Cu")
		(net "GND")
	)
	(segment
		(start 24.003 -248.031)
		(end 22.4028 -248.031)
		(width 0.508)
		(layer "F.Cu")
		(net "GND")
	)
	(segment
		(start 45.619924 -48.739806)
		(end 45.619924 -49.819814)
		(width 0.635)
		(layer "F.Cu")
		(net "GND")
	)
	(segment
		(start 16.2052 -250.5964)
		(end 15.9004 -250.5964)
		(width 0.508)
		(layer "F.Cu")
		(net "GND")
	)
	(segment
		(start 32.1564 -370.107972)
		(end 32.1564 -371.221)
		(width 0.4064)
		(layer "F.Cu")
		(net "GND")
	)
	(segment
		(start 29.464 -194.0814)
		(end 29.7688 -194.0814)
		(width 0.508)
		(layer "F.Cu")
		(net "GND")
	)
	(segment
		(start 35.6616 -145.4404)
		(end 35.6616 -146.3802)
		(width 0.508)
		(layer "F.Cu")
		(net "GND")
	)
	(segment
		(start 8.094472 -278.627332)
		(end 6.92404 -278.627332)
		(width 0.508)
		(layer "F.Cu")
		(net "GND")
	)
	(segment
		(start 33.5788 -361.944412)
		(end 32.9565 -362.566712)
		(width 0.508)
		(layer "F.Cu")
		(net "GND")
	)
	(segment
		(start 39.243 -371.475)
		(end 38.481 -370.713)
		(width 0.508)
		(layer "F.Cu")
		(net "GND")
	)
	(segment
		(start 18.8214 -146.4056)
		(end 18.288 -146.4056)
		(width 0.508)
		(layer "F.Cu")
		(net "GND")
	)
	(segment
		(start 23.749 -375.7295)
		(end 23.749 -376.6058)
		(width 0.508)
		(layer "F.Cu")
		(net "GND")
	)
	(segment
		(start 2.643378 -39.99992)
		(end 6.999986 -39.99992)
		(width 0.635)
		(layer "F.Cu")
		(net "GND")
	)
	(segment
		(start 43.079924 -41.119806)
		(end 44.159932 -41.119806)
		(width 0.635)
		(layer "F.Cu")
		(net "GND")
	)
	(segment
		(start 4.040124 -311.740042)
		(end 5.107432 -311.740042)
		(width 0.635)
		(layer "F.Cu")
		(net "GND")
	)
	(segment
		(start 2.972816 -22.37994)
		(end 4.040124 -22.37994)
		(width 0.635)
		(layer "F.Cu")
		(net "GND")
	)
	(segment
		(start 45.619924 -43.659806)
		(end 45.619924 -44.739814)
		(width 0.635)
		(layer "F.Cu")
		(net "GND")
	)
	(segment
		(start 16.052292 -291.261292)
		(end 16.052292 -290.081462)
		(width 0.508)
		(layer "F.Cu")
		(net "GND")
	)
	(segment
		(start 37.4015 -178.4985)
		(end 37.338 -178.562)
		(width 0.508)
		(layer "F.Cu")
		(net "GND")
	)
	(segment
		(start 16.764 -291.973)
		(end 16.052292 -291.261292)
		(width 0.508)
		(layer "F.Cu")
		(net "GND")
	)
	(segment
		(start 30.6832 -148.629116)
		(end 30.6832 -147.7518)
		(width 0.508)
		(layer "F.Cu")
		(net "GND")
	)
	(segment
		(start 17.91589 -176.54651)
		(end 17.5514 -176.911)
		(width 0.508)
		(layer "F.Cu")
		(net "GND")
	)
	(segment
		(start 41.85031 -160.088326)
		(end 41.3385 -159.576516)
		(width 0.508)
		(layer "F.Cu")
		(net "GND")
	)
	(segment
		(start 17.1831 -291.5539)
		(end 16.764 -291.973)
		(width 0.508)
		(layer "F.Cu")
		(net "GND")
	)
	(segment
		(start 37.999924 -41.119806)
		(end 37.999924 -42.199814)
		(width 0.635)
		(layer "F.Cu")
		(net "GND")
	)
	(segment
		(start 13.7668 -52.7939)
		(end 14.5796 -52.7939)
		(width 0.508)
		(layer "F.Cu")
		(net "GND")
	)
	(segment
		(start 8.219186 -429.224186)
		(end 8.219186 -426.847)
		(width 0.508)
		(layer "F.Cu")
		(net "GND")
	)
	(segment
		(start 4.963668 -435.576472)
		(end 4.963668 -434.471572)
		(width 0.508)
		(layer "F.Cu")
		(net "GND")
	)
	(segment
		(start 43.47845 -180.366416)
		(end 44.448984 -180.366416)
		(width 0.3048)
		(layer "F.Cu")
		(net "GND")
	)
	(segment
		(start 39.459916 -41.119806)
		(end 40.539924 -41.119806)
		(width 0.635)
		(layer "F.Cu")
		(net "GND")
	)
	(segment
		(start 39.2684 -282.194)
		(end 39.231062 -282.231338)
		(width 0.508)
		(layer "F.Cu")
		(net "GND")
	)
	(segment
		(start 40.539924 -41.119806)
		(end 41.619932 -41.119806)
		(width 0.635)
		(layer "F.Cu")
		(net "GND")
	)
	(segment
		(start 4.499864 -340.000082)
		(end 4.499864 -344.35669)
		(width 0.635)
		(layer "F.Cu")
		(net "GND")
	)
	(segment
		(start 15.3289 -41.4782)
		(end 15.748 -41.4782)
		(width 0.508)
		(layer "F.Cu")
		(net "GND")
	)
	(segment
		(start 39.116 -352.425)
		(end 38.862 -352.425)
		(width 0.508)
		(layer "F.Cu")
		(net "GND")
	)
	(segment
		(start 4.040124 -487.780076)
		(end 5.107432 -487.780076)
		(width 0.635)
		(layer "F.Cu")
		(net "GND")
	)
	(segment
		(start 37.94125 -172.05325)
		(end 37.846 -171.958)
		(width 0.508)
		(layer "F.Cu")
		(net "GND")
	)
	(segment
		(start 6.5786 -437.2991)
		(end 7.366 -437.2991)
		(width 0.508)
		(layer "F.Cu")
		(net "GND")
	)
	(segment
		(start 45.83811 -160.368234)
		(end 45.83811 -159.64789)
		(width 0.508)
		(layer "F.Cu")
		(net "GND")
	)
	(segment
		(start 30.329124 -170.915076)
		(end 30.226 -171.0182)
		(width 0.508)
		(layer "F.Cu")
		(net "GND")
	)
	(segment
		(start 4.040124 -377.73991)
		(end 4.040124 -378.807218)
		(width 0.635)
		(layer "F.Cu")
		(net "GND")
	)
	(segment
		(start 38.149022 -370.713)
		(end 38.020244 -370.841778)
		(width 0.508)
		(layer "F.Cu")
		(net "GND")
	)
	(segment
		(start 15.748 -41.4782)
		(end 16.51 -42.2402)
		(width 0.508)
		(layer "F.Cu")
		(net "GND")
	)
	(segment
		(start 31.914084 -356.096316)
		(end 31.7754 -356.235)
		(width 0.508)
		(layer "F.Cu")
		(net "GND")
	)
	(segment
		(start 4.040124 -22.37994)
		(end 5.107432 -22.37994)
		(width 0.635)
		(layer "F.Cu")
		(net "GND")
	)
	(segment
		(start 37.999924 -43.659806)
		(end 37.999924 -44.739814)
		(width 0.635)
		(layer "F.Cu")
		(net "GND")
	)
	(segment
		(start 45.449998 -337.49996)
		(end 45.449998 -342.618568)
		(width 0.635)
		(layer "F.Cu")
		(net "GND")
	)
	(segment
		(start 4.7117 -416.6108)
		(end 1.905 -416.6108)
		(width 0.508)
		(layer "F.Cu")
		(net "GND")
	)
	(segment
		(start 45.619924 -42.579798)
		(end 45.619924 -43.659806)
		(width 0.635)
		(layer "F.Cu")
		(net "GND")
	)
	(segment
		(start 2.972816 -487.780076)
		(end 4.040124 -487.780076)
		(width 0.635)
		(layer "F.Cu")
		(net "GND")
	)
	(segment
		(start 45.499782 -140.643356)
		(end 45.499782 -144.999964)
		(width 0.635)
		(layer "F.Cu")
		(net "GND")
	)
	(segment
		(start 43.079924 -45.119798)
		(end 43.079924 -46.199806)
		(width 0.635)
		(layer "F.Cu")
		(net "GND")
	)
	(via
		(at 1.2192 -90.4748)
		(size 0.7112)
		(drill 0.4064)
		(layers "F.Cu" "B.Cu")
		(net "GND")
	)
	(via
		(at 22.24913 -147.6502)
		(size 0.7112)
		(drill 0.4064)
		(layers "F.Cu" "B.Cu")
		(net "GND")
	)
	(via
		(at 22.2758 -367.411)
		(size 0.7112)
		(drill 0.4064)
		(layers "F.Cu" "B.Cu")
		(net "GND")
	)
	(via
		(at 10.16 -293.624)
		(size 0.7112)
		(drill 0.4064)
		(layers "F.Cu" "B.Cu")
		(net "GND")
	)
	(via
		(at 7.493 -379.9332)
		(size 0.7112)
		(drill 0.4064)
		(layers "F.Cu" "B.Cu")
		(net "GND")
	)
	(via
		(at 27.178 -233.172)
		(size 0.7112)
		(drill 0.4064)
		(layers "F.Cu" "B.Cu")
		(net "GND")
	)
	(via
		(at 6.7818 -401.2692)
		(size 0.7112)
		(drill 0.4064)
		(layers "F.Cu" "B.Cu")
		(net "GND")
	)
	(via
		(at 30.353 -306.197)
		(size 0.7112)
		(drill 0.4064)
		(layers "F.Cu" "B.Cu")
		(net "GND")
	)
	(via
		(at 40.259 -433.07)
		(size 0.7112)
		(drill 0.4064)
		(layers "F.Cu" "B.Cu")
		(net "GND")
	)
	(via
		(at 17.8689 -141.9479)
		(size 0.5588)
		(drill 0.3048)
		(layers "F.Cu" "B.Cu")
		(net "GND")
	)
	(via
		(at 18.5166 -353.9744)
		(size 0.7112)
		(drill 0.4064)
		(layers "F.Cu" "B.Cu")
		(net "GND")
	)
	(via
		(at 48.641 -193.04)
		(size 0.7112)
		(drill 0.4064)
		(layers "F.Cu" "B.Cu")
		(net "GND")
	)
	(via
		(at 3.683 -465.455)
		(size 0.7112)
		(drill 0.4064)
		(layers "F.Cu" "B.Cu")
		(net "GND")
	)
	(via
		(at 29.591 -266.446)
		(size 0.7112)
		(drill 0.4064)
		(layers "F.Cu" "B.Cu")
		(net "GND")
	)
	(via
		(at 4.064 -244.348)
		(size 0.7112)
		(drill 0.4064)
		(layers "F.Cu" "B.Cu")
		(net "GND")
	)
	(via
		(at 11.176 -336.804)
		(size 0.7112)
		(drill 0.4064)
		(layers "F.Cu" "B.Cu")
		(net "GND")
	)
	(via
		(at 46.101 -187.579)
		(size 0.7112)
		(drill 0.4064)
		(layers "F.Cu" "B.Cu")
		(net "GND")
	)
	(via
		(at 19.05 -17.145)
		(size 0.5588)
		(drill 0.3048)
		(layers "F.Cu" "B.Cu")
		(net "GND")
	)
	(via
		(at 42.164 -193.04)
		(size 0.5588)
		(drill 0.3048)
		(layers "F.Cu" "B.Cu")
		(net "GND")
	)
	(via
		(at 51.308 -83.312)
		(size 0.7112)
		(drill 0.4064)
		(layers "F.Cu" "B.Cu")
		(net "GND")
	)
	(via
		(at 40.894 -171.196)
		(size 0.5588)
		(drill 0.3048)
		(layers "F.Cu" "B.Cu")
		(net "GND")
	)
	(via
		(at 31.496 -343.408)
		(size 0.7112)
		(drill 0.4064)
		(layers "F.Cu" "B.Cu")
		(net "GND")
	)
	(via
		(at 26.797 -103.251)
		(size 0.7112)
		(drill 0.4064)
		(layers "F.Cu" "B.Cu")
		(net "GND")
	)
	(via
		(at 30.226 -27.813)
		(size 0.7112)
		(drill 0.4064)
		(layers "F.Cu" "B.Cu")
		(net "GND")
	)
	(via
		(at 9.144 -140.716)
		(size 0.7112)
		(drill 0.4064)
		(layers "F.Cu" "B.Cu")
		(net "GND")
	)
	(via
		(at 46.863 -219.837)
		(size 0.7112)
		(drill 0.4064)
		(layers "F.Cu" "B.Cu")
		(net "GND")
	)
	(via
		(at 39.497 -456.819)
		(size 0.7112)
		(drill 0.4064)
		(layers "F.Cu" "B.Cu")
		(net "GND")
	)
	(via
		(at 29.083 -348.107)
		(size 0.7112)
		(drill 0.4064)
		(layers "F.Cu" "B.Cu")
		(net "GND")
	)
	(via
		(at 3.429 -346.71)
		(size 0.7112)
		(drill 0.4064)
		(layers "F.Cu" "B.Cu")
		(net "GND")
	)
	(via
		(at 1.1938 -116.3828)
		(size 0.7112)
		(drill 0.4064)
		(layers "F.Cu" "B.Cu")
		(net "GND")
	)
	(via
		(at 8.128 -225.044)
		(size 0.7112)
		(drill 0.4064)
		(layers "F.Cu" "B.Cu")
		(net "GND")
	)
	(via
		(at 51.152806 -362.077)
		(size 0.5588)
		(drill 0.3048)
		(layers "F.Cu" "B.Cu")
		(net "GND")
	)
	(via
		(at 6.858 -94.234)
		(size 0.7112)
		(drill 0.4064)
		(layers "F.Cu" "B.Cu")
		(net "GND")
	)
	(via
		(at 9.6266 -398.78)
		(size 0.7112)
		(drill 0.4064)
		(layers "F.Cu" "B.Cu")
		(net "GND")
	)
	(via
		(at 8.9662 -489.0262)
		(size 0.7112)
		(drill 0.4064)
		(layers "F.Cu" "B.Cu")
		(net "GND")
	)
	(via
		(at 26.289 -261.239)
		(size 0.7112)
		(drill 0.4064)
		(layers "F.Cu" "B.Cu")
		(net "GND")
	)
	(via
		(at 50.165 -191.262)
		(size 0.7112)
		(drill 0.4064)
		(layers "F.Cu" "B.Cu")
		(net "GND")
	)
	(via
		(at 38.608 -454.68794)
		(size 0.7112)
		(drill 0.4064)
		(layers "F.Cu" "B.Cu")
		(net "GND")
	)
	(via
		(at 46.99 -11.43)
		(size 0.7112)
		(drill 0.4064)
		(layers "F.Cu" "B.Cu")
		(net "GND")
	)
	(via
		(at 7.493 -148.971)
		(size 0.5588)
		(drill 0.3048)
		(layers "F.Cu" "B.Cu")
		(net "GND")
	)
	(via
		(at 28.067 -264.541)
		(size 0.7112)
		(drill 0.4064)
		(layers "F.Cu" "B.Cu")
		(net "GND")
	)
	(via
		(at 1.524 -164.084)
		(size 0.7112)
		(drill 0.4064)
		(layers "F.Cu" "B.Cu")
		(net "GND")
	)
	(via
		(at 10.2362 -432.7906)
		(size 0.5588)
		(drill 0.3048)
		(layers "F.Cu" "B.Cu")
		(net "GND")
	)
	(via
		(at 30.353 -192.405)
		(size 0.5588)
		(drill 0.3048)
		(layers "F.Cu" "B.Cu")
		(net "GND")
	)
	(via
		(at 24.384 -149.352)
		(size 0.5588)
		(drill 0.3048)
		(layers "F.Cu" "B.Cu")
		(net "GND")
	)
	(via
		(at 48.895 -422.656)
		(size 0.7112)
		(drill 0.4064)
		(layers "F.Cu" "B.Cu")
		(net "GND")
	)
	(via
		(at 14.859 -280.543)
		(size 0.7112)
		(drill 0.3556)
		(layers "F.Cu" "B.Cu")
		(net "GND")
	)
	(via
		(at 30.3022 -309.7276)
		(size 0.7112)
		(drill 0.4064)
		(layers "F.Cu" "B.Cu")
		(net "GND")
	)
	(via
		(at 42.9514 -183.4134)
		(size 0.7112)
		(drill 0.4064)
		(layers "F.Cu" "B.Cu")
		(net "GND")
	)
	(via
		(at 34.1884 -149.0218)
		(size 0.5588)
		(drill 0.3048)
		(layers "F.Cu" "B.Cu")
		(net "GND")
	)
	(via
		(at 42.1386 -182.1942)
		(size 0.5588)
		(drill 0.3048)
		(layers "F.Cu" "B.Cu")
		(net "GND")
	)
	(via
		(at 51.076606 -134.493)
		(size 0.7112)
		(drill 0.4064)
		(layers "F.Cu" "B.Cu")
		(net "GND")
	)
	(via
		(at 38.989 -239.014)
		(size 0.7112)
		(drill 0.4064)
		(layers "F.Cu" "B.Cu")
		(net "GND")
	)
	(via
		(at 47.498 -226.314)
		(size 0.7112)
		(drill 0.4064)
		(layers "F.Cu" "B.Cu")
		(net "GND")
	)
	(via
		(at 7.8232 -356.5906)
		(size 0.7112)
		(drill 0.4064)
		(layers "F.Cu" "B.Cu")
		(net "GND")
	)
	(via
		(at 8.001 -310.388)
		(size 0.7112)
		(drill 0.4064)
		(layers "F.Cu" "B.Cu")
		(net "GND")
	)
	(via
		(at 13.7668 -56.0578)
		(size 0.5588)
		(drill 0.3048)
		(layers "F.Cu" "B.Cu")
		(net "GND")
	)
	(via
		(at 37.465 -327.152)
		(size 0.7112)
		(drill 0.4064)
		(layers "F.Cu" "B.Cu")
		(net "GND")
	)
	(via
		(at 22.098 -253.365)
		(size 0.7112)
		(drill 0.4064)
		(layers "F.Cu" "B.Cu")
		(net "GND")
	)
	(via
		(at 28.321 -259.08)
		(size 0.7112)
		(drill 0.4064)
		(layers "F.Cu" "B.Cu")
		(net "GND")
	)
	(via
		(at 2.413 -204.216)
		(size 0.7112)
		(drill 0.4064)
		(layers "F.Cu" "B.Cu")
		(net "GND")
	)
	(via
		(at 26.67 -13.97)
		(size 0.7112)
		(drill 0.4064)
		(layers "F.Cu" "B.Cu")
		(net "GND")
	)
	(via
		(at 49.403 -279.527)
		(size 0.7112)
		(drill 0.4064)
		(layers "F.Cu" "B.Cu")
		(net "GND")
	)
	(via
		(at 35.941 -424.942)
		(size 0.7112)
		(drill 0.4064)
		(layers "F.Cu" "B.Cu")
		(net "GND")
	)
	(via
		(at 23.8252 -343.8906)
		(size 0.7112)
		(drill 0.4064)
		(layers "F.Cu" "B.Cu")
		(net "GND")
	)
	(via
		(at 32.893 -198.628)
		(size 0.7112)
		(drill 0.4064)
		(layers "F.Cu" "B.Cu")
		(net "GND")
	)
	(via
		(at 20.701 -351.028)
		(size 0.7112)
		(drill 0.4064)
		(layers "F.Cu" "B.Cu")
		(net "GND")
	)
	(via
		(at 1.347216 -134.3406)
		(size 0.5588)
		(drill 0.3048)
		(layers "F.Cu" "B.Cu")
		(net "GND")
	)
	(via
		(at 1.547876 -65.278)
		(size 0.7112)
		(drill 0.4064)
		(layers "F.Cu" "B.Cu")
		(net "GND")
	)
	(via
		(at 16.764 -291.973)
		(size 0.7112)
		(drill 0.4064)
		(layers "F.Cu" "B.Cu")
		(net "GND")
	)
	(via
		(at 51.308 -154.305)
		(size 0.7112)
		(drill 0.4064)
		(layers "F.Cu" "B.Cu")
		(net "GND")
	)
	(via
		(at 6.731 -111.76)
		(size 0.7112)
		(drill 0.4064)
		(layers "F.Cu" "B.Cu")
		(net "GND")
	)
	(via
		(at 49.276 -14.097)
		(size 0.7112)
		(drill 0.4064)
		(layers "F.Cu" "B.Cu")
		(net "GND")
	)
	(via
		(at 51.308 -194.31)
		(size 0.7112)
		(drill 0.4064)
		(layers "F.Cu" "B.Cu")
		(net "GND")
	)
	(via
		(at 9.9822 -45.9994)
		(size 0.5588)
		(drill 0.3048)
		(layers "F.Cu" "B.Cu")
		(net "GND")
	)
	(via
		(at 11.303 -465.709)
		(size 0.7112)
		(drill 0.4064)
		(layers "F.Cu" "B.Cu")
		(net "GND")
	)
	(via
		(at 29.337 -236.22)
		(size 0.7112)
		(drill 0.4064)
		(layers "F.Cu" "B.Cu")
		(net "GND")
	)
	(via
		(at 10.9982 -418.2364)
		(size 0.5588)
		(drill 0.3048)
		(layers "F.Cu" "B.Cu")
		(net "GND")
	)
	(via
		(at 34.29 -233.172)
		(size 0.7112)
		(drill 0.4064)
		(layers "F.Cu" "B.Cu")
		(net "GND")
	)
	(via
		(at 32.258 -32.766)
		(size 0.7112)
		(drill 0.3556)
		(layers "F.Cu" "B.Cu")
		(net "GND")
	)
	(via
		(at 46.1772 -93.726)
		(size 0.7112)
		(drill 0.4064)
		(layers "F.Cu" "B.Cu")
		(net "GND")
	)
	(via
		(at 38.608 -438.30494)
		(size 0.7112)
		(drill 0.4064)
		(layers "F.Cu" "B.Cu")
		(net "GND")
	)
	(via
		(at 31.75 -192.659)
		(size 0.7112)
		(drill 0.4064)
		(layers "F.Cu" "B.Cu")
		(net "GND")
	)
	(via
		(at 18.14703 -135.176768)
		(size 0.5588)
		(drill 0.3048)
		(layers "F.Cu" "B.Cu")
		(net "GND")
	)
	(via
		(at 6.0452 -104.3178)
		(size 0.7112)
		(drill 0.4064)
		(layers "F.Cu" "B.Cu")
		(net "GND")
	)
	(via
		(at 3.048 -328.676)
		(size 0.7112)
		(drill 0.4064)
		(layers "F.Cu" "B.Cu")
		(net "GND")
	)
	(via
		(at 49.657 -187.706)
		(size 0.7112)
		(drill 0.4064)
		(layers "F.Cu" "B.Cu")
		(net "GND")
	)
	(via
		(at 38.020244 -370.841778)
		(size 0.7112)
		(drill 0.4064)
		(layers "F.Cu" "B.Cu")
		(net "GND")
	)
	(via
		(at 51.308 -74.93)
		(size 0.7112)
		(drill 0.4064)
		(layers "F.Cu" "B.Cu")
		(net "GND")
	)
	(via
		(at 43.942 -274.828)
		(size 0.7112)
		(drill 0.4064)
		(layers "F.Cu" "B.Cu")
		(net "GND")
	)
	(via
		(at 23.876 -340.36)
		(size 0.7112)
		(drill 0.4064)
		(layers "F.Cu" "B.Cu")
		(net "GND")
	)
	(via
		(at 7.112 -405.5872)
		(size 0.5588)
		(drill 0.3048)
		(layers "F.Cu" "B.Cu")
		(net "GND")
	)
	(via
		(at 32.9692 -176.9872)
		(size 0.7112)
		(drill 0.4064)
		(layers "F.Cu" "B.Cu")
		(net "GND")
	)
	(via
		(at 4.064 -265.684)
		(size 0.7112)
		(drill 0.4064)
		(layers "F.Cu" "B.Cu")
		(net "GND")
	)
	(via
		(at 50.8 -19.05)
		(size 0.7112)
		(drill 0.4064)
		(layers "F.Cu" "B.Cu")
		(net "GND")
	)
	(via
		(at 26.416 -257.556)
		(size 0.7112)
		(drill 0.4064)
		(layers "F.Cu" "B.Cu")
		(net "GND")
	)
	(via
		(at 1.420876 -220.726)
		(size 0.7112)
		(drill 0.4064)
		(layers "F.Cu" "B.Cu")
		(net "GND")
	)
	(via
		(at 1.347216 -421.386)
		(size 0.7112)
		(drill 0.4064)
		(layers "F.Cu" "B.Cu")
		(net "GND")
	)
	(via
		(at 14.097 -242.697)
		(size 0.7112)
		(drill 0.4064)
		(layers "F.Cu" "B.Cu")
		(net "GND")
	)
	(via
		(at 37.338 -134.5946)
		(size 0.5588)
		(drill 0.3048)
		(layers "F.Cu" "B.Cu")
		(net "GND")
	)
	(via
		(at 43.434 -262.255)
		(size 0.7112)
		(drill 0.4064)
		(layers "F.Cu" "B.Cu")
		(net "GND")
	)
	(via
		(at 48.895 -213.233)
		(size 0.7112)
		(drill 0.4064)
		(layers "F.Cu" "B.Cu")
		(net "GND")
	)
	(via
		(at 48.8696 -102.0826)
		(size 0.7112)
		(drill 0.4064)
		(layers "F.Cu" "B.Cu")
		(net "GND")
	)
	(via
		(at 50.292 -440.817)
		(size 0.7112)
		(drill 0.4064)
		(layers "F.Cu" "B.Cu")
		(net "GND")
	)
	(via
		(at 29.2608 -199.1868)
		(size 0.7112)
		(drill 0.4064)
		(layers "F.Cu" "B.Cu")
		(net "GND")
	)
	(via
		(at 1.347216 -306.832)
		(size 0.7112)
		(drill 0.4064)
		(layers "F.Cu" "B.Cu")
		(net "GND")
	)
	(via
		(at 49.1998 -151.13)
		(size 0.7112)
		(drill 0.4064)
		(layers "F.Cu" "B.Cu")
		(net "GND")
	)
	(via
		(at 4.064 -262.128)
		(size 0.7112)
		(drill 0.4064)
		(layers "F.Cu" "B.Cu")
		(net "GND")
	)
	(via
		(at 26.67 -36.322)
		(size 0.7112)
		(drill 0.4064)
		(layers "F.Cu" "B.Cu")
		(net "GND")
	)
	(via
		(at 1.27 -62.865)
		(size 0.7112)
		(drill 0.4064)
		(layers "F.Cu" "B.Cu")
		(net "GND")
	)
	(via
		(at 1.524 -318.008)
		(size 0.7112)
		(drill 0.4064)
		(layers "F.Cu" "B.Cu")
		(net "GND")
	)
	(via
		(at 10.16 -189.611)
		(size 0.7112)
		(drill 0.4064)
		(layers "F.Cu" "B.Cu")
		(net "GND")
	)
	(via
		(at 41.402 -264.795)
		(size 0.5588)
		(drill 0.3048)
		(layers "F.Cu" "B.Cu")
		(net "GND")
	)
	(via
		(at 23.1902 -146.558)
		(size 0.5588)
		(drill 0.3048)
		(layers "F.Cu" "B.Cu")
		(net "GND")
	)
	(via
		(at 25.273 -332.74)
		(size 0.7112)
		(drill 0.4064)
		(layers "F.Cu" "B.Cu")
		(net "GND")
	)
	(via
		(at 2.159 -314.198)
		(size 0.7112)
		(drill 0.4064)
		(layers "F.Cu" "B.Cu")
		(net "GND")
	)
	(via
		(at 9.271 -482.727)
		(size 0.7112)
		(drill 0.4064)
		(layers "F.Cu" "B.Cu")
		(net "GND")
	)
	(via
		(at 44.6532 -156.87929)
		(size 0.7112)
		(drill 0.4064)
		(layers "F.Cu" "B.Cu")
		(net "GND")
	)
	(via
		(at 29.591 -263.017)
		(size 0.7112)
		(drill 0.4064)
		(layers "F.Cu" "B.Cu")
		(net "GND")
	)
	(via
		(at 1.524 -179.451)
		(size 0.7112)
		(drill 0.4064)
		(layers "F.Cu" "B.Cu")
		(net "GND")
	)
	(via
		(at 12.459462 -495.743738)
		(size 0.7112)
		(drill 0.4064)
		(layers "F.Cu" "B.Cu")
		(net "GND")
	)
	(via
		(at 1.143 -217.805)
		(size 0.7112)
		(drill 0.4064)
		(layers "F.Cu" "B.Cu")
		(net "GND")
	)
	(via
		(at 29.591 -269.875)
		(size 0.7112)
		(drill 0.4064)
		(layers "F.Cu" "B.Cu")
		(net "GND")
	)
	(via
		(at 44.264072 -431.06594)
		(size 0.7112)
		(drill 0.4064)
		(layers "F.Cu" "B.Cu")
		(net "GND")
	)
	(via
		(at 9.2456 -386.9436)
		(size 0.5588)
		(drill 0.3048)
		(layers "F.Cu" "B.Cu")
		(net "GND")
	)
	(via
		(at 48.8696 -134.4676)
		(size 0.7112)
		(drill 0.4064)
		(layers "F.Cu" "B.Cu")
		(net "GND")
	)
	(via
		(at 24.13 -11.43)
		(size 0.7112)
		(drill 0.4064)
		(layers "F.Cu" "B.Cu")
		(net "GND")
	)
	(via
		(at 45.847 -159.453834)
		(size 0.7112)
		(drill 0.4064)
		(layers "F.Cu" "B.Cu")
		(net "GND")
	)
	(via
		(at 21.463 -14.351)
		(size 0.5588)
		(drill 0.3048)
		(layers "F.Cu" "B.Cu")
		(net "GND")
	)
	(via
		(at 44.8818 -488.6706)
		(size 0.5588)
		(drill 0.3048)
		(layers "F.Cu" "B.Cu")
		(net "GND")
	)
	(via
		(at 8.4328 -119.1006)
		(size 0.5588)
		(drill 0.3048)
		(layers "F.Cu" "B.Cu")
		(net "GND")
	)
	(via
		(at 1.166876 -477.139)
		(size 0.7112)
		(drill 0.4064)
		(layers "F.Cu" "B.Cu")
		(net "GND")
	)
	(via
		(at 27.0002 -140.5128)
		(size 0.5588)
		(drill 0.3048)
		(layers "F.Cu" "B.Cu")
		(net "GND")
	)
	(via
		(at 51.308 -218.313)
		(size 0.5588)
		(drill 0.3048)
		(layers "F.Cu" "B.Cu")
		(net "GND")
	)
	(via
		(at 44.196 -14.097)
		(size 0.7112)
		(drill 0.4064)
		(layers "F.Cu" "B.Cu")
		(net "GND")
	)
	(via
		(at 34.798 -363.0168)
		(size 0.7112)
		(drill 0.4064)
		(layers "F.Cu" "B.Cu")
		(net "GND")
	)
	(via
		(at 16.256 -4.318)
		(size 0.7112)
		(drill 0.4064)
		(layers "F.Cu" "B.Cu")
		(net "GND")
	)
	(via
		(at 1.293876 -119.253)
		(size 0.7112)
		(drill 0.4064)
		(layers "F.Cu" "B.Cu")
		(net "GND")
	)
	(via
		(at 48.895 -424.307)
		(size 0.7112)
		(drill 0.4064)
		(layers "F.Cu" "B.Cu")
		(net "GND")
	)
	(via
		(at 11.811 -468.376)
		(size 0.7112)
		(drill 0.4064)
		(layers "F.Cu" "B.Cu")
		(net "GND")
	)
	(via
		(at 24.638 -381.7874)
		(size 0.7112)
		(drill 0.4064)
		(layers "F.Cu" "B.Cu")
		(net "GND")
	)
	(via
		(at 46.863 -179.959)
		(size 0.7112)
		(drill 0.4064)
		(layers "F.Cu" "B.Cu")
		(net "GND")
	)
	(via
		(at 45.6692 -239.1156)
		(size 0.5588)
		(drill 0.3048)
		(layers "F.Cu" "B.Cu")
		(net "GND")
	)
	(via
		(at 4.191 -44.45)
		(size 0.7112)
		(drill 0.4064)
		(layers "F.Cu" "B.Cu")
		(net "GND")
	)
	(via
		(at 48.895 -415.036)
		(size 0.7112)
		(drill 0.4064)
		(layers "F.Cu" "B.Cu")
		(net "GND")
	)
	(via
		(at 2.182876 -1.651)
		(size 0.7112)
		(drill 0.4064)
		(layers "F.Cu" "B.Cu")
		(net "GND")
	)
	(via
		(at 4.572 -224.536)
		(size 0.7112)
		(drill 0.4064)
		(layers "F.Cu" "B.Cu")
		(net "GND")
	)
	(via
		(at 42.291 -162.56)
		(size 0.7112)
		(drill 0.3556)
		(layers "F.Cu" "B.Cu")
		(net "GND")
	)
	(via
		(at 45.375576 -305.439826)
		(size 0.7112)
		(drill 0.4064)
		(layers "F.Cu" "B.Cu")
		(net "GND")
	)
	(via
		(at 35.179 -467.233)
		(size 0.7112)
		(drill 0.4064)
		(layers "F.Cu" "B.Cu")
		(net "GND")
	)
	(via
		(at 4.7244 -63.2714)
		(size 0.7112)
		(drill 0.3556)
		(layers "F.Cu" "B.Cu")
		(net "GND")
	)
	(via
		(at 26.289 -272.669)
		(size 0.7112)
		(drill 0.4064)
		(layers "F.Cu" "B.Cu")
		(net "GND")
	)
	(via
		(at 32.4358 -30.2768)
		(size 0.7112)
		(drill 0.4064)
		(layers "F.Cu" "B.Cu")
		(net "GND")
	)
	(via
		(at 1.651 -330.708)
		(size 0.7112)
		(drill 0.4064)
		(layers "F.Cu" "B.Cu")
		(net "GND")
	)
	(via
		(at 44.45 -268.986)
		(size 0.7112)
		(drill 0.4064)
		(layers "F.Cu" "B.Cu")
		(net "GND")
	)
	(via
		(at 39.751 -225.806)
		(size 0.7112)
		(drill 0.4064)
		(layers "F.Cu" "B.Cu")
		(net "GND")
	)
	(via
		(at 51.2318 -352.6282)
		(size 0.5588)
		(drill 0.3048)
		(layers "F.Cu" "B.Cu")
		(net "GND")
	)
	(via
		(at 1.905 -349.631)
		(size 0.7112)
		(drill 0.4064)
		(layers "F.Cu" "B.Cu")
		(net "GND")
	)
	(via
		(at 46.99 -214.249)
		(size 0.7112)
		(drill 0.4064)
		(layers "F.Cu" "B.Cu")
		(net "GND")
	)
	(via
		(at 44.323 -36.449)
		(size 0.7112)
		(drill 0.4064)
		(layers "F.Cu" "B.Cu")
		(net "GND")
	)
	(via
		(at 20.182332 -147.004532)
		(size 0.7112)
		(drill 0.4064)
		(layers "F.Cu" "B.Cu")
		(net "GND")
	)
	(via
		(at 14.7574 -370.6622)
		(size 0.7112)
		(drill 0.4064)
		(layers "F.Cu" "B.Cu")
		(net "GND")
	)
	(via
		(at 51.308 -89.662)
		(size 0.7112)
		(drill 0.4064)
		(layers "F.Cu" "B.Cu")
		(net "GND")
	)
	(via
		(at 51.308 -263.398)
		(size 0.5588)
		(drill 0.3048)
		(layers "F.Cu" "B.Cu")
		(net "GND")
	)
	(via
		(at 1.166876 -47.625)
		(size 0.7112)
		(drill 0.4064)
		(layers "F.Cu" "B.Cu")
		(net "GND")
	)
	(via
		(at 34.29 -17.78)
		(size 0.7112)
		(drill 0.4064)
		(layers "F.Cu" "B.Cu")
		(net "GND")
	)
	(via
		(at 2.54 -206.121)
		(size 0.7112)
		(drill 0.4064)
		(layers "F.Cu" "B.Cu")
		(net "GND")
	)
	(via
		(at 51.308 -86.36)
		(size 0.7112)
		(drill 0.4064)
		(layers "F.Cu" "B.Cu")
		(net "GND")
	)
	(via
		(at 5.08 -176.784)
		(size 0.7112)
		(drill 0.4064)
		(layers "F.Cu" "B.Cu")
		(net "GND")
	)
	(via
		(at 50.8 -30.48)
		(size 0.7112)
		(drill 0.4064)
		(layers "F.Cu" "B.Cu")
		(net "GND")
	)
	(via
		(at 15.748 -476.758)
		(size 0.5588)
		(drill 0.3048)
		(layers "F.Cu" "B.Cu")
		(net "GND")
	)
	(via
		(at 24.397462 -229.424738)
		(size 0.7112)
		(drill 0.4064)
		(layers "F.Cu" "B.Cu")
		(net "GND")
	)
	(via
		(at 45.72 -243.9416)
		(size 0.5588)
		(drill 0.3048)
		(layers "F.Cu" "B.Cu")
		(net "GND")
	)
	(via
		(at 47.7266 -199.4662)
		(size 0.7112)
		(drill 0.4064)
		(layers "F.Cu" "B.Cu")
		(net "GND")
	)
	(via
		(at 8.509 -242.062)
		(size 0.7112)
		(drill 0.4064)
		(layers "F.Cu" "B.Cu")
		(net "GND")
	)
	(via
		(at 25.146 -242.062)
		(size 0.7112)
		(drill 0.4064)
		(layers "F.Cu" "B.Cu")
		(net "GND")
	)
	(via
		(at 34.29 -247.777)
		(size 0.7112)
		(drill 0.4064)
		(layers "F.Cu" "B.Cu")
		(net "GND")
	)
	(via
		(at 14.732 -306.324)
		(size 0.7112)
		(drill 0.4064)
		(layers "F.Cu" "B.Cu")
		(net "GND")
	)
	(via
		(at 51.308 -148.844)
		(size 0.7112)
		(drill 0.4064)
		(layers "F.Cu" "B.Cu")
		(net "GND")
	)
	(via
		(at 39.751 -452.628)
		(size 0.7112)
		(drill 0.4064)
		(layers "F.Cu" "B.Cu")
		(net "GND")
	)
	(via
		(at 21.717 -229.362)
		(size 0.7112)
		(drill 0.4064)
		(layers "F.Cu" "B.Cu")
		(net "GND")
	)
	(via
		(at 48.7426 -136.7028)
		(size 0.7112)
		(drill 0.4064)
		(layers "F.Cu" "B.Cu")
		(net "GND")
	)
	(via
		(at 51.054 -277.622)
		(size 0.7112)
		(drill 0.4064)
		(layers "F.Cu" "B.Cu")
		(net "GND")
	)
	(via
		(at 5.842 -172.085)
		(size 0.7112)
		(drill 0.4064)
		(layers "F.Cu" "B.Cu")
		(net "GND")
	)
	(via
		(at 3.429 -58.547)
		(size 0.7112)
		(drill 0.4064)
		(layers "F.Cu" "B.Cu")
		(net "GND")
	)
	(via
		(at 29.845 -226.822)
		(size 0.7112)
		(drill 0.4064)
		(layers "F.Cu" "B.Cu")
		(net "GND")
	)
	(via
		(at 49.149 -261.366)
		(size 0.7112)
		(drill 0.4064)
		(layers "F.Cu" "B.Cu")
		(net "GND")
	)
	(via
		(at 41.275 -450.342)
		(size 0.7112)
		(drill 0.4064)
		(layers "F.Cu" "B.Cu")
		(net "GND")
	)
	(via
		(at 17.6276 -356.3366)
		(size 0.7112)
		(drill 0.4064)
		(layers "F.Cu" "B.Cu")
		(net "GND")
	)
	(via
		(at 37.465 -296.037)
		(size 0.7112)
		(drill 0.4064)
		(layers "F.Cu" "B.Cu")
		(net "GND")
	)
	(via
		(at 1.293876 -152.4)
		(size 0.7112)
		(drill 0.4064)
		(layers "F.Cu" "B.Cu")
		(net "GND")
	)
	(via
		(at 19.632422 -286.951166)
		(size 0.7112)
		(drill 0.4064)
		(layers "F.Cu" "B.Cu")
		(net "GND")
	)
	(via
		(at 11.684 -184.404)
		(size 0.7112)
		(drill 0.4064)
		(layers "F.Cu" "B.Cu")
		(net "GND")
	)
	(via
		(at 1.293876 -487.934)
		(size 0.7112)
		(drill 0.4064)
		(layers "F.Cu" "B.Cu")
		(net "GND")
	)
	(via
		(at 9.652 -208.28)
		(size 0.7112)
		(drill 0.4064)
		(layers "F.Cu" "B.Cu")
		(net "GND")
	)
	(via
		(at 29.477462 -229.424738)
		(size 0.7112)
		(drill 0.4064)
		(layers "F.Cu" "B.Cu")
		(net "GND")
	)
	(via
		(at 33.02 -187.071)
		(size 0.7112)
		(drill 0.4064)
		(layers "F.Cu" "B.Cu")
		(net "GND")
	)
	(via
		(at 20.066 -217.678)
		(size 0.7112)
		(drill 0.4064)
		(layers "F.Cu" "B.Cu")
		(net "GND")
	)
	(via
		(at 15.4686 -353.187)
		(size 0.7112)
		(drill 0.4064)
		(layers "F.Cu" "B.Cu")
		(net "GND")
	)
	(via
		(at 15.494 -346.329)
		(size 0.7112)
		(drill 0.4064)
		(layers "F.Cu" "B.Cu")
		(net "GND")
	)
	(via
		(at 3.3274 -491.2106)
		(size 0.7112)
		(drill 0.4064)
		(layers "F.Cu" "B.Cu")
		(net "GND")
	)
	(via
		(at 41.783 -330.073)
		(size 0.7112)
		(drill 0.4064)
		(layers "F.Cu" "B.Cu")
		(net "GND")
	)
	(via
		(at 45.593 -224.536)
		(size 0.5588)
		(drill 0.3048)
		(layers "F.Cu" "B.Cu")
		(net "GND")
	)
	(via
		(at 1.293876 -322.199)
		(size 0.7112)
		(drill 0.4064)
		(layers "F.Cu" "B.Cu")
		(net "GND")
	)
	(via
		(at 8.636 -290.576)
		(size 0.7112)
		(drill 0.4064)
		(layers "F.Cu" "B.Cu")
		(net "GND")
	)
	(via
		(at 48.768 -237.363)
		(size 0.7112)
		(drill 0.4064)
		(layers "F.Cu" "B.Cu")
		(net "GND")
	)
	(via
		(at 29.718 -134.62)
		(size 0.7112)
		(drill 0.4064)
		(layers "F.Cu" "B.Cu")
		(net "GND")
	)
	(via
		(at 33.909 -238.252)
		(size 0.7112)
		(drill 0.4064)
		(layers "F.Cu" "B.Cu")
		(net "GND")
	)
	(via
		(at 11.4046 -442.0362)
		(size 0.7112)
		(drill 0.4064)
		(layers "F.Cu" "B.Cu")
		(net "GND")
	)
	(via
		(at 1.347216 -167.894)
		(size 0.7112)
		(drill 0.4064)
		(layers "F.Cu" "B.Cu")
		(net "GND")
	)
	(via
		(at 15.621 -222.631)
		(size 0.7112)
		(drill 0.4064)
		(layers "F.Cu" "B.Cu")
		(net "GND")
	)
	(via
		(at 40.767 -267.589)
		(size 0.7112)
		(drill 0.4064)
		(layers "F.Cu" "B.Cu")
		(net "GND")
	)
	(via
		(at 11.176 -198.628)
		(size 0.7112)
		(drill 0.4064)
		(layers "F.Cu" "B.Cu")
		(net "GND")
	)
	(via
		(at 44.010072 -451.104)
		(size 0.7112)
		(drill 0.4064)
		(layers "F.Cu" "B.Cu")
		(net "GND")
	)
	(via
		(at 48.6918 -47.371)
		(size 0.7112)
		(drill 0.4064)
		(layers "F.Cu" "B.Cu")
		(net "GND")
	)
	(via
		(at 3.683 -473.329)
		(size 0.7112)
		(drill 0.4064)
		(layers "F.Cu" "B.Cu")
		(net "GND")
	)
	(via
		(at 24.765 -358.648)
		(size 0.7112)
		(drill 0.4064)
		(layers "F.Cu" "B.Cu")
		(net "GND")
	)
	(via
		(at 29.748988 -367.792254)
		(size 0.7112)
		(drill 0.4064)
		(layers "F.Cu" "B.Cu")
		(net "GND")
	)
	(via
		(at 1.420876 -79.248)
		(size 0.7112)
		(drill 0.4064)
		(layers "F.Cu" "B.Cu")
		(net "GND")
	)
	(via
		(at 1.347216 -437.769)
		(size 0.7112)
		(drill 0.4064)
		(layers "F.Cu" "B.Cu")
		(net "GND")
	)
	(via
		(at 26.035 -226.949)
		(size 0.7112)
		(drill 0.4064)
		(layers "F.Cu" "B.Cu")
		(net "GND")
	)
	(via
		(at 38.481 -261.747)
		(size 0.5588)
		(drill 0.3048)
		(layers "F.Cu" "B.Cu")
		(net "GND")
	)
	(via
		(at 23.876 -302.006)
		(size 0.7112)
		(drill 0.4064)
		(layers "F.Cu" "B.Cu")
		(net "GND")
	)
	(via
		(at 35.0266 -43.5356)
		(size 0.7112)
		(drill 0.4064)
		(layers "F.Cu" "B.Cu")
		(net "GND")
	)
	(via
		(at 3.81 -471.1446)
		(size 0.7112)
		(drill 0.4064)
		(layers "F.Cu" "B.Cu")
		(net "GND")
	)
	(via
		(at 50.165 -38.481)
		(size 0.7112)
		(drill 0.4064)
		(layers "F.Cu" "B.Cu")
		(net "GND")
	)
	(via
		(at 22.352 -262.763)
		(size 0.7112)
		(drill 0.3556)
		(layers "F.Cu" "B.Cu")
		(net "GND")
	)
	(via
		(at 39.2684 -282.194)
		(size 0.7112)
		(drill 0.4064)
		(layers "F.Cu" "B.Cu")
		(net "GND")
	)
	(via
		(at 51.435 -215.011)
		(size 0.5588)
		(drill 0.3048)
		(layers "F.Cu" "B.Cu")
		(net "GND")
	)
	(via
		(at 1.166876 -469.9)
		(size 0.7112)
		(drill 0.4064)
		(layers "F.Cu" "B.Cu")
		(net "GND")
	)
	(via
		(at 41.148 -207.645)
		(size 0.5588)
		(drill 0.3048)
		(layers "F.Cu" "B.Cu")
		(net "GND")
	)
	(via
		(at 1.651 -202.946)
		(size 0.7112)
		(drill 0.4064)
		(layers "F.Cu" "B.Cu")
		(net "GND")
	)
	(via
		(at 24.892 -179.832)
		(size 0.5588)
		(drill 0.3048)
		(layers "F.Cu" "B.Cu")
		(net "GND")
	)
	(via
		(at 49.53 -475.996)
		(size 0.7112)
		(drill 0.4064)
		(layers "F.Cu" "B.Cu")
		(net "GND")
	)
	(via
		(at 51.181 -96.012)
		(size 0.7112)
		(drill 0.4064)
		(layers "F.Cu" "B.Cu")
		(net "GND")
	)
	(via
		(at 51.308 -222.25)
		(size 0.5588)
		(drill 0.3048)
		(layers "F.Cu" "B.Cu")
		(net "GND")
	)
	(via
		(at 47.3964 -108.1405)
		(size 0.7112)
		(drill 0.4064)
		(layers "F.Cu" "B.Cu")
		(net "GND")
	)
	(via
		(at 3.683 -25.527)
		(size 0.7112)
		(drill 0.4064)
		(layers "F.Cu" "B.Cu")
		(net "GND")
	)
	(via
		(at 47.244 -287.782)
		(size 0.7112)
		(drill 0.3556)
		(layers "F.Cu" "B.Cu")
		(net "GND")
	)
	(via
		(at 21.844 -38.608)
		(size 0.7112)
		(drill 0.4064)
		(layers "F.Cu" "B.Cu")
		(net "GND")
	)
	(via
		(at 37.973 -13.208)
		(size 0.5588)
		(drill 0.3048)
		(layers "F.Cu" "B.Cu")
		(net "GND")
	)
	(via
		(at 7.112 -179.324)
		(size 0.7112)
		(drill 0.4064)
		(layers "F.Cu" "B.Cu")
		(net "GND")
	)
	(via
		(at 11.684 -488.442)
		(size 0.7112)
		(drill 0.4064)
		(layers "F.Cu" "B.Cu")
		(net "GND")
	)
	(via
		(at 51.308 -67.056)
		(size 0.7112)
		(drill 0.4064)
		(layers "F.Cu" "B.Cu")
		(net "GND")
	)
	(via
		(at 36.83 -11.43)
		(size 0.7112)
		(drill 0.4064)
		(layers "F.Cu" "B.Cu")
		(net "GND")
	)
	(via
		(at 31.75 -186.436)
		(size 0.7112)
		(drill 0.4064)
		(layers "F.Cu" "B.Cu")
		(net "GND")
	)
	(via
		(at 43.561508 -286.904938)
		(size 0.7112)
		(drill 0.4064)
		(layers "F.Cu" "B.Cu")
		(net "GND")
	)
	(via
		(at 3.81 -33.401)
		(size 0.7112)
		(drill 0.4064)
		(layers "F.Cu" "B.Cu")
		(net "GND")
	)
	(via
		(at 51.308 -171.831)
		(size 0.7112)
		(drill 0.4064)
		(layers "F.Cu" "B.Cu")
		(net "GND")
	)
	(via
		(at 36.195 -139.7)
		(size 0.5588)
		(drill 0.3048)
		(layers "F.Cu" "B.Cu")
		(net "GND")
	)
	(via
		(at 1.166876 -242.316)
		(size 0.7112)
		(drill 0.4064)
		(layers "F.Cu" "B.Cu")
		(net "GND")
	)
	(via
		(at 39.116 -26.797)
		(size 0.7112)
		(drill 0.4064)
		(layers "F.Cu" "B.Cu")
		(net "GND")
	)
	(via
		(at 34.925 -222.631)
		(size 0.7112)
		(drill 0.4064)
		(layers "F.Cu" "B.Cu")
		(net "GND")
	)
	(via
		(at 8.2804 -73.787)
		(size 0.5588)
		(drill 0.3048)
		(layers "F.Cu" "B.Cu")
		(net "GND")
	)
	(via
		(at 22.098 -213.233)
		(size 0.7112)
		(drill 0.4064)
		(layers "F.Cu" "B.Cu")
		(net "GND")
	)
	(via
		(at 33.4772 -73.5838)
		(size 0.7112)
		(drill 0.4064)
		(layers "F.Cu" "B.Cu")
		(net "GND")
	)
	(via
		(at 4.572 -186.055)
		(size 0.7112)
		(drill 0.4064)
		(layers "F.Cu" "B.Cu")
		(net "GND")
	)
	(via
		(at 43.18 -280.162)
		(size 0.7112)
		(drill 0.4064)
		(layers "F.Cu" "B.Cu")
		(net "GND")
	)
	(via
		(at 21.2852 -346.9386)
		(size 0.7112)
		(drill 0.4064)
		(layers "F.Cu" "B.Cu")
		(net "GND")
	)
	(via
		(at 49.53 -275.971)
		(size 0.7112)
		(drill 0.4064)
		(layers "F.Cu" "B.Cu")
		(net "GND")
	)
	(via
		(at 1.166876 -450.85)
		(size 0.7112)
		(drill 0.4064)
		(layers "F.Cu" "B.Cu")
		(net "GND")
	)
	(via
		(at 4.064 -251.46)
		(size 0.7112)
		(drill 0.4064)
		(layers "F.Cu" "B.Cu")
		(net "GND")
	)
	(via
		(at 32.004 -242.316)
		(size 0.7112)
		(drill 0.4064)
		(layers "F.Cu" "B.Cu")
		(net "GND")
	)
	(via
		(at 11.176 -340.36)
		(size 0.7112)
		(drill 0.4064)
		(layers "F.Cu" "B.Cu")
		(net "GND")
	)
	(via
		(at 17.4752 -360.1212)
		(size 0.7112)
		(drill 0.4064)
		(layers "F.Cu" "B.Cu")
		(net "GND")
	)
	(via
		(at 45.212 -202.565)
		(size 0.7112)
		(drill 0.4064)
		(layers "F.Cu" "B.Cu")
		(net "GND")
	)
	(via
		(at 17.5514 -177.293524)
		(size 0.7112)
		(drill 0.4064)
		(layers "F.Cu" "B.Cu")
		(net "GND")
	)
	(via
		(at 1.2446 -83.312)
		(size 0.7112)
		(drill 0.4064)
		(layers "F.Cu" "B.Cu")
		(net "GND")
	)
	(via
		(at 30.353 -189.611)
		(size 0.5588)
		(drill 0.3048)
		(layers "F.Cu" "B.Cu")
		(net "GND")
	)
	(via
		(at 43.18 -487.807)
		(size 0.5588)
		(drill 0.3048)
		(layers "F.Cu" "B.Cu")
		(net "GND")
	)
	(via
		(at 26.67 -11.43)
		(size 0.7112)
		(drill 0.4064)
		(layers "F.Cu" "B.Cu")
		(net "GND")
	)
	(via
		(at 18.923 -371.2972)
		(size 0.7112)
		(drill 0.4064)
		(layers "F.Cu" "B.Cu")
		(net "GND")
	)
	(via
		(at 30.819852 -368.813334)
		(size 0.7112)
		(drill 0.4064)
		(layers "F.Cu" "B.Cu")
		(net "GND")
	)
	(via
		(at 30.353 -187.833)
		(size 0.5588)
		(drill 0.3048)
		(layers "F.Cu" "B.Cu")
		(net "GND")
	)
	(via
		(at 9.398 -31.496)
		(size 0.7112)
		(drill 0.4064)
		(layers "F.Cu" "B.Cu")
		(net "GND")
	)
	(via
		(at 46.6344 -448.3354)
		(size 0.7112)
		(drill 0.4064)
		(layers "F.Cu" "B.Cu")
		(net "GND")
	)
	(via
		(at 10.541 -429.768)
		(size 0.5588)
		(drill 0.3048)
		(layers "F.Cu" "B.Cu")
		(net "GND")
	)
	(via
		(at 1.27 -103.759)
		(size 0.7112)
		(drill 0.4064)
		(layers "F.Cu" "B.Cu")
		(net "GND")
	)
	(via
		(at 43.688 -192.405)
		(size 0.7112)
		(drill 0.4064)
		(layers "F.Cu" "B.Cu")
		(net "GND")
	)
	(via
		(at 23.622 -235.077)
		(size 0.7112)
		(drill 0.4064)
		(layers "F.Cu" "B.Cu")
		(net "GND")
	)
	(via
		(at 7.62 -198.628)
		(size 0.7112)
		(drill 0.4064)
		(layers "F.Cu" "B.Cu")
		(net "GND")
	)
	(via
		(at 26.67 -299.974)
		(size 0.5588)
		(drill 0.3048)
		(layers "F.Cu" "B.Cu")
		(net "GND")
	)
	(via
		(at 40.1066 -488.4674)
		(size 0.5588)
		(drill 0.3048)
		(layers "F.Cu" "B.Cu")
		(net "GND")
	)
	(via
		(at 6.8326 -396.0114)
		(size 0.7112)
		(drill 0.4064)
		(layers "F.Cu" "B.Cu")
		(net "GND")
	)
	(via
		(at 11.8364 -391.4394)
		(size 0.7112)
		(drill 0.4064)
		(layers "F.Cu" "B.Cu")
		(net "GND")
	)
	(via
		(at 41.656 -14.097)
		(size 0.7112)
		(drill 0.4064)
		(layers "F.Cu" "B.Cu")
		(net "GND")
	)
	(via
		(at 48.895 -392.049)
		(size 0.7112)
		(drill 0.4064)
		(layers "F.Cu" "B.Cu")
		(net "GND")
	)
	(via
		(at 13.8684 -145.6436)
		(size 0.5588)
		(drill 0.3048)
		(layers "F.Cu" "B.Cu")
		(net "GND")
	)
	(via
		(at 20.066 -364.8456)
		(size 0.7112)
		(drill 0.4064)
		(layers "F.Cu" "B.Cu")
		(net "GND")
	)
	(via
		(at 9.652 -211.836)
		(size 0.7112)
		(drill 0.4064)
		(layers "F.Cu" "B.Cu")
		(net "GND")
	)
	(via
		(at 44.704 -172.466)
		(size 0.7112)
		(drill 0.4064)
		(layers "F.Cu" "B.Cu")
		(net "GND")
	)
	(via
		(at 23.241 -312.166)
		(size 0.7112)
		(drill 0.4064)
		(layers "F.Cu" "B.Cu")
		(net "GND")
	)
	(via
		(at 3.556 -46.736)
		(size 0.7112)
		(drill 0.4064)
		(layers "F.Cu" "B.Cu")
		(net "GND")
	)
	(via
		(at 32.1564 -371.221)
		(size 0.7112)
		(drill 0.4064)
		(layers "F.Cu" "B.Cu")
		(net "GND")
	)
	(via
		(at 29.724096 -368.808)
		(size 0.7112)
		(drill 0.4064)
		(layers "F.Cu" "B.Cu")
		(net "GND")
	)
	(via
		(at 51.308 -146.812)
		(size 0.7112)
		(drill 0.4064)
		(layers "F.Cu" "B.Cu")
		(net "GND")
	)
	(via
		(at 38.0492 -256.2098)
		(size 0.5588)
		(drill 0.3048)
		(layers "F.Cu" "B.Cu")
		(net "GND")
	)
	(via
		(at 51.152806 -271.018)
		(size 0.5588)
		(drill 0.3048)
		(layers "F.Cu" "B.Cu")
		(net "GND")
	)
	(via
		(at 4.064 -217.424)
		(size 0.7112)
		(drill 0.4064)
		(layers "F.Cu" "B.Cu")
		(net "GND")
	)
	(via
		(at 34.8488 -31.3944)
		(size 0.7112)
		(drill 0.4064)
		(layers "F.Cu" "B.Cu")
		(net "GND")
	)
	(via
		(at 26.416 -186.436)
		(size 0.7112)
		(drill 0.3556)
		(layers "F.Cu" "B.Cu")
		(net "GND")
	)
	(via
		(at 41.4274 -248.5644)
		(size 0.5588)
		(drill 0.3048)
		(layers "F.Cu" "B.Cu")
		(net "GND")
	)
	(via
		(at 50.927 -59.69)
		(size 0.7112)
		(drill 0.4064)
		(layers "F.Cu" "B.Cu")
		(net "GND")
	)
	(via
		(at 48.387 -488.696)
		(size 0.7112)
		(drill 0.4064)
		(layers "F.Cu" "B.Cu")
		(net "GND")
	)
	(via
		(at 1.524 -177.292)
		(size 0.7112)
		(drill 0.4064)
		(layers "F.Cu" "B.Cu")
		(net "GND")
	)
	(via
		(at 32.6898 -26.4668)
		(size 0.7112)
		(drill 0.4064)
		(layers "F.Cu" "B.Cu")
		(net "GND")
	)
	(via
		(at 32.766 -196.723)
		(size 0.7112)
		(drill 0.4064)
		(layers "F.Cu" "B.Cu")
		(net "GND")
	)
	(via
		(at 35.2552 -41.1734)
		(size 0.7112)
		(drill 0.4064)
		(layers "F.Cu" "B.Cu")
		(net "GND")
	)
	(via
		(at 48.768 -219.837)
		(size 0.7112)
		(drill 0.4064)
		(layers "F.Cu" "B.Cu")
		(net "GND")
	)
	(via
		(at 39.5986 -354.8634)
		(size 0.5588)
		(drill 0.3048)
		(layers "F.Cu" "B.Cu")
		(net "GND")
	)
	(via
		(at 20.701 -356.616)
		(size 0.7112)
		(drill 0.4064)
		(layers "F.Cu" "B.Cu")
		(net "GND")
	)
	(via
		(at 31.75 -355.219)
		(size 0.5588)
		(drill 0.3048)
		(layers "F.Cu" "B.Cu")
		(net "GND")
	)
	(via
		(at 34.29 -142.621)
		(size 0.5588)
		(drill 0.3048)
		(layers "F.Cu" "B.Cu")
		(net "GND")
	)
	(via
		(at 18.669 -185.928)
		(size 0.5588)
		(drill 0.3048)
		(layers "F.Cu" "B.Cu")
		(net "GND")
	)
	(via
		(at 48.871886 -106.08437)
		(size 0.7112)
		(drill 0.4064)
		(layers "F.Cu" "B.Cu")
		(net "GND")
	)
	(via
		(at 32.7406 -488.5182)
		(size 0.5588)
		(drill 0.3048)
		(layers "F.Cu" "B.Cu")
		(net "GND")
	)
	(via
		(at 48.895 -250.317)
		(size 0.7112)
		(drill 0.4064)
		(layers "F.Cu" "B.Cu")
		(net "GND")
	)
	(via
		(at 45.72 -221.615)
		(size 0.5588)
		(drill 0.3048)
		(layers "F.Cu" "B.Cu")
		(net "GND")
	)
	(via
		(at 39.7002 -140.2334)
		(size 0.5588)
		(drill 0.3048)
		(layers "F.Cu" "B.Cu")
		(net "GND")
	)
	(via
		(at 6.236462 -292.924738)
		(size 0.7112)
		(drill 0.4064)
		(layers "F.Cu" "B.Cu")
		(net "GND")
	)
	(via
		(at 8.636 -375.3104)
		(size 0.7112)
		(drill 0.4064)
		(layers "F.Cu" "B.Cu")
		(net "GND")
	)
	(via
		(at 37.465 -301.244)
		(size 0.7112)
		(drill 0.4064)
		(layers "F.Cu" "B.Cu")
		(net "GND")
	)
	(via
		(at 1.166876 -483.108)
		(size 0.7112)
		(drill 0.4064)
		(layers "F.Cu" "B.Cu")
		(net "GND")
	)
	(via
		(at 8.128 -221.488)
		(size 0.7112)
		(drill 0.4064)
		(layers "F.Cu" "B.Cu")
		(net "GND")
	)
	(via
		(at 50.927 -476.631)
		(size 0.5588)
		(drill 0.3048)
		(layers "F.Cu" "B.Cu")
		(net "GND")
	)
	(via
		(at 22.606 -151.13)
		(size 0.5588)
		(drill 0.3048)
		(layers "F.Cu" "B.Cu")
		(net "GND")
	)
	(via
		(at 1.143 -231.902)
		(size 0.7112)
		(drill 0.4064)
		(layers "F.Cu" "B.Cu")
		(net "GND")
	)
	(via
		(at 16.026892 -30.252162)
		(size 0.7112)
		(drill 0.4064)
		(layers "F.Cu" "B.Cu")
		(net "GND")
	)
	(via
		(at 41.021 -195.072)
		(size 0.5588)
		(drill 0.3048)
		(layers "F.Cu" "B.Cu")
		(net "GND")
	)
	(via
		(at 15.875 -218.948)
		(size 0.7112)
		(drill 0.4064)
		(layers "F.Cu" "B.Cu")
		(net "GND")
	)
	(via
		(at 29.852366 -241.006376)
		(size 0.7112)
		(drill 0.4064)
		(layers "F.Cu" "B.Cu")
		(net "GND")
	)
	(via
		(at 19.8882 -227.0506)
		(size 0.7112)
		(drill 0.4064)
		(layers "F.Cu" "B.Cu")
		(net "GND")
	)
	(via
		(at 38.5826 -480.4156)
		(size 0.5588)
		(drill 0.3048)
		(layers "F.Cu" "B.Cu")
		(net "GND")
	)
	(via
		(at 51.435 -169.164)
		(size 0.5588)
		(drill 0.3048)
		(layers "F.Cu" "B.Cu")
		(net "GND")
	)
	(via
		(at 41.021 -197.612)
		(size 0.5588)
		(drill 0.3048)
		(layers "F.Cu" "B.Cu")
		(net "GND")
	)
	(via
		(at 11.557 -429.26)
		(size 0.5588)
		(drill 0.3048)
		(layers "F.Cu" "B.Cu")
		(net "GND")
	)
	(via
		(at 40.767 -271.018)
		(size 0.7112)
		(drill 0.4064)
		(layers "F.Cu" "B.Cu")
		(net "GND")
	)
	(via
		(at 21.209 -247.0912)
		(size 0.5588)
		(drill 0.3048)
		(layers "F.Cu" "B.Cu")
		(net "GND")
	)
	(via
		(at 12.7 -190.246)
		(size 0.7112)
		(drill 0.4064)
		(layers "F.Cu" "B.Cu")
		(net "GND")
	)
	(via
		(at 3.175 -452.755)
		(size 0.7112)
		(drill 0.4064)
		(layers "F.Cu" "B.Cu")
		(net "GND")
	)
	(via
		(at 47.244 -454.66)
		(size 0.7112)
		(drill 0.4064)
		(layers "F.Cu" "B.Cu")
		(net "GND")
	)
	(via
		(at 33.02 -191.262)
		(size 0.5588)
		(drill 0.3048)
		(layers "F.Cu" "B.Cu")
		(net "GND")
	)
	(via
		(at 31.496 -322.58)
		(size 0.7112)
		(drill 0.4064)
		(layers "F.Cu" "B.Cu")
		(net "GND")
	)
	(via
		(at 3.2766 -448.3608)
		(size 0.7112)
		(drill 0.4064)
		(layers "F.Cu" "B.Cu")
		(net "GND")
	)
	(via
		(at 51.181 -41.91)
		(size 0.5588)
		(drill 0.3048)
		(layers "F.Cu" "B.Cu")
		(net "GND")
	)
	(via
		(at 41.1734 -485.648)
		(size 0.5588)
		(drill 0.3048)
		(layers "F.Cu" "B.Cu")
		(net "GND")
	)
	(via
		(at 30.861 -199.009)
		(size 0.7112)
		(drill 0.4064)
		(layers "F.Cu" "B.Cu")
		(net "GND")
	)
	(via
		(at 7.5438 -48.6156)
		(size 0.7112)
		(drill 0.4064)
		(layers "F.Cu" "B.Cu")
		(net "GND")
	)
	(via
		(at 49.276 -156.21)
		(size 0.7112)
		(drill 0.4064)
		(layers "F.Cu" "B.Cu")
		(net "GND")
	)
	(via
		(at 31.4452 -326.1106)
		(size 0.7112)
		(drill 0.4064)
		(layers "F.Cu" "B.Cu")
		(net "GND")
	)
	(via
		(at 49.0474 -172.466)
		(size 0.7112)
		(drill 0.4064)
		(layers "F.Cu" "B.Cu")
		(net "GND")
	)
	(via
		(at 1.166876 -59.436)
		(size 0.7112)
		(drill 0.4064)
		(layers "F.Cu" "B.Cu")
		(net "GND")
	)
	(via
		(at 33.02 -177.927)
		(size 0.5588)
		(drill 0.3048)
		(layers "F.Cu" "B.Cu")
		(net "GND")
	)
	(via
		(at 7.3914 -437.2737)
		(size 0.5588)
		(drill 0.3048)
		(layers "F.Cu" "B.Cu")
		(net "GND")
	)
	(via
		(at 6.604 -166.751)
		(size 0.7112)
		(drill 0.4064)
		(layers "F.Cu" "B.Cu")
		(net "GND")
	)
	(via
		(at 37.211 -206.248)
		(size 0.5588)
		(drill 0.3048)
		(layers "F.Cu" "B.Cu")
		(net "GND")
	)
	(via
		(at 18.669 -37.084)
		(size 0.7112)
		(drill 0.4064)
		(layers "F.Cu" "B.Cu")
		(net "GND")
	)
	(via
		(at 50.292 -429.641)
		(size 0.7112)
		(drill 0.4064)
		(layers "F.Cu" "B.Cu")
		(net "GND")
	)
	(via
		(at 27.559 -244.856)
		(size 0.7112)
		(drill 0.4064)
		(layers "F.Cu" "B.Cu")
		(net "GND")
	)
	(via
		(at 13.208 -29.3624)
		(size 0.7112)
		(drill 0.4064)
		(layers "F.Cu" "B.Cu")
		(net "GND")
	)
	(via
		(at 5.588 -312.928)
		(size 0.7112)
		(drill 0.4064)
		(layers "F.Cu" "B.Cu")
		(net "GND")
	)
	(via
		(at 51.435 -191.897)
		(size 0.5588)
		(drill 0.3048)
		(layers "F.Cu" "B.Cu")
		(net "GND")
	)
	(via
		(at 7.366 -50.927)
		(size 0.7112)
		(drill 0.4064)
		(layers "F.Cu" "B.Cu")
		(net "GND")
	)
	(via
		(at 30.607 -186.055)
		(size 0.7112)
		(drill 0.4064)
		(layers "F.Cu" "B.Cu")
		(net "GND")
	)
	(via
		(at 1.143 -246.38)
		(size 0.7112)
		(drill 0.4064)
		(layers "F.Cu" "B.Cu")
		(net "GND")
	)
	(via
		(at 38.735 -478.3074)
		(size 0.5588)
		(drill 0.3048)
		(layers "F.Cu" "B.Cu")
		(net "GND")
	)
	(via
		(at 46.99 -470.535)
		(size 0.7112)
		(drill 0.4064)
		(layers "F.Cu" "B.Cu")
		(net "GND")
	)
	(via
		(at 37.846 -171.958)
		(size 0.5588)
		(drill 0.3048)
		(layers "F.Cu" "B.Cu")
		(net "GND")
	)
	(via
		(at 22.479 -177.8)
		(size 0.5588)
		(drill 0.3048)
		(layers "F.Cu" "B.Cu")
		(net "GND")
	)
	(via
		(at 8.382 -400.05)
		(size 0.7112)
		(drill 0.3556)
		(layers "F.Cu" "B.Cu")
		(net "GND")
	)
	(via
		(at 22.479 -238.887)
		(size 0.7112)
		(drill 0.4064)
		(layers "F.Cu" "B.Cu")
		(net "GND")
	)
	(via
		(at 10.8458 -407.924)
		(size 0.5588)
		(drill 0.3048)
		(layers "F.Cu" "B.Cu")
		(net "GND")
	)
	(via
		(at 43.434 -357.505)
		(size 0.7112)
		(drill 0.3556)
		(layers "F.Cu" "B.Cu")
		(net "GND")
	)
	(via
		(at 1.420876 -13.589)
		(size 0.7112)
		(drill 0.4064)
		(layers "F.Cu" "B.Cu")
		(net "GND")
	)
	(via
		(at 49.53 -272.923)
		(size 0.7112)
		(drill 0.4064)
		(layers "F.Cu" "B.Cu")
		(net "GND")
	)
	(via
		(at 49.784 -200.533)
		(size 0.7112)
		(drill 0.4064)
		(layers "F.Cu" "B.Cu")
		(net "GND")
	)
	(via
		(at 14.605 -266.827)
		(size 0.7112)
		(drill 0.3556)
		(layers "F.Cu" "B.Cu")
		(net "GND")
	)
	(via
		(at 44.03725 -363.855)
		(size 0.7112)
		(drill 0.4064)
		(layers "F.Cu" "B.Cu")
		(net "GND")
	)
	(via
		(at 34.1884 -169.0624)
		(size 0.5588)
		(drill 0.3048)
		(layers "F.Cu" "B.Cu")
		(net "GND")
	)
	(via
		(at 19.558 -221.361)
		(size 0.7112)
		(drill 0.4064)
		(layers "F.Cu" "B.Cu")
		(net "GND")
	)
	(via
		(at 28.194 -354.076)
		(size 0.5588)
		(drill 0.3048)
		(layers "F.Cu" "B.Cu")
		(net "GND")
	)
	(via
		(at 1.143 -239.141)
		(size 0.7112)
		(drill 0.4064)
		(layers "F.Cu" "B.Cu")
		(net "GND")
	)
	(via
		(at 31.369 -207.264)
		(size 0.7112)
		(drill 0.4064)
		(layers "F.Cu" "B.Cu")
		(net "GND")
	)
	(via
		(at 23.876 -362.6612)
		(size 0.7112)
		(drill 0.4064)
		(layers "F.Cu" "B.Cu")
		(net "GND")
	)
	(via
		(at 7.62 -439.674)
		(size 0.7112)
		(drill 0.4064)
		(layers "F.Cu" "B.Cu")
		(net "GND")
	)
	(via
		(at 41.021 -470.535)
		(size 0.7112)
		(drill 0.4064)
		(layers "F.Cu" "B.Cu")
		(net "GND")
	)
	(via
		(at 48.768 -240.919)
		(size 0.7112)
		(drill 0.4064)
		(layers "F.Cu" "B.Cu")
		(net "GND")
	)
	(via
		(at 2.032 -347.472)
		(size 0.7112)
		(drill 0.4064)
		(layers "F.Cu" "B.Cu")
		(net "GND")
	)
	(via
		(at 28.321 -99.06)
		(size 0.7112)
		(drill 0.4064)
		(layers "F.Cu" "B.Cu")
		(net "GND")
	)
	(via
		(at 14.986 -366.903)
		(size 0.7112)
		(drill 0.4064)
		(layers "F.Cu" "B.Cu")
		(net "GND")
	)
	(via
		(at 1.347216 -110.363)
		(size 0.7112)
		(drill 0.4064)
		(layers "F.Cu" "B.Cu")
		(net "GND")
	)
	(via
		(at 33.274 -35.0774)
		(size 0.7112)
		(drill 0.4064)
		(layers "F.Cu" "B.Cu")
		(net "GND")
	)
	(via
		(at 11.5062 -397.1544)
		(size 0.7112)
		(drill 0.4064)
		(layers "F.Cu" "B.Cu")
		(net "GND")
	)
	(via
		(at 1.420876 -22.098)
		(size 0.7112)
		(drill 0.4064)
		(layers "F.Cu" "B.Cu")
		(net "GND")
	)
	(via
		(at 51.308 -165.227)
		(size 0.7112)
		(drill 0.4064)
		(layers "F.Cu" "B.Cu")
		(net "GND")
	)
	(via
		(at 9.017 -424.307)
		(size 0.5588)
		(drill 0.3048)
		(layers "F.Cu" "B.Cu")
		(net "GND")
	)
	(via
		(at 51.435 -244.348)
		(size 0.5588)
		(drill 0.3048)
		(layers "F.Cu" "B.Cu")
		(net "GND")
	)
	(via
		(at 37.465 -332.994)
		(size 0.7112)
		(drill 0.4064)
		(layers "F.Cu" "B.Cu")
		(net "GND")
	)
	(via
		(at 30.099 -296.164)
		(size 0.7112)
		(drill 0.4064)
		(layers "F.Cu" "B.Cu")
		(net "GND")
	)
	(via
		(at 26.543 -306.832)
		(size 0.7112)
		(drill 0.4064)
		(layers "F.Cu" "B.Cu")
		(net "GND")
	)
	(via
		(at 6.2992 -489.331)
		(size 0.7112)
		(drill 0.4064)
		(layers "F.Cu" "B.Cu")
		(net "GND")
	)
	(via
		(at 23.7744 -357.4034)
		(size 0.7112)
		(drill 0.4064)
		(layers "F.Cu" "B.Cu")
		(net "GND")
	)
	(via
		(at 10.9982 -385.699)
		(size 0.7112)
		(drill 0.4064)
		(layers "F.Cu" "B.Cu")
		(net "GND")
	)
	(via
		(at 7.62 -314.96)
		(size 0.7112)
		(drill 0.4064)
		(layers "F.Cu" "B.Cu")
		(net "GND")
	)
	(via
		(at 32.639 -273.5072)
		(size 0.7112)
		(drill 0.3556)
		(layers "F.Cu" "B.Cu")
		(net "GND")
	)
	(via
		(at 32.8168 -210.9216)
		(size 0.7112)
		(drill 0.4064)
		(layers "F.Cu" "B.Cu")
		(net "GND")
	)
	(via
		(at 8.128 -214.376)
		(size 0.7112)
		(drill 0.4064)
		(layers "F.Cu" "B.Cu")
		(net "GND")
	)
	(via
		(at 1.27 -344.17)
		(size 0.5588)
		(drill 0.3048)
		(layers "F.Cu" "B.Cu")
		(net "GND")
	)
	(via
		(at 3.683 -467.868)
		(size 0.7112)
		(drill 0.4064)
		(layers "F.Cu" "B.Cu")
		(net "GND")
	)
	(via
		(at 21.971 -236.728)
		(size 0.7112)
		(drill 0.4064)
		(layers "F.Cu" "B.Cu")
		(net "GND")
	)
	(via
		(at 11.2014 -428.0408)
		(size 0.5588)
		(drill 0.3048)
		(layers "F.Cu" "B.Cu")
		(net "GND")
	)
	(via
		(at 39.878 -279.781)
		(size 0.7112)
		(drill 0.4064)
		(layers "F.Cu" "B.Cu")
		(net "GND")
	)
	(via
		(at 1.166876 -190.246)
		(size 0.5588)
		(drill 0.3048)
		(layers "F.Cu" "B.Cu")
		(net "GND")
	)
	(via
		(at 28.321 -261.62)
		(size 0.7112)
		(drill 0.4064)
		(layers "F.Cu" "B.Cu")
		(net "GND")
	)
	(via
		(at 8.5344 -261.5946)
		(size 0.7112)
		(drill 0.4064)
		(layers "F.Cu" "B.Cu")
		(net "GND")
	)
	(via
		(at 41.9862 -36.8808)
		(size 0.7112)
		(drill 0.4064)
		(layers "F.Cu" "B.Cu")
		(net "GND")
	)
	(via
		(at 10.8204 -366.8268)
		(size 0.7112)
		(drill 0.4064)
		(layers "F.Cu" "B.Cu")
		(net "GND")
	)
	(via
		(at 31.6992 -176.9364)
		(size 0.7112)
		(drill 0.4064)
		(layers "F.Cu" "B.Cu")
		(net "GND")
	)
	(via
		(at 29.972 -31.623)
		(size 0.7112)
		(drill 0.4064)
		(layers "F.Cu" "B.Cu")
		(net "GND")
	)
	(via
		(at 1.2192 -371.0178)
		(size 0.7112)
		(drill 0.4064)
		(layers "F.Cu" "B.Cu")
		(net "GND")
	)
	(via
		(at 44.069 -194.056)
		(size 0.7112)
		(drill 0.4064)
		(layers "F.Cu" "B.Cu")
		(net "GND")
	)
	(via
		(at 37.0332 -150.9776)
		(size 0.5588)
		(drill 0.3048)
		(layers "F.Cu" "B.Cu")
		(net "GND")
	)
	(via
		(at 26.543 -309.753)
		(size 0.7112)
		(drill 0.4064)
		(layers "F.Cu" "B.Cu")
		(net "GND")
	)
	(via
		(at 1.293876 -272.923)
		(size 0.7112)
		(drill 0.4064)
		(layers "F.Cu" "B.Cu")
		(net "GND")
	)
	(via
		(at 48.7172 -325.3486)
		(size 0.7112)
		(drill 0.4064)
		(layers "F.Cu" "B.Cu")
		(net "GND")
	)
	(via
		(at 42.019982 -175.862488)
		(size 0.5588)
		(drill 0.3048)
		(layers "F.Cu" "B.Cu")
		(net "GND")
	)
	(via
		(at 23.876 -346.964)
		(size 0.7112)
		(drill 0.4064)
		(layers "F.Cu" "B.Cu")
		(net "GND")
	)
	(via
		(at 8.128 -353.441)
		(size 0.7112)
		(drill 0.4064)
		(layers "F.Cu" "B.Cu")
		(net "GND")
	)
	(via
		(at 32.766 -40.6654)
		(size 0.7112)
		(drill 0.4064)
		(layers "F.Cu" "B.Cu")
		(net "GND")
	)
	(via
		(at 43.883072 -454.68794)
		(size 0.7112)
		(drill 0.4064)
		(layers "F.Cu" "B.Cu")
		(net "GND")
	)
	(via
		(at 47.625 -276.86)
		(size 0.7112)
		(drill 0.4064)
		(layers "F.Cu" "B.Cu")
		(net "GND")
	)
	(via
		(at 10.3886 -228.981)
		(size 0.7112)
		(drill 0.4064)
		(layers "F.Cu" "B.Cu")
		(net "GND")
	)
	(via
		(at 51.4096 -366.776)
		(size 0.5588)
		(drill 0.3048)
		(layers "F.Cu" "B.Cu")
		(net "GND")
	)
	(via
		(at 21.209 -247.9802)
		(size 0.5588)
		(drill 0.3048)
		(layers "F.Cu" "B.Cu")
		(net "GND")
	)
	(via
		(at 29.4132 -346.4306)
		(size 0.7112)
		(drill 0.4064)
		(layers "F.Cu" "B.Cu")
		(net "GND")
	)
	(via
		(at 33.909 -147.828)
		(size 0.5588)
		(drill 0.3048)
		(layers "F.Cu" "B.Cu")
		(net "GND")
	)
	(via
		(at 43.561 -26.797)
		(size 0.7112)
		(drill 0.4064)
		(layers "F.Cu" "B.Cu")
		(net "GND")
	)
	(via
		(at 31.623 -209.5754)
		(size 0.7112)
		(drill 0.4064)
		(layers "F.Cu" "B.Cu")
		(net "GND")
	)
	(via
		(at 36.576 -235.966)
		(size 0.7112)
		(drill 0.4064)
		(layers "F.Cu" "B.Cu")
		(net "GND")
	)
	(via
		(at 3.175 -50.165)
		(size 0.7112)
		(drill 0.4064)
		(layers "F.Cu" "B.Cu")
		(net "GND")
	)
	(via
		(at 11.3284 -437.9976)
		(size 0.7112)
		(drill 0.4064)
		(layers "F.Cu" "B.Cu")
		(net "GND")
	)
	(via
		(at 16.002 -376.5042)
		(size 0.7112)
		(drill 0.4064)
		(layers "F.Cu" "B.Cu")
		(net "GND")
	)
	(via
		(at 24.511 -232.791)
		(size 0.7112)
		(drill 0.4064)
		(layers "F.Cu" "B.Cu")
		(net "GND")
	)
	(via
		(at 51.181 -291.338)
		(size 0.5588)
		(drill 0.3048)
		(layers "F.Cu" "B.Cu")
		(net "GND")
	)
	(via
		(at 16.764 -139.827)
		(size 0.5588)
		(drill 0.3048)
		(layers "F.Cu" "B.Cu")
		(net "GND")
	)
	(via
		(at 44.983908 -286.9692)
		(size 0.7112)
		(drill 0.4064)
		(layers "F.Cu" "B.Cu")
		(net "GND")
	)
	(via
		(at 38.735 -449.86194)
		(size 0.7112)
		(drill 0.4064)
		(layers "F.Cu" "B.Cu")
		(net "GND")
	)
	(via
		(at 36.957 -224.79)
		(size 0.7112)
		(drill 0.4064)
		(layers "F.Cu" "B.Cu")
		(net "GND")
	)
	(via
		(at 6.617462 -210.374738)
		(size 0.7112)
		(drill 0.4064)
		(layers "F.Cu" "B.Cu")
		(net "GND")
	)
	(via
		(at 24.765 -482.854)
		(size 0.7112)
		(drill 0.3556)
		(layers "F.Cu" "B.Cu")
		(net "GND")
	)
	(via
		(at 1.651 -95.25)
		(size 0.7112)
		(drill 0.4064)
		(layers "F.Cu" "B.Cu")
		(net "GND")
	)
	(via
		(at 37.084 -194.437)
		(size 0.5588)
		(drill 0.3048)
		(layers "F.Cu" "B.Cu")
		(net "GND")
	)
	(via
		(at 46.228 -438.404)
		(size 0.7112)
		(drill 0.4064)
		(layers "F.Cu" "B.Cu")
		(net "GND")
	)
	(via
		(at 1.27 -123.571)
		(size 0.7112)
		(drill 0.4064)
		(layers "F.Cu" "B.Cu")
		(net "GND")
	)
	(via
		(at 13.7922 -232.537)
		(size 0.5588)
		(drill 0.3048)
		(layers "F.Cu" "B.Cu")
		(net "GND")
	)
	(via
		(at 11.049 -494.03)
		(size 0.7112)
		(drill 0.4064)
		(layers "F.Cu" "B.Cu")
		(net "GND")
	)
	(via
		(at 24.892 -108.331)
		(size 0.7112)
		(drill 0.4064)
		(layers "F.Cu" "B.Cu")
		(net "GND")
	)
	(via
		(at 31.496 -246.761)
		(size 0.7112)
		(drill 0.4064)
		(layers "F.Cu" "B.Cu")
		(net "GND")
	)
	(via
		(at 31.75 -190.754)
		(size 0.7112)
		(drill 0.4064)
		(layers "F.Cu" "B.Cu")
		(net "GND")
	)
	(via
		(at 1.905 -416.6108)
		(size 0.7112)
		(drill 0.4064)
		(layers "F.Cu" "B.Cu")
		(net "GND")
	)
	(via
		(at 51.076606 -46.1518)
		(size 0.7112)
		(drill 0.4064)
		(layers "F.Cu" "B.Cu")
		(net "GND")
	)
	(via
		(at 38.989 -262.509)
		(size 0.5588)
		(drill 0.3048)
		(layers "F.Cu" "B.Cu")
		(net "GND")
	)
	(via
		(at 4.064 -240.792)
		(size 0.7112)
		(drill 0.4064)
		(layers "F.Cu" "B.Cu")
		(net "GND")
	)
	(via
		(at 4.7244 -475.3356)
		(size 0.7112)
		(drill 0.4064)
		(layers "F.Cu" "B.Cu")
		(net "GND")
	)
	(via
		(at 41.8338 -262.5344)
		(size 0.7112)
		(drill 0.4064)
		(layers "F.Cu" "B.Cu")
		(net "GND")
	)
	(via
		(at 40.513 -269.748)
		(size 0.5588)
		(drill 0.3048)
		(layers "F.Cu" "B.Cu")
		(net "GND")
	)
	(via
		(at 10.668 -200.152)
		(size 0.7112)
		(drill 0.4064)
		(layers "F.Cu" "B.Cu")
		(net "GND")
	)
	(via
		(at 4.963668 -434.471572)
		(size 0.5588)
		(drill 0.3048)
		(layers "F.Cu" "B.Cu")
		(net "GND")
	)
	(via
		(at 14.969744 -65.097406)
		(size 0.5588)
		(drill 0.3048)
		(layers "F.Cu" "B.Cu")
		(net "GND")
	)
	(via
		(at 37.338 -321.437)
		(size 0.7112)
		(drill 0.4064)
		(layers "F.Cu" "B.Cu")
		(net "GND")
	)
	(via
		(at 1.27 -473.4814)
		(size 0.7112)
		(drill 0.4064)
		(layers "F.Cu" "B.Cu")
		(net "GND")
	)
	(via
		(at 36.068 -121.539)
		(size 0.5588)
		(drill 0.3048)
		(layers "F.Cu" "B.Cu")
		(net "GND")
	)
	(via
		(at 13.843 -263.017)
		(size 0.5588)
		(drill 0.3048)
		(layers "F.Cu" "B.Cu")
		(net "GND")
	)
	(via
		(at 20.701 -359.791)
		(size 0.7112)
		(drill 0.4064)
		(layers "F.Cu" "B.Cu")
		(net "GND")
	)
	(via
		(at 11.811 -469.9508)
		(size 0.7112)
		(drill 0.4064)
		(layers "F.Cu" "B.Cu")
		(net "GND")
	)
	(via
		(at 17.78 -235.077)
		(size 0.7112)
		(drill 0.4064)
		(layers "F.Cu" "B.Cu")
		(net "GND")
	)
	(via
		(at 35.687 -215.011)
		(size 0.7112)
		(drill 0.4064)
		(layers "F.Cu" "B.Cu")
		(net "GND")
	)
	(via
		(at 14.732 -328.168)
		(size 0.7112)
		(drill 0.4064)
		(layers "F.Cu" "B.Cu")
		(net "GND")
	)
	(via
		(at 37.084 -184.404)
		(size 0.5588)
		(drill 0.3048)
		(layers "F.Cu" "B.Cu")
		(net "GND")
	)
	(via
		(at 41.91 -199.644)
		(size 0.7112)
		(drill 0.4064)
		(layers "F.Cu" "B.Cu")
		(net "GND")
	)
	(via
		(at 9.144 -185.42)
		(size 0.7112)
		(drill 0.4064)
		(layers "F.Cu" "B.Cu")
		(net "GND")
	)
	(via
		(at 48.895 -389.382)
		(size 0.7112)
		(drill 0.4064)
		(layers "F.Cu" "B.Cu")
		(net "GND")
	)
	(via
		(at 19.4056 -253.7714)
		(size 0.7112)
		(drill 0.4064)
		(layers "F.Cu" "B.Cu")
		(net "GND")
	)
	(via
		(at 28.2448 -108.3056)
		(size 0.7112)
		(drill 0.4064)
		(layers "F.Cu" "B.Cu")
		(net "GND")
	)
	(via
		(at 4.064 -291.592)
		(size 0.7112)
		(drill 0.4064)
		(layers "F.Cu" "B.Cu")
		(net "GND")
	)
	(via
		(at 5.08 -1.524)
		(size 0.7112)
		(drill 0.4064)
		(layers "F.Cu" "B.Cu")
		(net "GND")
	)
	(via
		(at 48.9331 -416.941)
		(size 0.5588)
		(drill 0.3048)
		(layers "F.Cu" "B.Cu")
		(net "GND")
	)
	(via
		(at 42.291 -196.977)
		(size 0.5588)
		(drill 0.3048)
		(layers "F.Cu" "B.Cu")
		(net "GND")
	)
	(via
		(at 10.668 -166.497)
		(size 0.7112)
		(drill 0.3556)
		(layers "F.Cu" "B.Cu")
		(net "GND")
	)
	(via
		(at 50.8 -13.97)
		(size 0.7112)
		(drill 0.4064)
		(layers "F.Cu" "B.Cu")
		(net "GND")
	)
	(via
		(at 51.0794 -484.8352)
		(size 0.5588)
		(drill 0.3048)
		(layers "F.Cu" "B.Cu")
		(net "GND")
	)
	(via
		(at 11.4554 -491.0836)
		(size 0.7112)
		(drill 0.4064)
		(layers "F.Cu" "B.Cu")
		(net "GND")
	)
	(via
		(at 37.465 -140.081)
		(size 0.7112)
		(drill 0.4064)
		(layers "F.Cu" "B.Cu")
		(net "GND")
	)
	(via
		(at 27.94 -241.173)
		(size 0.7112)
		(drill 0.4064)
		(layers "F.Cu" "B.Cu")
		(net "GND")
	)
	(via
		(at 38.227 -151.384)
		(size 0.7112)
		(drill 0.4064)
		(layers "F.Cu" "B.Cu")
		(net "GND")
	)
	(via
		(at 48.768 -244.348)
		(size 0.7112)
		(drill 0.4064)
		(layers "F.Cu" "B.Cu")
		(net "GND")
	)
	(via
		(at 22.86 -226.822)
		(size 0.7112)
		(drill 0.4064)
		(layers "F.Cu" "B.Cu")
		(net "GND")
	)
	(via
		(at 49.657 -254.254)
		(size 0.7112)
		(drill 0.4064)
		(layers "F.Cu" "B.Cu")
		(net "GND")
	)
	(via
		(at 7.874 -189.738)
		(size 0.7112)
		(drill 0.4064)
		(layers "F.Cu" "B.Cu")
		(net "GND")
	)
	(via
		(at 31.623 -222.631)
		(size 0.7112)
		(drill 0.4064)
		(layers "F.Cu" "B.Cu")
		(net "GND")
	)
	(via
		(at 18.542 -378.7648)
		(size 0.7112)
		(drill 0.4064)
		(layers "F.Cu" "B.Cu")
		(net "GND")
	)
	(via
		(at 8.636 -258.445)
		(size 0.7112)
		(drill 0.4064)
		(layers "F.Cu" "B.Cu")
		(net "GND")
	)
	(via
		(at 48.387 -211.074)
		(size 0.7112)
		(drill 0.4064)
		(layers "F.Cu" "B.Cu")
		(net "GND")
	)
	(via
		(at 5.461 -61.341)
		(size 0.7112)
		(drill 0.4064)
		(layers "F.Cu" "B.Cu")
		(net "GND")
	)
	(via
		(at 25.654 -148.082)
		(size 0.5588)
		(drill 0.3048)
		(layers "F.Cu" "B.Cu")
		(net "GND")
	)
	(via
		(at 44.45 -11.43)
		(size 0.7112)
		(drill 0.4064)
		(layers "F.Cu" "B.Cu")
		(net "GND")
	)
	(via
		(at 4.064 -298.704)
		(size 0.7112)
		(drill 0.4064)
		(layers "F.Cu" "B.Cu")
		(net "GND")
	)
	(via
		(at 43.434 -265.684)
		(size 0.7112)
		(drill 0.4064)
		(layers "F.Cu" "B.Cu")
		(net "GND")
	)
	(via
		(at 27.686 -275.209)
		(size 0.7112)
		(drill 0.4064)
		(layers "F.Cu" "B.Cu")
		(net "GND")
	)
	(via
		(at 35.306 -430.911)
		(size 0.7112)
		(drill 0.4064)
		(layers "F.Cu" "B.Cu")
		(net "GND")
	)
	(via
		(at 3.556 -272.796)
		(size 0.7112)
		(drill 0.4064)
		(layers "F.Cu" "B.Cu")
		(net "GND")
	)
	(via
		(at 28.829 -231.013)
		(size 0.7112)
		(drill 0.4064)
		(layers "F.Cu" "B.Cu")
		(net "GND")
	)
	(via
		(at 1.524 -185.547)
		(size 0.7112)
		(drill 0.4064)
		(layers "F.Cu" "B.Cu")
		(net "GND")
	)
	(via
		(at 22.1488 -363.7026)
		(size 0.7112)
		(drill 0.4064)
		(layers "F.Cu" "B.Cu")
		(net "GND")
	)
	(via
		(at 45.847 -247.1928)
		(size 0.5588)
		(drill 0.3048)
		(layers "F.Cu" "B.Cu")
		(net "GND")
	)
	(via
		(at 33.02 -203.2)
		(size 0.7112)
		(drill 0.4064)
		(layers "F.Cu" "B.Cu")
		(net "GND")
	)
	(via
		(at 11.303 -426.212)
		(size 0.5588)
		(drill 0.3048)
		(layers "F.Cu" "B.Cu")
		(net "GND")
	)
	(via
		(at 6.7564 -398.8054)
		(size 0.7112)
		(drill 0.4064)
		(layers "F.Cu" "B.Cu")
		(net "GND")
	)
	(via
		(at 36.1696 -488.6452)
		(size 0.5588)
		(drill 0.3048)
		(layers "F.Cu" "B.Cu")
		(net "GND")
	)
	(via
		(at 9.906 -338.709)
		(size 0.7112)
		(drill 0.4064)
		(layers "F.Cu" "B.Cu")
		(net "GND")
	)
	(via
		(at 40.894 -482.981)
		(size 0.7112)
		(drill 0.4064)
		(layers "F.Cu" "B.Cu")
		(net "GND")
	)
	(via
		(at 47.244 -36.322)
		(size 0.7112)
		(drill 0.4064)
		(layers "F.Cu" "B.Cu")
		(net "GND")
	)
	(via
		(at 37.1602 -486.0798)
		(size 0.5588)
		(drill 0.3048)
		(layers "F.Cu" "B.Cu")
		(net "GND")
	)
	(via
		(at 13.335 -63.119)
		(size 0.5588)
		(drill 0.3048)
		(layers "F.Cu" "B.Cu")
		(net "GND")
	)
	(via
		(at 4.064 -320.548)
		(size 0.7112)
		(drill 0.4064)
		(layers "F.Cu" "B.Cu")
		(net "GND")
	)
	(via
		(at 40.5638 -165.608)
		(size 0.7112)
		(drill 0.4064)
		(layers "F.Cu" "B.Cu")
		(net "GND")
	)
	(via
		(at 38.608 -434.49494)
		(size 0.7112)
		(drill 0.4064)
		(layers "F.Cu" "B.Cu")
		(net "GND")
	)
	(via
		(at 10.795 -66.0908)
		(size 0.5588)
		(drill 0.3048)
		(layers "F.Cu" "B.Cu")
		(net "GND")
	)
	(via
		(at 29.21 -178.943)
		(size 0.7112)
		(drill 0.4064)
		(layers "F.Cu" "B.Cu")
		(net "GND")
	)
	(via
		(at 22.987 -211.201)
		(size 0.7112)
		(drill 0.4064)
		(layers "F.Cu" "B.Cu")
		(net "GND")
	)
	(via
		(at 51.181 -358.902)
		(size 0.5588)
		(drill 0.3048)
		(layers "F.Cu" "B.Cu")
		(net "GND")
	)
	(via
		(at 51.308 -199.644)
		(size 0.7112)
		(drill 0.4064)
		(layers "F.Cu" "B.Cu")
		(net "GND")
	)
	(via
		(at 51.435 -255.524)
		(size 0.5588)
		(drill 0.3048)
		(layers "F.Cu" "B.Cu")
		(net "GND")
	)
	(via
		(at 7.112 -335.28)
		(size 0.7112)
		(drill 0.4064)
		(layers "F.Cu" "B.Cu")
		(net "GND")
	)
	(via
		(at 29.21 -206.502)
		(size 0.7112)
		(drill 0.4064)
		(layers "F.Cu" "B.Cu")
		(net "GND")
	)
	(via
		(at 27.206702 -171.196254)
		(size 0.7112)
		(drill 0.4064)
		(layers "F.Cu" "B.Cu")
		(net "GND")
	)
	(via
		(at 46.228 -432.816)
		(size 0.7112)
		(drill 0.4064)
		(layers "F.Cu" "B.Cu")
		(net "GND")
	)
	(via
		(at 18.034 -33.492186)
		(size 0.7112)
		(drill 0.4064)
		(layers "F.Cu" "B.Cu")
		(net "GND")
	)
	(via
		(at 23.876 -231.267)
		(size 0.7112)
		(drill 0.4064)
		(layers "F.Cu" "B.Cu")
		(net "GND")
	)
	(via
		(at 46.228 -258.064)
		(size 0.7112)
		(drill 0.4064)
		(layers "F.Cu" "B.Cu")
		(net "GND")
	)
	(via
		(at 28.829 -185.166)
		(size 0.5588)
		(drill 0.3048)
		(layers "F.Cu" "B.Cu")
		(net "GND")
	)
	(via
		(at 46.736 -250.825)
		(size 0.7112)
		(drill 0.4064)
		(layers "F.Cu" "B.Cu")
		(net "GND")
	)
	(via
		(at 1.27 -224.409)
		(size 0.7112)
		(drill 0.4064)
		(layers "F.Cu" "B.Cu")
		(net "GND")
	)
	(via
		(at 4.064 -254)
		(size 0.7112)
		(drill 0.4064)
		(layers "F.Cu" "B.Cu")
		(net "GND")
	)
	(via
		(at 8.636 -272.288)
		(size 0.7112)
		(drill 0.4064)
		(layers "F.Cu" "B.Cu")
		(net "GND")
	)
	(via
		(at 49.784 -182.499)
		(size 0.7112)
		(drill 0.4064)
		(layers "F.Cu" "B.Cu")
		(net "GND")
	)
	(via
		(at 45.974 -282.575)
		(size 0.7112)
		(drill 0.4064)
		(layers "F.Cu" "B.Cu")
		(net "GND")
	)
	(via
		(at 31.623 -217.932)
		(size 0.7112)
		(drill 0.4064)
		(layers "F.Cu" "B.Cu")
		(net "GND")
	)
	(via
		(at 30.3022 -316.3316)
		(size 0.7112)
		(drill 0.4064)
		(layers "F.Cu" "B.Cu")
		(net "GND")
	)
	(via
		(at 33.02 -194.056)
		(size 0.5588)
		(drill 0.3048)
		(layers "F.Cu" "B.Cu")
		(net "GND")
	)
	(via
		(at 4.064 -213.868)
		(size 0.7112)
		(drill 0.4064)
		(layers "F.Cu" "B.Cu")
		(net "GND")
	)
	(via
		(at 41.402 -431.038)
		(size 0.7112)
		(drill 0.4064)
		(layers "F.Cu" "B.Cu")
		(net "GND")
	)
	(via
		(at 32.004 -226.695)
		(size 0.7112)
		(drill 0.4064)
		(layers "F.Cu" "B.Cu")
		(net "GND")
	)
	(via
		(at 39.116 -90.297)
		(size 0.7112)
		(drill 0.3556)
		(layers "F.Cu" "B.Cu")
		(net "GND")
	)
	(via
		(at 51.054 -56.515)
		(size 0.7112)
		(drill 0.4064)
		(layers "F.Cu" "B.Cu")
		(net "GND")
	)
	(via
		(at 4.699 -227.711)
		(size 0.7112)
		(drill 0.4064)
		(layers "F.Cu" "B.Cu")
		(net "GND")
	)
	(via
		(at 45.6946 -228.8286)
		(size 0.5588)
		(drill 0.3048)
		(layers "F.Cu" "B.Cu")
		(net "GND")
	)
	(via
		(at 21.1836 -223.1644)
		(size 0.7112)
		(drill 0.4064)
		(layers "F.Cu" "B.Cu")
		(net "GND")
	)
	(via
		(at 44.704 -33.274)
		(size 0.7112)
		(drill 0.4064)
		(layers "F.Cu" "B.Cu")
		(net "GND")
	)
	(via
		(at 1.524 -283.972)
		(size 0.7112)
		(drill 0.4064)
		(layers "F.Cu" "B.Cu")
		(net "GND")
	)
	(via
		(at 30.734 -287.782)
		(size 0.7112)
		(drill 0.3556)
		(layers "F.Cu" "B.Cu")
		(net "GND")
	)
	(via
		(at 12.9032 -67.6656)
		(size 0.5588)
		(drill 0.3048)
		(layers "F.Cu" "B.Cu")
		(net "GND")
	)
	(via
		(at 29.972 -36.195)
		(size 0.7112)
		(drill 0.4064)
		(layers "F.Cu" "B.Cu")
		(net "GND")
	)
	(via
		(at 10.033 -312.674)
		(size 0.7112)
		(drill 0.4064)
		(layers "F.Cu" "B.Cu")
		(net "GND")
	)
	(via
		(at 30.226 -247.65)
		(size 0.7112)
		(drill 0.4064)
		(layers "F.Cu" "B.Cu")
		(net "GND")
	)
	(via
		(at 9.7282 -401.2184)
		(size 0.7112)
		(drill 0.4064)
		(layers "F.Cu" "B.Cu")
		(net "GND")
	)
	(via
		(at 3.302 -53.975)
		(size 0.7112)
		(drill 0.4064)
		(layers "F.Cu" "B.Cu")
		(net "GND")
	)
	(via
		(at 51.308 -316.484)
		(size 0.5588)
		(drill 0.3048)
		(layers "F.Cu" "B.Cu")
		(net "GND")
	)
	(via
		(at 33.909 -372.6434)
		(size 0.7112)
		(drill 0.4064)
		(layers "F.Cu" "B.Cu")
		(net "GND")
	)
	(via
		(at 24.257 -253.746)
		(size 0.7112)
		(drill 0.4064)
		(layers "F.Cu" "B.Cu")
		(net "GND")
	)
	(via
		(at 23.368 -308.483)
		(size 0.7112)
		(drill 0.4064)
		(layers "F.Cu" "B.Cu")
		(net "GND")
	)
	(via
		(at 8.509 -244.475)
		(size 0.7112)
		(drill 0.4064)
		(layers "F.Cu" "B.Cu")
		(net "GND")
	)
	(via
		(at 43.434 -271.272)
		(size 0.7112)
		(drill 0.4064)
		(layers "F.Cu" "B.Cu")
		(net "GND")
	)
	(via
		(at 35.052 -463.296)
		(size 0.7112)
		(drill 0.4064)
		(layers "F.Cu" "B.Cu")
		(net "GND")
	)
	(via
		(at 12.7254 -320.421)
		(size 0.7112)
		(drill 0.4064)
		(layers "F.Cu" "B.Cu")
		(net "GND")
	)
	(via
		(at 8.001 -354.965)
		(size 0.7112)
		(drill 0.4064)
		(layers "F.Cu" "B.Cu")
		(net "GND")
	)
	(via
		(at 9.525 -284.2006)
		(size 0.7112)
		(drill 0.4064)
		(layers "F.Cu" "B.Cu")
		(net "GND")
	)
	(via
		(at 20.077176 -290.604448)
		(size 0.7112)
		(drill 0.4064)
		(layers "F.Cu" "B.Cu")
		(net "GND")
	)
	(via
		(at 49.403 -195.326)
		(size 0.7112)
		(drill 0.4064)
		(layers "F.Cu" "B.Cu")
		(net "GND")
	)
	(via
		(at 32.004 -236.22)
		(size 0.7112)
		(drill 0.4064)
		(layers "F.Cu" "B.Cu")
		(net "GND")
	)
	(via
		(at 21.336 -343.408)
		(size 0.7112)
		(drill 0.4064)
		(layers "F.Cu" "B.Cu")
		(net "GND")
	)
	(via
		(at 7.9756 -418.6428)
		(size 0.5588)
		(drill 0.3048)
		(layers "F.Cu" "B.Cu")
		(net "GND")
	)
	(via
		(at 51.181 -140.335)
		(size 0.7112)
		(drill 0.4064)
		(layers "F.Cu" "B.Cu")
		(net "GND")
	)
	(via
		(at 49.53 -11.43)
		(size 0.7112)
		(drill 0.4064)
		(layers "F.Cu" "B.Cu")
		(net "GND")
	)
	(via
		(at 50.165 -457.327)
		(size 0.7112)
		(drill 0.4064)
		(layers "F.Cu" "B.Cu")
		(net "GND")
	)
	(via
		(at 14.097 -245.872)
		(size 0.7112)
		(drill 0.4064)
		(layers "F.Cu" "B.Cu")
		(net "GND")
	)
	(via
		(at 6.858 -190.5)
		(size 0.7112)
		(drill 0.4064)
		(layers "F.Cu" "B.Cu")
		(net "GND")
	)
	(via
		(at 8.29945 -76.073)
		(size 0.5588)
		(drill 0.3048)
		(layers "F.Cu" "B.Cu")
		(net "GND")
	)
	(via
		(at 31.115 -201.295)
		(size 0.7112)
		(drill 0.4064)
		(layers "F.Cu" "B.Cu")
		(net "GND")
	)
	(via
		(at 34.036 -251.587)
		(size 0.7112)
		(drill 0.4064)
		(layers "F.Cu" "B.Cu")
		(net "GND")
	)
	(via
		(at 27.559 -246.634)
		(size 0.7112)
		(drill 0.4064)
		(layers "F.Cu" "B.Cu")
		(net "GND")
	)
	(via
		(at 51.181 -342.9)
		(size 0.5588)
		(drill 0.3048)
		(layers "F.Cu" "B.Cu")
		(net "GND")
	)
	(via
		(at 41.91 -278.638)
		(size 0.7112)
		(drill 0.4064)
		(layers "F.Cu" "B.Cu")
		(net "GND")
	)
	(via
		(at 14.0462 -497.6114)
		(size 0.7112)
		(drill 0.4064)
		(layers "F.Cu" "B.Cu")
		(net "GND")
	)
	(via
		(at 47.625 -33.147)
		(size 0.7112)
		(drill 0.4064)
		(layers "F.Cu" "B.Cu")
		(net "GND")
	)
	(via
		(at 31.75 -11.43)
		(size 0.7112)
		(drill 0.4064)
		(layers "F.Cu" "B.Cu")
		(net "GND")
	)
	(via
		(at 10.8458 -381)
		(size 0.7112)
		(drill 0.4064)
		(layers "F.Cu" "B.Cu")
		(net "GND")
	)
	(via
		(at 51.1048 -480.187)
		(size 0.5588)
		(drill 0.3048)
		(layers "F.Cu" "B.Cu")
		(net "GND")
	)
	(via
		(at 37.465 -338.328)
		(size 0.7112)
		(drill 0.4064)
		(layers "F.Cu" "B.Cu")
		(net "GND")
	)
	(via
		(at 1.143 -211.709)
		(size 0.7112)
		(drill 0.4064)
		(layers "F.Cu" "B.Cu")
		(net "GND")
	)
	(via
		(at 24.13 -31.75)
		(size 0.7112)
		(drill 0.4064)
		(layers "F.Cu" "B.Cu")
		(net "GND")
	)
	(via
		(at 42.672 -210.82)
		(size 0.5588)
		(drill 0.3048)
		(layers "F.Cu" "B.Cu")
		(net "GND")
	)
	(via
		(at 1.347216 -86.995)
		(size 0.7112)
		(drill 0.4064)
		(layers "F.Cu" "B.Cu")
		(net "GND")
	)
	(via
		(at 51.36134 -371.348)
		(size 0.5588)
		(drill 0.3048)
		(layers "F.Cu" "B.Cu")
		(net "GND")
	)
	(via
		(at 11.176 -303.276)
		(size 0.7112)
		(drill 0.4064)
		(layers "F.Cu" "B.Cu")
		(net "GND")
	)
	(via
		(at 24.13 -36.322)
		(size 0.7112)
		(drill 0.4064)
		(layers "F.Cu" "B.Cu")
		(net "GND")
	)
	(via
		(at 8.128 -169.164)
		(size 0.7112)
		(drill 0.4064)
		(layers "F.Cu" "B.Cu")
		(net "GND")
	)
	(via
		(at 25.273 -328.676)
		(size 0.7112)
		(drill 0.4064)
		(layers "F.Cu" "B.Cu")
		(net "GND")
	)
	(via
		(at 41.021 -192.786)
		(size 0.5588)
		(drill 0.3048)
		(layers "F.Cu" "B.Cu")
		(net "GND")
	)
	(via
		(at 46.609 -315.341)
		(size 0.7112)
		(drill 0.4064)
		(layers "F.Cu" "B.Cu")
		(net "GND")
	)
	(via
		(at 14.7066 -482.5492)
		(size 0.5588)
		(drill 0.3048)
		(layers "F.Cu" "B.Cu")
		(net "GND")
	)
	(via
		(at 41.021 -189.865)
		(size 0.5588)
		(drill 0.3048)
		(layers "F.Cu" "B.Cu")
		(net "GND")
	)
	(via
		(at 1.524 -183.388)
		(size 0.7112)
		(drill 0.4064)
		(layers "F.Cu" "B.Cu")
		(net "GND")
	)
	(via
		(at 31.496 -18.923)
		(size 0.7112)
		(drill 0.4064)
		(layers "F.Cu" "B.Cu")
		(net "GND")
	)
	(via
		(at 34.29 -226.822)
		(size 0.7112)
		(drill 0.4064)
		(layers "F.Cu" "B.Cu")
		(net "GND")
	)
	(via
		(at 39.2938 -231.0638)
		(size 0.7112)
		(drill 0.4064)
		(layers "F.Cu" "B.Cu")
		(net "GND")
	)
	(via
		(at 30.734 -197.104)
		(size 0.7112)
		(drill 0.4064)
		(layers "F.Cu" "B.Cu")
		(net "GND")
	)
	(via
		(at 28.829 -186.944)
		(size 0.5588)
		(drill 0.3048)
		(layers "F.Cu" "B.Cu")
		(net "GND")
	)
	(via
		(at 12.2174 -216.7636)
		(size 0.7112)
		(drill 0.4064)
		(layers "F.Cu" "B.Cu")
		(net "GND")
	)
	(via
		(at 13.335 -173.355)
		(size 0.5588)
		(drill 0.3048)
		(layers "F.Cu" "B.Cu")
		(net "GND")
	)
	(via
		(at 10.668 -321.564)
		(size 0.7112)
		(drill 0.4064)
		(layers "F.Cu" "B.Cu")
		(net "GND")
	)
	(via
		(at 47.7774 -175.0314)
		(size 0.7112)
		(drill 0.4064)
		(layers "F.Cu" "B.Cu")
		(net "GND")
	)
	(via
		(at 3.937 -493.395)
		(size 0.7112)
		(drill 0.4064)
		(layers "F.Cu" "B.Cu")
		(net "GND")
	)
	(via
		(at 5.588 -189.484)
		(size 0.7112)
		(drill 0.4064)
		(layers "F.Cu" "B.Cu")
		(net "GND")
	)
	(via
		(at 8.5217 -274.3454)
		(size 0.7112)
		(drill 0.4064)
		(layers "F.Cu" "B.Cu")
		(net "GND")
	)
	(via
		(at 10.541 -479.933)
		(size 0.5588)
		(drill 0.3048)
		(layers "F.Cu" "B.Cu")
		(net "GND")
	)
	(via
		(at 1.293876 -145.923)
		(size 0.5588)
		(drill 0.3048)
		(layers "F.Cu" "B.Cu")
		(net "GND")
	)
	(via
		(at 4.064 -288.036)
		(size 0.7112)
		(drill 0.4064)
		(layers "F.Cu" "B.Cu")
		(net "GND")
	)
	(via
		(at 29.718 -256.159)
		(size 0.7112)
		(drill 0.4064)
		(layers "F.Cu" "B.Cu")
		(net "GND")
	)
	(via
		(at 13.4874 -363.3978)
		(size 0.7112)
		(drill 0.4064)
		(layers "F.Cu" "B.Cu")
		(net "GND")
	)
	(via
		(at 23.114 -323.215)
		(size 0.7112)
		(drill 0.3556)
		(layers "F.Cu" "B.Cu")
		(net "GND")
	)
	(via
		(at 11.938 -479.0948)
		(size 0.5588)
		(drill 0.3048)
		(layers "F.Cu" "B.Cu")
		(net "GND")
	)
	(via
		(at 21.59 -11.43)
		(size 0.7112)
		(drill 0.4064)
		(layers "F.Cu" "B.Cu")
		(net "GND")
	)
	(via
		(at 8.636 -113.792)
		(size 0.5588)
		(drill 0.3048)
		(layers "F.Cu" "B.Cu")
		(net "GND")
	)
	(via
		(at 22.17674 -171.906184)
		(size 0.7112)
		(drill 0.4064)
		(layers "F.Cu" "B.Cu")
		(net "GND")
	)
	(via
		(at 28.067 -270.383)
		(size 0.7112)
		(drill 0.4064)
		(layers "F.Cu" "B.Cu")
		(net "GND")
	)
	(via
		(at 48.641 -183.896)
		(size 0.7112)
		(drill 0.4064)
		(layers "F.Cu" "B.Cu")
		(net "GND")
	)
	(via
		(at 8.636 -249.936)
		(size 0.7112)
		(drill 0.4064)
		(layers "F.Cu" "B.Cu")
		(net "GND")
	)
	(via
		(at 13.335 -347.599)
		(size 0.7112)
		(drill 0.4064)
		(layers "F.Cu" "B.Cu")
		(net "GND")
	)
	(via
		(at 24.257 -372.872)
		(size 0.7112)
		(drill 0.4064)
		(layers "F.Cu" "B.Cu")
		(net "GND")
	)
	(via
		(at 30.734 -147.701)
		(size 0.5588)
		(drill 0.3048)
		(layers "F.Cu" "B.Cu")
		(net "GND")
	)
	(via
		(at 5.855462 -218.756738)
		(size 0.7112)
		(drill 0.4064)
		(layers "F.Cu" "B.Cu")
		(net "GND")
	)
	(via
		(at 17.526 -38.862)
		(size 0.7112)
		(drill 0.4064)
		(layers "F.Cu" "B.Cu")
		(net "GND")
	)
	(via
		(at 6.985 -478.409)
		(size 0.7112)
		(drill 0.4064)
		(layers "F.Cu" "B.Cu")
		(net "GND")
	)
	(via
		(at 45.72 -217.424)
		(size 0.5588)
		(drill 0.3048)
		(layers "F.Cu" "B.Cu")
		(net "GND")
	)
	(via
		(at 41.91 -321.183)
		(size 0.7112)
		(drill 0.4064)
		(layers "F.Cu" "B.Cu")
		(net "GND")
	)
	(via
		(at 8.89 -491.109)
		(size 0.7112)
		(drill 0.4064)
		(layers "F.Cu" "B.Cu")
		(net "GND")
	)
	(via
		(at 50.292 -445.516)
		(size 0.7112)
		(drill 0.4064)
		(layers "F.Cu" "B.Cu")
		(net "GND")
	)
	(via
		(at 26.289 -231.013)
		(size 0.7112)
		(drill 0.4064)
		(layers "F.Cu" "B.Cu")
		(net "GND")
	)
	(via
		(at 15.6464 -496.4938)
		(size 0.7112)
		(drill 0.4064)
		(layers "F.Cu" "B.Cu")
		(net "GND")
	)
	(via
		(at 16.51 -142.621)
		(size 0.5588)
		(drill 0.3048)
		(layers "F.Cu" "B.Cu")
		(net "GND")
	)
	(via
		(at 44.45 -199.771)
		(size 0.7112)
		(drill 0.4064)
		(layers "F.Cu" "B.Cu")
		(net "GND")
	)
	(via
		(at 1.166876 -257.429)
		(size 0.7112)
		(drill 0.4064)
		(layers "F.Cu" "B.Cu")
		(net "GND")
	)
	(via
		(at 12.4714 -367.8936)
		(size 0.7112)
		(drill 0.4064)
		(layers "F.Cu" "B.Cu")
		(net "GND")
	)
	(via
		(at 41.021 -311.785)
		(size 0.7112)
		(drill 0.4064)
		(layers "F.Cu" "B.Cu")
		(net "GND")
	)
	(via
		(at 48.768 -223.266)
		(size 0.7112)
		(drill 0.4064)
		(layers "F.Cu" "B.Cu")
		(net "GND")
	)
	(via
		(at 49.403 -382.397)
		(size 0.5588)
		(drill 0.3048)
		(layers "F.Cu" "B.Cu")
		(net "GND")
	)
	(via
		(at 5.9436 -89.789)
		(size 0.5588)
		(drill 0.3048)
		(layers "F.Cu" "B.Cu")
		(net "GND")
	)
	(via
		(at 1.524 -155.448)
		(size 0.7112)
		(drill 0.4064)
		(layers "F.Cu" "B.Cu")
		(net "GND")
	)
	(via
		(at 24.892 -178.562)
		(size 0.5588)
		(drill 0.3048)
		(layers "F.Cu" "B.Cu")
		(net "GND")
	)
	(via
		(at 19.431 -235.458)
		(size 0.7112)
		(drill 0.4064)
		(layers "F.Cu" "B.Cu")
		(net "GND")
	)
	(via
		(at 5.588 -454.1012)
		(size 0.5588)
		(drill 0.3048)
		(layers "F.Cu" "B.Cu")
		(net "GND")
	)
	(via
		(at 51.435 -325.12)
		(size 0.5588)
		(drill 0.3048)
		(layers "F.Cu" "B.Cu")
		(net "GND")
	)
	(via
		(at 51.076606 -144.9324)
		(size 0.7112)
		(drill 0.4064)
		(layers "F.Cu" "B.Cu")
		(net "GND")
	)
	(via
		(at 12.4206 -353.187)
		(size 0.7112)
		(drill 0.4064)
		(layers "F.Cu" "B.Cu")
		(net "GND")
	)
	(via
		(at 29.972 -39.243)
		(size 0.7112)
		(drill 0.4064)
		(layers "F.Cu" "B.Cu")
		(net "GND")
	)
	(via
		(at 49.911 -202.438)
		(size 0.7112)
		(drill 0.4064)
		(layers "F.Cu" "B.Cu")
		(net "GND")
	)
	(via
		(at 50.8 -478.028)
		(size 0.7112)
		(drill 0.4064)
		(layers "F.Cu" "B.Cu")
		(net "GND")
	)
	(via
		(at 51.181 -236.601)
		(size 0.5588)
		(drill 0.3048)
		(layers "F.Cu" "B.Cu")
		(net "GND")
	)
	(via
		(at 42.926 -452.501)
		(size 0.7112)
		(drill 0.4064)
		(layers "F.Cu" "B.Cu")
		(net "GND")
	)
	(via
		(at 28.829 -201.295)
		(size 0.7112)
		(drill 0.4064)
		(layers "F.Cu" "B.Cu")
		(net "GND")
	)
	(via
		(at 49.53 -170.18)
		(size 0.7112)
		(drill 0.4064)
		(layers "F.Cu" "B.Cu")
		(net "GND")
	)
	(via
		(at 42.926 -362.3945)
		(size 0.5588)
		(drill 0.3048)
		(layers "F.Cu" "B.Cu")
		(net "GND")
	)
	(via
		(at 15.4432 -37.5158)
		(size 0.7112)
		(drill 0.4064)
		(layers "F.Cu" "B.Cu")
		(net "GND")
	)
	(via
		(at 10.16 -324.612)
		(size 0.7112)
		(drill 0.4064)
		(layers "F.Cu" "B.Cu")
		(net "GND")
	)
	(via
		(at 51.308 -180.34)
		(size 0.7112)
		(drill 0.4064)
		(layers "F.Cu" "B.Cu")
		(net "GND")
	)
	(via
		(at 6.604 -109.855)
		(size 0.7112)
		(drill 0.4064)
		(layers "F.Cu" "B.Cu")
		(net "GND")
	)
	(via
		(at 28.956 -323.596)
		(size 0.7112)
		(drill 0.4064)
		(layers "F.Cu" "B.Cu")
		(net "GND")
	)
	(via
		(at 44.069 -197.485)
		(size 0.7112)
		(drill 0.4064)
		(layers "F.Cu" "B.Cu")
		(net "GND")
	)
	(via
		(at 51.36134 -162.179)
		(size 0.5588)
		(drill 0.3048)
		(layers "F.Cu" "B.Cu")
		(net "GND")
	)
	(via
		(at 3.302 -81.534)
		(size 0.7112)
		(drill 0.4064)
		(layers "F.Cu" "B.Cu")
		(net "GND")
	)
	(via
		(at 29.083 -204.597)
		(size 0.7112)
		(drill 0.4064)
		(layers "F.Cu" "B.Cu")
		(net "GND")
	)
	(via
		(at 30.1498 -213.5378)
		(size 0.5588)
		(drill 0.3048)
		(layers "F.Cu" "B.Cu")
		(net "GND")
	)
	(via
		(at 26.035 -108.331)
		(size 0.7112)
		(drill 0.4064)
		(layers "F.Cu" "B.Cu")
		(net "GND")
	)
	(via
		(at 51.076606 -141.732)
		(size 0.7112)
		(drill 0.4064)
		(layers "F.Cu" "B.Cu")
		(net "GND")
	)
	(via
		(at 1.166876 -408.305)
		(size 0.7112)
		(drill 0.4064)
		(layers "F.Cu" "B.Cu")
		(net "GND")
	)
	(via
		(at 51.308 -64.516)
		(size 0.7112)
		(drill 0.4064)
		(layers "F.Cu" "B.Cu")
		(net "GND")
	)
	(via
		(at 3.175 -67.691)
		(size 0.7112)
		(drill 0.4064)
		(layers "F.Cu" "B.Cu")
		(net "GND")
	)
	(via
		(at 36.957 -153.416)
		(size 0.7112)
		(drill 0.4064)
		(layers "F.Cu" "B.Cu")
		(net "GND")
	)
	(via
		(at 6.858 -95.885)
		(size 0.7112)
		(drill 0.4064)
		(layers "F.Cu" "B.Cu")
		(net "GND")
	)
	(via
		(at 45.085 -206.248)
		(size 0.7112)
		(drill 0.4064)
		(layers "F.Cu" "B.Cu")
		(net "GND")
	)
	(via
		(at 14.9352 -358.7496)
		(size 0.7112)
		(drill 0.4064)
		(layers "F.Cu" "B.Cu")
		(net "GND")
	)
	(via
		(at 37.211 -360.075226)
		(size 0.7112)
		(drill 0.4064)
		(layers "F.Cu" "B.Cu")
		(net "GND")
	)
	(via
		(at 31.75 -245.618)
		(size 0.7112)
		(drill 0.4064)
		(layers "F.Cu" "B.Cu")
		(net "GND")
	)
	(via
		(at 4.572 -237.236)
		(size 0.7112)
		(drill 0.4064)
		(layers "F.Cu" "B.Cu")
		(net "GND")
	)
	(via
		(at 11.5316 -387.0452)
		(size 0.7112)
		(drill 0.4064)
		(layers "F.Cu" "B.Cu")
		(net "GND")
	)
	(via
		(at 5.8674 -86.9696)
		(size 0.5588)
		(drill 0.3048)
		(layers "F.Cu" "B.Cu")
		(net "GND")
	)
	(via
		(at 3.556 -155.956)
		(size 0.7112)
		(drill 0.4064)
		(layers "F.Cu" "B.Cu")
		(net "GND")
	)
	(via
		(at 48.26 -267.208)
		(size 0.7112)
		(drill 0.4064)
		(layers "F.Cu" "B.Cu")
		(net "GND")
	)
	(via
		(at 26.1874 -149.2504)
		(size 0.7112)
		(drill 0.4064)
		(layers "F.Cu" "B.Cu")
		(net "GND")
	)
	(via
		(at 16.129 -45.5422)
		(size 0.5588)
		(drill 0.3048)
		(layers "F.Cu" "B.Cu")
		(net "GND")
	)
	(via
		(at 1.166876 -364.617)
		(size 0.7112)
		(drill 0.4064)
		(layers "F.Cu" "B.Cu")
		(net "GND")
	)
	(via
		(at 51.181 -138.303)
		(size 0.7112)
		(drill 0.4064)
		(layers "F.Cu" "B.Cu")
		(net "GND")
	)
	(via
		(at 1.420876 -250.063)
		(size 0.7112)
		(drill 0.4064)
		(layers "F.Cu" "B.Cu")
		(net "GND")
	)
	(via
		(at 19.937476 -177.25009)
		(size 0.5588)
		(drill 0.3048)
		(layers "F.Cu" "B.Cu")
		(net "GND")
	)
	(via
		(at 48.895 -394.716)
		(size 0.7112)
		(drill 0.4064)
		(layers "F.Cu" "B.Cu")
		(net "GND")
	)
	(via
		(at 6.35 -498.475)
		(size 0.7112)
		(drill 0.4064)
		(layers "F.Cu" "B.Cu")
		(net "GND")
	)
	(via
		(at 6.6294 -276.5044)
		(size 0.7112)
		(drill 0.4064)
		(layers "F.Cu" "B.Cu")
		(net "GND")
	)
	(via
		(at 48.9204 -160.782)
		(size 0.7112)
		(drill 0.4064)
		(layers "F.Cu" "B.Cu")
		(net "GND")
	)
	(via
		(at 14.732 -333.248)
		(size 0.7112)
		(drill 0.4064)
		(layers "F.Cu" "B.Cu")
		(net "GND")
	)
	(via
		(at 14.224 -259.461)
		(size 0.5588)
		(drill 0.3048)
		(layers "F.Cu" "B.Cu")
		(net "GND")
	)
	(via
		(at 37.211 -354.8634)
		(size 0.5588)
		(drill 0.3048)
		(layers "F.Cu" "B.Cu")
		(net "GND")
	)
	(via
		(at 48.895 -167.259)
		(size 0.7112)
		(drill 0.4064)
		(layers "F.Cu" "B.Cu")
		(net "GND")
	)
	(via
		(at 1.1938 -425.7294)
		(size 0.7112)
		(drill 0.4064)
		(layers "F.Cu" "B.Cu")
		(net "GND")
	)
	(via
		(at 26.139902 -171.189142)
		(size 0.7112)
		(drill 0.4064)
		(layers "F.Cu" "B.Cu")
		(net "GND")
	)
	(via
		(at 11.6586 -389.3312)
		(size 0.7112)
		(drill 0.4064)
		(layers "F.Cu" "B.Cu")
		(net "GND")
	)
	(via
		(at 8.636 -372.3386)
		(size 0.7112)
		(drill 0.4064)
		(layers "F.Cu" "B.Cu")
		(net "GND")
	)
	(via
		(at 51.181 -100.965)
		(size 0.7112)
		(drill 0.4064)
		(layers "F.Cu" "B.Cu")
		(net "GND")
	)
	(via
		(at 31.652972 -243.647976)
		(size 0.7112)
		(drill 0.4064)
		(layers "F.Cu" "B.Cu")
		(net "GND")
	)
	(via
		(at 13.462 -43.561)
		(size 0.5588)
		(drill 0.3048)
		(layers "F.Cu" "B.Cu")
		(net "GND")
	)
	(via
		(at 47.117 -38.481)
		(size 0.7112)
		(drill 0.4064)
		(layers "F.Cu" "B.Cu")
		(net "GND")
	)
	(via
		(at 48.9204 -99.7204)
		(size 0.7112)
		(drill 0.4064)
		(layers "F.Cu" "B.Cu")
		(net "GND")
	)
	(via
		(at 40.513 -276.225)
		(size 0.7112)
		(drill 0.4064)
		(layers "F.Cu" "B.Cu")
		(net "GND")
	)
	(via
		(at 10.9474 -219.9894)
		(size 0.7112)
		(drill 0.3556)
		(layers "F.Cu" "B.Cu")
		(net "GND")
	)
	(via
		(at 51.076606 -80.137)
		(size 0.7112)
		(drill 0.4064)
		(layers "F.Cu" "B.Cu")
		(net "GND")
	)
	(via
		(at 35.306 -457.327)
		(size 0.7112)
		(drill 0.4064)
		(layers "F.Cu" "B.Cu")
		(net "GND")
	)
	(via
		(at 31.8516 -249.8344)
		(size 0.5588)
		(drill 0.3048)
		(layers "F.Cu" "B.Cu")
		(net "GND")
	)
	(via
		(at 30.48 -279.908)
		(size 0.7112)
		(drill 0.4064)
		(layers "F.Cu" "B.Cu")
		(net "GND")
	)
	(via
		(at 51.076606 -71.7804)
		(size 0.7112)
		(drill 0.4064)
		(layers "F.Cu" "B.Cu")
		(net "GND")
	)
	(via
		(at 48.641 -180.467)
		(size 0.7112)
		(drill 0.4064)
		(layers "F.Cu" "B.Cu")
		(net "GND")
	)
	(via
		(at 46.863 -487.807)
		(size 0.5588)
		(drill 0.3048)
		(layers "F.Cu" "B.Cu")
		(net "GND")
	)
	(via
		(at 6.223 -216.789)
		(size 0.7112)
		(drill 0.4064)
		(layers "F.Cu" "B.Cu")
		(net "GND")
	)
	(via
		(at 51.435 -240.157)
		(size 0.5588)
		(drill 0.3048)
		(layers "F.Cu" "B.Cu")
		(net "GND")
	)
	(via
		(at 51.308 -69.596)
		(size 0.7112)
		(drill 0.4064)
		(layers "F.Cu" "B.Cu")
		(net "GND")
	)
	(via
		(at 7.874 -177.927)
		(size 0.7112)
		(drill 0.4064)
		(layers "F.Cu" "B.Cu")
		(net "GND")
	)
	(via
		(at 11.2776 -404.3934)
		(size 0.7112)
		(drill 0.4064)
		(layers "F.Cu" "B.Cu")
		(net "GND")
	)
	(via
		(at 28.956 -203.2)
		(size 0.7112)
		(drill 0.4064)
		(layers "F.Cu" "B.Cu")
		(net "GND")
	)
	(via
		(at 7.112 -272.288)
		(size 0.7112)
		(drill 0.4064)
		(layers "F.Cu" "B.Cu")
		(net "GND")
	)
	(via
		(at 1.166876 -181.356)
		(size 0.5588)
		(drill 0.3048)
		(layers "F.Cu" "B.Cu")
		(net "GND")
	)
	(via
		(at 20.066 -16.637)
		(size 0.5588)
		(drill 0.3048)
		(layers "F.Cu" "B.Cu")
		(net "GND")
	)
	(via
		(at 29.21 -11.43)
		(size 0.7112)
		(drill 0.4064)
		(layers "F.Cu" "B.Cu")
		(net "GND")
	)
	(via
		(at 31.877 -233.68)
		(size 0.7112)
		(drill 0.4064)
		(layers "F.Cu" "B.Cu")
		(net "GND")
	)
	(via
		(at 49.403 -383.54)
		(size 0.5588)
		(drill 0.3048)
		(layers "F.Cu" "B.Cu")
		(net "GND")
	)
	(via
		(at 3.3274 -439.1406)
		(size 0.7112)
		(drill 0.4064)
		(layers "F.Cu" "B.Cu")
		(net "GND")
	)
	(via
		(at 7.112 -330.2)
		(size 0.7112)
		(drill 0.4064)
		(layers "F.Cu" "B.Cu")
		(net "GND")
	)
	(via
		(at 7.493 -87.249)
		(size 0.5588)
		(drill 0.3048)
		(layers "F.Cu" "B.Cu")
		(net "GND")
	)
	(via
		(at 19.05 -478.028)
		(size 0.7112)
		(drill 0.3556)
		(layers "F.Cu" "B.Cu")
		(net "GND")
	)
	(via
		(at 29.845 -259.969)
		(size 0.7112)
		(drill 0.4064)
		(layers "F.Cu" "B.Cu")
		(net "GND")
	)
	(via
		(at 12.7 -180.975)
		(size 0.7112)
		(drill 0.4064)
		(layers "F.Cu" "B.Cu")
		(net "GND")
	)
	(via
		(at 18.796 -15.367)
		(size 0.5588)
		(drill 0.3048)
		(layers "F.Cu" "B.Cu")
		(net "GND")
	)
	(via
		(at 15.1384 -31.9532)
		(size 0.5588)
		(drill 0.3048)
		(layers "F.Cu" "B.Cu")
		(net "GND")
	)
	(via
		(at 46.99 -441.579)
		(size 0.7112)
		(drill 0.4064)
		(layers "F.Cu" "B.Cu")
		(net "GND")
	)
	(via
		(at 1.524 -334.772)
		(size 0.7112)
		(drill 0.4064)
		(layers "F.Cu" "B.Cu")
		(net "GND")
	)
	(via
		(at 34.163 -224.917)
		(size 0.7112)
		(drill 0.4064)
		(layers "F.Cu" "B.Cu")
		(net "GND")
	)
	(via
		(at 44.069 -188.087)
		(size 0.7112)
		(drill 0.3556)
		(layers "F.Cu" "B.Cu")
		(net "GND")
	)
	(via
		(at 9.7536 -405.5618)
		(size 0.5588)
		(drill 0.3048)
		(layers "F.Cu" "B.Cu")
		(net "GND")
	)
	(via
		(at 46.355 -192.659)
		(size 0.7112)
		(drill 0.4064)
		(layers "F.Cu" "B.Cu")
		(net "GND")
	)
	(via
		(at 48.8442 -104.3813)
		(size 0.7112)
		(drill 0.4064)
		(layers "F.Cu" "B.Cu")
		(net "GND")
	)
	(via
		(at 8.636 -429.641)
		(size 0.5588)
		(drill 0.3048)
		(layers "F.Cu" "B.Cu")
		(net "GND")
	)
	(via
		(at 7.8232 -33.0962)
		(size 0.7112)
		(drill 0.4064)
		(layers "F.Cu" "B.Cu")
		(net "GND")
	)
	(via
		(at 40.005 -217.932)
		(size 0.7112)
		(drill 0.4064)
		(layers "F.Cu" "B.Cu")
		(net "GND")
	)
	(via
		(at 1.547876 -208.153)
		(size 0.7112)
		(drill 0.4064)
		(layers "F.Cu" "B.Cu")
		(net "GND")
	)
	(via
		(at 1.420876 -174.879)
		(size 0.7112)
		(drill 0.4064)
		(layers "F.Cu" "B.Cu")
		(net "GND")
	)
	(via
		(at 39.497 -261.62)
		(size 0.5588)
		(drill 0.3048)
		(layers "F.Cu" "B.Cu")
		(net "GND")
	)
	(via
		(at 51.181 -274.955)
		(size 0.5588)
		(drill 0.3048)
		(layers "F.Cu" "B.Cu")
		(net "GND")
	)
	(via
		(at 4.064 -295.148)
		(size 0.7112)
		(drill 0.4064)
		(layers "F.Cu" "B.Cu")
		(net "GND")
	)
	(via
		(at 46.99 -233.045)
		(size 0.7112)
		(drill 0.4064)
		(layers "F.Cu" "B.Cu")
		(net "GND")
	)
	(via
		(at 18.388838 -134.187438)
		(size 0.5588)
		(drill 0.3048)
		(layers "F.Cu" "B.Cu")
		(net "GND")
	)
	(via
		(at 24.7142 -251.6632)
		(size 0.5588)
		(drill 0.3048)
		(layers "F.Cu" "B.Cu")
		(net "GND")
	)
	(via
		(at 20.828 -165.608)
		(size 0.5588)
		(drill 0.3048)
		(layers "F.Cu" "B.Cu")
		(net "GND")
	)
	(via
		(at 49.657 -483.87)
		(size 0.7112)
		(drill 0.4064)
		(layers "F.Cu" "B.Cu")
		(net "GND")
	)
	(via
		(at 28.067 -282.448)
		(size 0.7112)
		(drill 0.4064)
		(layers "F.Cu" "B.Cu")
		(net "GND")
	)
	(via
		(at 51.308 -188.087)
		(size 0.7112)
		(drill 0.4064)
		(layers "F.Cu" "B.Cu")
		(net "GND")
	)
	(via
		(at 23.622 -177.419)
		(size 0.5588)
		(drill 0.3048)
		(layers "F.Cu" "B.Cu")
		(net "GND")
	)
	(via
		(at 51.36134 -229.489)
		(size 0.5588)
		(drill 0.3048)
		(layers "F.Cu" "B.Cu")
		(net "GND")
	)
	(via
		(at 31.75 -220.599)
		(size 0.7112)
		(drill 0.4064)
		(layers "F.Cu" "B.Cu")
		(net "GND")
	)
	(via
		(at 50.8 -21.59)
		(size 0.7112)
		(drill 0.4064)
		(layers "F.Cu" "B.Cu")
		(net "GND")
	)
	(via
		(at 34.671 -245.618)
		(size 0.7112)
		(drill 0.4064)
		(layers "F.Cu" "B.Cu")
		(net "GND")
	)
	(via
		(at 46.609 -270.637)
		(size 0.7112)
		(drill 0.4064)
		(layers "F.Cu" "B.Cu")
		(net "GND")
	)
	(via
		(at 1.27 -56.134)
		(size 0.7112)
		(drill 0.4064)
		(layers "F.Cu" "B.Cu")
		(net "GND")
	)
	(via
		(at 17.399 -369.4684)
		(size 0.7112)
		(drill 0.4064)
		(layers "F.Cu" "B.Cu")
		(net "GND")
	)
	(via
		(at 51.181 -331.851)
		(size 0.5588)
		(drill 0.3048)
		(layers "F.Cu" "B.Cu")
		(net "GND")
	)
	(via
		(at 14.732 -310.388)
		(size 0.7112)
		(drill 0.4064)
		(layers "F.Cu" "B.Cu")
		(net "GND")
	)
	(via
		(at 13.7668 -52.7939)
		(size 0.5588)
		(drill 0.3048)
		(layers "F.Cu" "B.Cu")
		(net "GND")
	)
	(via
		(at 17.9832 -251.587)
		(size 0.5588)
		(drill 0.3048)
		(layers "F.Cu" "B.Cu")
		(net "GND")
	)
	(via
		(at 31.7754 -356.235)
		(size 0.5588)
		(drill 0.3048)
		(layers "F.Cu" "B.Cu")
		(net "GND")
	)
	(via
		(at 19.685 -232.918)
		(size 0.7112)
		(drill 0.4064)
		(layers "F.Cu" "B.Cu")
		(net "GND")
	)
	(via
		(at 25.146254 -176.495964)
		(size 0.7112)
		(drill 0.4064)
		(layers "F.Cu" "B.Cu")
		(net "GND")
	)
	(via
		(at 4.572 -233.68)
		(size 0.7112)
		(drill 0.4064)
		(layers "F.Cu" "B.Cu")
		(net "GND")
	)
	(via
		(at 27.178 -108.331)
		(size 0.7112)
		(drill 0.4064)
		(layers "F.Cu" "B.Cu")
		(net "GND")
	)
	(via
		(at 41.0464 -187.9092)
		(size 0.5588)
		(drill 0.3048)
		(layers "F.Cu" "B.Cu")
		(net "GND")
	)
	(via
		(at 4.064 -206.756)
		(size 0.7112)
		(drill 0.4064)
		(layers "F.Cu" "B.Cu")
		(net "GND")
	)
	(via
		(at 51.181 -212.217)
		(size 0.7112)
		(drill 0.4064)
		(layers "F.Cu" "B.Cu")
		(net "GND")
	)
	(via
		(at 33.147 -245.364)
		(size 0.7112)
		(drill 0.4064)
		(layers "F.Cu" "B.Cu")
		(net "GND")
	)
	(via
		(at 15.3924 -361.5944)
		(size 0.7112)
		(drill 0.4064)
		(layers "F.Cu" "B.Cu")
		(net "GND")
	)
	(via
		(at 4.318 -9.271)
		(size 0.7112)
		(drill 0.4064)
		(layers "F.Cu" "B.Cu")
		(net "GND")
	)
	(via
		(at 27.4574 -121.3231)
		(size 0.5588)
		(drill 0.3048)
		(layers "F.Cu" "B.Cu")
		(net "GND")
	)
	(via
		(at 10.668 -315.468)
		(size 0.7112)
		(drill 0.4064)
		(layers "F.Cu" "B.Cu")
		(net "GND")
	)
	(via
		(at 48.768 -138.049)
		(size 0.7112)
		(drill 0.4064)
		(layers "F.Cu" "B.Cu")
		(net "GND")
	)
	(via
		(at 31.4452 -333.2226)
		(size 0.7112)
		(drill 0.4064)
		(layers "F.Cu" "B.Cu")
		(net "GND")
	)
	(via
		(at 26.924 -180.086)
		(size 0.5588)
		(drill 0.3048)
		(layers "F.Cu" "B.Cu")
		(net "GND")
	)
	(via
		(at 51.308 -226.06)
		(size 0.5588)
		(drill 0.3048)
		(layers "F.Cu" "B.Cu")
		(net "GND")
	)
	(via
		(at 29.21 -233.68)
		(size 0.7112)
		(drill 0.4064)
		(layers "F.Cu" "B.Cu")
		(net "GND")
	)
	(via
		(at 1.166876 -264.541)
		(size 0.7112)
		(drill 0.4064)
		(layers "F.Cu" "B.Cu")
		(net "GND")
	)
	(via
		(at 50.165 -173.99)
		(size 0.7112)
		(drill 0.4064)
		(layers "F.Cu" "B.Cu")
		(net "GND")
	)
	(via
		(at 12.446 -358.9782)
		(size 0.7112)
		(drill 0.4064)
		(layers "F.Cu" "B.Cu")
		(net "GND")
	)
	(via
		(at 44.704 -258.699)
		(size 0.7112)
		(drill 0.4064)
		(layers "F.Cu" "B.Cu")
		(net "GND")
	)
	(via
		(at 11.684 -215.392)
		(size 0.7112)
		(drill 0.4064)
		(layers "F.Cu" "B.Cu")
		(net "GND")
	)
	(via
		(at 31.496 -230.886)
		(size 0.7112)
		(drill 0.4064)
		(layers "F.Cu" "B.Cu")
		(net "GND")
	)
	(via
		(at 16.891 -364.109)
		(size 0.7112)
		(drill 0.4064)
		(layers "F.Cu" "B.Cu")
		(net "GND")
	)
	(via
		(at 14.605 -250.9012)
		(size 0.5588)
		(drill 0.3048)
		(layers "F.Cu" "B.Cu")
		(net "GND")
	)
	(via
		(at 36.0934 -147.6756)
		(size 0.5588)
		(drill 0.3048)
		(layers "F.Cu" "B.Cu")
		(net "GND")
	)
	(via
		(at 46.863 -82.677)
		(size 0.7112)
		(drill 0.4064)
		(layers "F.Cu" "B.Cu")
		(net "GND")
	)
	(via
		(at 28.956 -334.772)
		(size 0.7112)
		(drill 0.4064)
		(layers "F.Cu" "B.Cu")
		(net "GND")
	)
	(via
		(at 1.397 -75.057)
		(size 0.7112)
		(drill 0.4064)
		(layers "F.Cu" "B.Cu")
		(net "GND")
	)
	(via
		(at 43.18 -276.733)
		(size 0.7112)
		(drill 0.4064)
		(layers "F.Cu" "B.Cu")
		(net "GND")
	)
	(via
		(at 31.496 -329.692)
		(size 0.7112)
		(drill 0.4064)
		(layers "F.Cu" "B.Cu")
		(net "GND")
	)
	(via
		(at 46.1518 -195.1736)
		(size 0.7112)
		(drill 0.4064)
		(layers "F.Cu" "B.Cu")
		(net "GND")
	)
	(via
		(at 17.653 -238.506)
		(size 0.7112)
		(drill 0.4064)
		(layers "F.Cu" "B.Cu")
		(net "GND")
	)
	(via
		(at 25.146 -321.437)
		(size 0.7112)
		(drill 0.4064)
		(layers "F.Cu" "B.Cu")
		(net "GND")
	)
	(via
		(at 28.9052 -338.3026)
		(size 0.7112)
		(drill 0.4064)
		(layers "F.Cu" "B.Cu")
		(net "GND")
	)
	(via
		(at 24.257 -213.741)
		(size 0.7112)
		(drill 0.4064)
		(layers "F.Cu" "B.Cu")
		(net "GND")
	)
	(via
		(at 23.1394 -488.3912)
		(size 0.5588)
		(drill 0.3048)
		(layers "F.Cu" "B.Cu")
		(net "GND")
	)
	(via
		(at 15.621 -238.379)
		(size 0.7112)
		(drill 0.4064)
		(layers "F.Cu" "B.Cu")
		(net "GND")
	)
	(via
		(at 8.4074 -403.1996)
		(size 0.7112)
		(drill 0.4064)
		(layers "F.Cu" "B.Cu")
		(net "GND")
	)
	(via
		(at 48.641 -189.611)
		(size 0.7112)
		(drill 0.4064)
		(layers "F.Cu" "B.Cu")
		(net "GND")
	)
	(via
		(at 41.2242 -167.4114)
		(size 0.7112)
		(drill 0.4064)
		(layers "F.Cu" "B.Cu")
		(net "GND")
	)
	(via
		(at 26.416 -266.573)
		(size 0.5588)
		(drill 0.3048)
		(layers "F.Cu" "B.Cu")
		(net "GND")
	)
	(via
		(at 1.143 -51.435)
		(size 0.7112)
		(drill 0.4064)
		(layers "F.Cu" "B.Cu")
		(net "GND")
	)
	(via
		(at 13.335 -446.024)
		(size 0.5588)
		(drill 0.3048)
		(layers "F.Cu" "B.Cu")
		(net "GND")
	)
	(via
		(at 51.308 -307.848)
		(size 0.5588)
		(drill 0.3048)
		(layers "F.Cu" "B.Cu")
		(net "GND")
	)
	(via
		(at 48.895 -396.875)
		(size 0.7112)
		(drill 0.4064)
		(layers "F.Cu" "B.Cu")
		(net "GND")
	)
	(via
		(at 8.128 -282.956)
		(size 0.7112)
		(drill 0.4064)
		(layers "F.Cu" "B.Cu")
		(net "GND")
	)
	(via
		(at 14.732 -323.088)
		(size 0.7112)
		(drill 0.4064)
		(layers "F.Cu" "B.Cu")
		(net "GND")
	)
	(via
		(at 37.4904 -38.3286)
		(size 0.7112)
		(drill 0.4064)
		(layers "F.Cu" "B.Cu")
		(net "GND")
	)
	(via
		(at 28.9052 -327.1266)
		(size 0.7112)
		(drill 0.4064)
		(layers "F.Cu" "B.Cu")
		(net "GND")
	)
	(via
		(at 6.858 -46.228)
		(size 0.7112)
		(drill 0.4064)
		(layers "F.Cu" "B.Cu")
		(net "GND")
	)
	(via
		(at 37.338 -342.392)
		(size 0.7112)
		(drill 0.4064)
		(layers "F.Cu" "B.Cu")
		(net "GND")
	)
	(via
		(at 50.038 -207.01)
		(size 0.7112)
		(drill 0.4064)
		(layers "F.Cu" "B.Cu")
		(net "GND")
	)
	(via
		(at 16.152876 -1.778)
		(size 0.7112)
		(drill 0.4064)
		(layers "F.Cu" "B.Cu")
		(net "GND")
	)
	(via
		(at 10.795 -431.673)
		(size 0.7112)
		(drill 0.4064)
		(layers "F.Cu" "B.Cu")
		(net "GND")
	)
	(via
		(at 41.4528 -250.2408)
		(size 0.5588)
		(drill 0.3048)
		(layers "F.Cu" "B.Cu")
		(net "GND")
	)
	(via
		(at 1.524 -289.052)
		(size 0.7112)
		(drill 0.4064)
		(layers "F.Cu" "B.Cu")
		(net "GND")
	)
	(via
		(at 31.7246 -147.828)
		(size 0.5588)
		(drill 0.3048)
		(layers "F.Cu" "B.Cu")
		(net "GND")
	)
	(via
		(at 19.558 -368.046)
		(size 0.7112)
		(drill 0.4064)
		(layers "F.Cu" "B.Cu")
		(net "GND")
	)
	(via
		(at 1.651 -498.348)
		(size 0.7112)
		(drill 0.4064)
		(layers "F.Cu" "B.Cu")
		(net "GND")
	)
	(via
		(at 10.668 -203.708)
		(size 0.7112)
		(drill 0.4064)
		(layers "F.Cu" "B.Cu")
		(net "GND")
	)
	(via
		(at 16.51 -42.2402)
		(size 0.5588)
		(drill 0.3048)
		(layers "F.Cu" "B.Cu")
		(net "GND")
	)
	(via
		(at 1.166876 -414.528)
		(size 0.7112)
		(drill 0.4064)
		(layers "F.Cu" "B.Cu")
		(net "GND")
	)
	(via
		(at 16.5862 -479.1964)
		(size 0.5588)
		(drill 0.3048)
		(layers "F.Cu" "B.Cu")
		(net "GND")
	)
	(via
		(at 48.895 -246.888)
		(size 0.7112)
		(drill 0.4064)
		(layers "F.Cu" "B.Cu")
		(net "GND")
	)
	(via
		(at 25.527 -351.663)
		(size 0.7112)
		(drill 0.4064)
		(layers "F.Cu" "B.Cu")
		(net "GND")
	)
	(via
		(at 3.429 -74.93)
		(size 0.7112)
		(drill 0.4064)
		(layers "F.Cu" "B.Cu")
		(net "GND")
	)
	(via
		(at 7.874 -325.247)
		(size 0.7112)
		(drill 0.3556)
		(layers "F.Cu" "B.Cu")
		(net "GND")
	)
	(via
		(at 13.843 -479.933)
		(size 0.7112)
		(drill 0.4064)
		(layers "F.Cu" "B.Cu")
		(net "GND")
	)
	(via
		(at 42.2402 -259.4102)
		(size 0.7112)
		(drill 0.4064)
		(layers "F.Cu" "B.Cu")
		(net "GND")
	)
	(via
		(at 10.795 -424.942)
		(size 0.5588)
		(drill 0.3048)
		(layers "F.Cu" "B.Cu")
		(net "GND")
	)
	(via
		(at 8.636 -247.523)
		(size 0.7112)
		(drill 0.4064)
		(layers "F.Cu" "B.Cu")
		(net "GND")
	)
	(via
		(at 20.2946 -488.442)
		(size 0.5588)
		(drill 0.3048)
		(layers "F.Cu" "B.Cu")
		(net "GND")
	)
	(via
		(at 8.6868 -72.3392)
		(size 0.5588)
		(drill 0.3048)
		(layers "F.Cu" "B.Cu")
		(net "GND")
	)
	(via
		(at 37.211 -315.341)
		(size 0.7112)
		(drill 0.4064)
		(layers "F.Cu" "B.Cu")
		(net "GND")
	)
	(via
		(at 9.525 -230.505)
		(size 0.7112)
		(drill 0.4064)
		(layers "F.Cu" "B.Cu")
		(net "GND")
	)
	(via
		(at 15.899892 -35.840162)
		(size 0.7112)
		(drill 0.4064)
		(layers "F.Cu" "B.Cu")
		(net "GND")
	)
	(via
		(at 13.1826 -37.0078)
		(size 0.7112)
		(drill 0.4064)
		(layers "F.Cu" "B.Cu")
		(net "GND")
	)
	(via
		(at 45.085 -209.931)
		(size 0.7112)
		(drill 0.4064)
		(layers "F.Cu" "B.Cu")
		(net "GND")
	)
	(via
		(at 41.8973 -156.3878)
		(size 0.7112)
		(drill 0.4064)
		(layers "F.Cu" "B.Cu")
		(net "GND")
	)
	(via
		(at 18.288 -345.44)
		(size 0.7112)
		(drill 0.4064)
		(layers "F.Cu" "B.Cu")
		(net "GND")
	)
	(via
		(at 13.1318 -33.4518)
		(size 0.7112)
		(drill 0.4064)
		(layers "F.Cu" "B.Cu")
		(net "GND")
	)
	(via
		(at 9.144 -66.138044)
		(size 0.5588)
		(drill 0.3048)
		(layers "F.Cu" "B.Cu")
		(net "GND")
	)
	(via
		(at 18.4658 -376.047)
		(size 0.7112)
		(drill 0.4064)
		(layers "F.Cu" "B.Cu")
		(net "GND")
	)
	(via
		(at 1.27 -34.925)
		(size 0.7112)
		(drill 0.4064)
		(layers "F.Cu" "B.Cu")
		(net "GND")
	)
	(via
		(at 29.464 -342.9)
		(size 0.7112)
		(drill 0.4064)
		(layers "F.Cu" "B.Cu")
		(net "GND")
	)
	(via
		(at 30.4292 -144.3482)
		(size 0.5588)
		(drill 0.3048)
		(layers "F.Cu" "B.Cu")
		(net "GND")
	)
	(via
		(at 19.9136 -148.2598)
		(size 0.5588)
		(drill 0.3048)
		(layers "F.Cu" "B.Cu")
		(net "GND")
	)
	(via
		(at 26.67 -31.75)
		(size 0.7112)
		(drill 0.4064)
		(layers "F.Cu" "B.Cu")
		(net "GND")
	)
	(via
		(at 45.339 -322.199)
		(size 0.7112)
		(drill 0.3556)
		(layers "F.Cu" "B.Cu")
		(net "GND")
	)
	(via
		(at 6.096 -53.848)
		(size 0.7112)
		(drill 0.4064)
		(layers "F.Cu" "B.Cu")
		(net "GND")
	)
	(via
		(at 10.0838 -474.9038)
		(size 0.7112)
		(drill 0.4064)
		(layers "F.Cu" "B.Cu")
		(net "GND")
	)
	(via
		(at 51.181 -143.256)
		(size 0.7112)
		(drill 0.4064)
		(layers "F.Cu" "B.Cu")
		(net "GND")
	)
	(via
		(at 45.974 -274.193)
		(size 0.7112)
		(drill 0.4064)
		(layers "F.Cu" "B.Cu")
		(net "GND")
	)
	(via
		(at 11.0744 -423.7482)
		(size 0.5588)
		(drill 0.3048)
		(layers "F.Cu" "B.Cu")
		(net "GND")
	)
	(via
		(at 45.6946 -235.1278)
		(size 0.5588)
		(drill 0.3048)
		(layers "F.Cu" "B.Cu")
		(net "GND")
	)
	(via
		(at 31.242 -205.359)
		(size 0.7112)
		(drill 0.4064)
		(layers "F.Cu" "B.Cu")
		(net "GND")
	)
	(via
		(at 23.241 -333.883)
		(size 0.7112)
		(drill 0.4064)
		(layers "F.Cu" "B.Cu")
		(net "GND")
	)
	(via
		(at 22.098 -164.592)
		(size 0.5588)
		(drill 0.3048)
		(layers "F.Cu" "B.Cu")
		(net "GND")
	)
	(via
		(at 51.076606 -103.378)
		(size 0.7112)
		(drill 0.4064)
		(layers "F.Cu" "B.Cu")
		(net "GND")
	)
	(via
		(at 49.149 -264.795)
		(size 0.7112)
		(drill 0.4064)
		(layers "F.Cu" "B.Cu")
		(net "GND")
	)
	(via
		(at 18.2372 -178.1302)
		(size 0.7112)
		(drill 0.4064)
		(layers "F.Cu" "B.Cu")
		(net "GND")
	)
	(via
		(at 36.576 -233.553)
		(size 0.7112)
		(drill 0.4064)
		(layers "F.Cu" "B.Cu")
		(net "GND")
	)
	(via
		(at 49.53 -282.448)
		(size 0.5588)
		(drill 0.3048)
		(layers "F.Cu" "B.Cu")
		(net "GND")
	)
	(via
		(at 2.032 -172.212)
		(size 0.7112)
		(drill 0.4064)
		(layers "F.Cu" "B.Cu")
		(net "GND")
	)
	(via
		(at 46.9138 -168.6306)
		(size 0.7112)
		(drill 0.4064)
		(layers "F.Cu" "B.Cu")
		(net "GND")
	)
	(via
		(at 17.907 -350.139)
		(size 0.7112)
		(drill 0.4064)
		(layers "F.Cu" "B.Cu")
		(net "GND")
	)
	(via
		(at 44.45 -272.415)
		(size 0.7112)
		(drill 0.4064)
		(layers "F.Cu" "B.Cu")
		(net "GND")
	)
	(via
		(at 16.383 -10.16)
		(size 0.7112)
		(drill 0.4064)
		(layers "F.Cu" "B.Cu")
		(net "GND")
	)
	(via
		(at 36.322 -231.267)
		(size 0.7112)
		(drill 0.4064)
		(layers "F.Cu" "B.Cu")
		(net "GND")
	)
	(via
		(at 50.419 -472.313)
		(size 0.7112)
		(drill 0.4064)
		(layers "F.Cu" "B.Cu")
		(net "GND")
	)
	(via
		(at 44.069 -38.481)
		(size 0.7112)
		(drill 0.4064)
		(layers "F.Cu" "B.Cu")
		(net "GND")
	)
	(via
		(at 21.082 -248.8692)
		(size 0.5588)
		(drill 0.3048)
		(layers "F.Cu" "B.Cu")
		(net "GND")
	)
	(via
		(at 46.609 -177.292)
		(size 0.7112)
		(drill 0.4064)
		(layers "F.Cu" "B.Cu")
		(net "GND")
	)
	(via
		(at 25.61844 -356.17404)
		(size 0.5588)
		(drill 0.3048)
		(layers "F.Cu" "B.Cu")
		(net "GND")
	)
	(via
		(at 27.6606 -137.4902)
		(size 0.5588)
		(drill 0.3048)
		(layers "F.Cu" "B.Cu")
		(net "GND")
	)
	(via
		(at 28.067 -266.954)
		(size 0.7112)
		(drill 0.4064)
		(layers "F.Cu" "B.Cu")
		(net "GND")
	)
	(via
		(at 19.7104 -215.6714)
		(size 0.7112)
		(drill 0.4064)
		(layers "F.Cu" "B.Cu")
		(net "GND")
	)
	(via
		(at 48.7426 -42.5958)
		(size 0.7112)
		(drill 0.4064)
		(layers "F.Cu" "B.Cu")
		(net "GND")
	)
	(via
		(at 50.8 -106.807)
		(size 0.7112)
		(drill 0.4064)
		(layers "F.Cu" "B.Cu")
		(net "GND")
	)
	(via
		(at 45.9994 -92.4687)
		(size 0.7112)
		(drill 0.4064)
		(layers "F.Cu" "B.Cu")
		(net "GND")
	)
	(via
		(at 8.128 -10.16)
		(size 0.7112)
		(drill 0.4064)
		(layers "F.Cu" "B.Cu")
		(net "GND")
	)
	(via
		(at 12.446 -4.699)
		(size 0.7112)
		(drill 0.4064)
		(layers "F.Cu" "B.Cu")
		(net "GND")
	)
	(via
		(at 14.986 -373.888)
		(size 0.7112)
		(drill 0.4064)
		(layers "F.Cu" "B.Cu")
		(net "GND")
	)
	(via
		(at 4.572 -154.432)
		(size 0.7112)
		(drill 0.4064)
		(layers "F.Cu" "B.Cu")
		(net "GND")
	)
	(via
		(at 4.572 -180.848)
		(size 0.7112)
		(drill 0.4064)
		(layers "F.Cu" "B.Cu")
		(net "GND")
	)
	(via
		(at 26.416 -269.875)
		(size 0.5588)
		(drill 0.3048)
		(layers "F.Cu" "B.Cu")
		(net "GND")
	)
	(via
		(at 37.465 -347.091)
		(size 0.7112)
		(drill 0.4064)
		(layers "F.Cu" "B.Cu")
		(net "GND")
	)
	(via
		(at 3.683 -28.575)
		(size 0.7112)
		(drill 0.4064)
		(layers "F.Cu" "B.Cu")
		(net "GND")
	)
	(via
		(at 51.181 -197.358)
		(size 0.5588)
		(drill 0.3048)
		(layers "F.Cu" "B.Cu")
		(net "GND")
	)
	(via
		(at 30.734 -195.0466)
		(size 0.7112)
		(drill 0.4064)
		(layers "F.Cu" "B.Cu")
		(net "GND")
	)
	(via
		(at 29.21 -281.559)
		(size 0.7112)
		(drill 0.4064)
		(layers "F.Cu" "B.Cu")
		(net "GND")
	)
	(via
		(at 6.096 -192.024)
		(size 0.7112)
		(drill 0.4064)
		(layers "F.Cu" "B.Cu")
		(net "GND")
	)
	(via
		(at 48.895 -216.662)
		(size 0.7112)
		(drill 0.4064)
		(layers "F.Cu" "B.Cu")
		(net "GND")
	)
	(via
		(at 36.0172 -142.0495)
		(size 0.7112)
		(drill 0.4064)
		(layers "F.Cu" "B.Cu")
		(net "GND")
	)
	(via
		(at 27.178 -229.362)
		(size 0.7112)
		(drill 0.4064)
		(layers "F.Cu" "B.Cu")
		(net "GND")
	)
	(via
		(at 26.67 -303.784)
		(size 0.7112)
		(drill 0.4064)
		(layers "F.Cu" "B.Cu")
		(net "GND")
	)
	(via
		(at 51.054 -488.442)
		(size 0.7112)
		(drill 0.4064)
		(layers "F.Cu" "B.Cu")
		(net "GND")
	)
	(via
		(at 48.7172 -59.6646)
		(size 0.7112)
		(drill 0.4064)
		(layers "F.Cu" "B.Cu")
		(net "GND")
	)
	(via
		(at 1.166876 -158.75)
		(size 0.7112)
		(drill 0.4064)
		(layers "F.Cu" "B.Cu")
		(net "GND")
	)
	(via
		(at 13.208 -329.2602)
		(size 0.7112)
		(drill 0.4064)
		(layers "F.Cu" "B.Cu")
		(net "GND")
	)
	(via
		(at 49.911 -402.844)
		(size 0.7112)
		(drill 0.4064)
		(layers "F.Cu" "B.Cu")
		(net "GND")
	)
	(via
		(at 51.308 -205.105)
		(size 0.7112)
		(drill 0.4064)
		(layers "F.Cu" "B.Cu")
		(net "GND")
	)
	(via
		(at 7.493 -104.267)
		(size 0.5588)
		(drill 0.3048)
		(layers "F.Cu" "B.Cu")
		(net "GND")
	)
	(via
		(at 51.181 -258.826)
		(size 0.5588)
		(drill 0.3048)
		(layers "F.Cu" "B.Cu")
		(net "GND")
	)
	(via
		(at 31.5468 -144.3736)
		(size 0.5588)
		(drill 0.3048)
		(layers "F.Cu" "B.Cu")
		(net "GND")
	)
	(via
		(at 29.591 -273.304)
		(size 0.7112)
		(drill 0.4064)
		(layers "F.Cu" "B.Cu")
		(net "GND")
	)
	(via
		(at 44.4754 -180.34)
		(size 0.5588)
		(drill 0.3048)
		(layers "F.Cu" "B.Cu")
		(net "GND")
	)
	(via
		(at 14.4018 -355.6254)
		(size 0.7112)
		(drill 0.4064)
		(layers "F.Cu" "B.Cu")
		(net "GND")
	)
	(via
		(at 50.292 -466.979)
		(size 0.7112)
		(drill 0.4064)
		(layers "F.Cu" "B.Cu")
		(net "GND")
	)
	(via
		(at 1.293876 -493.903)
		(size 0.7112)
		(drill 0.4064)
		(layers "F.Cu" "B.Cu")
		(net "GND")
	)
	(via
		(at 46.736 -14.097)
		(size 0.7112)
		(drill 0.4064)
		(layers "F.Cu" "B.Cu")
		(net "GND")
	)
	(via
		(at 5.715 -48.26)
		(size 0.7112)
		(drill 0.4064)
		(layers "F.Cu" "B.Cu")
		(net "GND")
	)
	(via
		(at 18.2372 -348.9706)
		(size 0.7112)
		(drill 0.4064)
		(layers "F.Cu" "B.Cu")
		(net "GND")
	)
	(via
		(at 18.161 -186.817)
		(size 0.5588)
		(drill 0.3048)
		(layers "F.Cu" "B.Cu")
		(net "GND")
	)
	(via
		(at 6.604 -185.928)
		(size 0.7112)
		(drill 0.4064)
		(layers "F.Cu" "B.Cu")
		(net "GND")
	)
	(via
		(at 46.228 -241.427)
		(size 0.7112)
		(drill 0.4064)
		(layers "F.Cu" "B.Cu")
		(net "GND")
	)
	(via
		(at 41.489376 -300.0248)
		(size 0.7112)
		(drill 0.4064)
		(layers "F.Cu" "B.Cu")
		(net "GND")
	)
	(via
		(at 35.306 -434.975)
		(size 0.7112)
		(drill 0.4064)
		(layers "F.Cu" "B.Cu")
		(net "GND")
	)
	(via
		(at 1.347216 -112.903)
		(size 0.7112)
		(drill 0.4064)
		(layers "F.Cu" "B.Cu")
		(net "GND")
	)
	(via
		(at 23.876 -246.8372)
		(size 0.5588)
		(drill 0.3048)
		(layers "F.Cu" "B.Cu")
		(net "GND")
	)
	(via
		(at 31.877 -188.341)
		(size 0.7112)
		(drill 0.4064)
		(layers "F.Cu" "B.Cu")
		(net "GND")
	)
	(via
		(at 19.035268 -134.869682)
		(size 0.7112)
		(drill 0.4064)
		(layers "F.Cu" "B.Cu")
		(net "GND")
	)
	(via
		(at 22.7838 -358.0638)
		(size 0.7112)
		(drill 0.4064)
		(layers "F.Cu" "B.Cu")
		(net "GND")
	)
	(via
		(at 15.3162 -480.6442)
		(size 0.5588)
		(drill 0.3048)
		(layers "F.Cu" "B.Cu")
		(net "GND")
	)
	(via
		(at 34.417 -230.886)
		(size 0.7112)
		(drill 0.4064)
		(layers "F.Cu" "B.Cu")
		(net "GND")
	)
	(via
		(at 39.37 -11.43)
		(size 0.7112)
		(drill 0.4064)
		(layers "F.Cu" "B.Cu")
		(net "GND")
	)
	(via
		(at 19.177 -237.871)
		(size 0.7112)
		(drill 0.4064)
		(layers "F.Cu" "B.Cu")
		(net "GND")
	)
	(via
		(at 38.481 -470.18194)
		(size 0.7112)
		(drill 0.4064)
		(layers "F.Cu" "B.Cu")
		(net "GND")
	)
	(via
		(at 3.2004 -445.4652)
		(size 0.7112)
		(drill 0.4064)
		(layers "F.Cu" "B.Cu")
		(net "GND")
	)
	(via
		(at 47.8282 -93.6244)
		(size 0.7112)
		(drill 0.4064)
		(layers "F.Cu" "B.Cu")
		(net "GND")
	)
	(via
		(at 46.5074 -466.9282)
		(size 0.7112)
		(drill 0.4064)
		(layers "F.Cu" "B.Cu")
		(net "GND")
	)
	(via
		(at 16.8148 -165.989)
		(size 0.5588)
		(drill 0.3048)
		(layers "F.Cu" "B.Cu")
		(net "GND")
	)
	(via
		(at 11.811 -473.837)
		(size 0.7112)
		(drill 0.4064)
		(layers "F.Cu" "B.Cu")
		(net "GND")
	)
	(via
		(at 45.974 -279.019)
		(size 0.7112)
		(drill 0.4064)
		(layers "F.Cu" "B.Cu")
		(net "GND")
	)
	(via
		(at 9.525 -231.648)
		(size 0.7112)
		(drill 0.4064)
		(layers "F.Cu" "B.Cu")
		(net "GND")
	)
	(via
		(at 26.797 -99.06)
		(size 0.7112)
		(drill 0.4064)
		(layers "F.Cu" "B.Cu")
		(net "GND")
	)
	(via
		(at 16.129 -498.602)
		(size 0.7112)
		(drill 0.4064)
		(layers "F.Cu" "B.Cu")
		(net "GND")
	)
	(via
		(at 48.26 -209.169)
		(size 0.7112)
		(drill 0.4064)
		(layers "F.Cu" "B.Cu")
		(net "GND")
	)
	(via
		(at 40.28313 -282.140406)
		(size 0.7112)
		(drill 0.4064)
		(layers "F.Cu" "B.Cu")
		(net "GND")
	)
	(via
		(at 45.9359 -88.5952)
		(size 0.7112)
		(drill 0.4064)
		(layers "F.Cu" "B.Cu")
		(net "GND")
	)
	(via
		(at 26.0858 -137.414)
		(size 0.5588)
		(drill 0.3048)
		(layers "F.Cu" "B.Cu")
		(net "GND")
	)
	(via
		(at 3.43154 -151.88946)
		(size 0.7112)
		(drill 0.4064)
		(layers "F.Cu" "B.Cu")
		(net "GND")
	)
	(via
		(at 35.306 -470.154)
		(size 0.7112)
		(drill 0.4064)
		(layers "F.Cu" "B.Cu")
		(net "GND")
	)
	(via
		(at 42.037 -172.085)
		(size 0.7112)
		(drill 0.4064)
		(layers "F.Cu" "B.Cu")
		(net "GND")
	)
	(via
		(at 11.557 -355.6)
		(size 0.5588)
		(drill 0.3048)
		(layers "F.Cu" "B.Cu")
		(net "GND")
	)
	(via
		(at 5.969 -31.496)
		(size 0.7112)
		(drill 0.4064)
		(layers "F.Cu" "B.Cu")
		(net "GND")
	)
	(via
		(at 49.403 -198.755)
		(size 0.7112)
		(drill 0.4064)
		(layers "F.Cu" "B.Cu")
		(net "GND")
	)
	(via
		(at 1.2446 -433.832)
		(size 0.7112)
		(drill 0.4064)
		(layers "F.Cu" "B.Cu")
		(net "GND")
	)
	(via
		(at 4.064 -257.556)
		(size 0.7112)
		(drill 0.4064)
		(layers "F.Cu" "B.Cu")
		(net "GND")
	)
	(via
		(at 8.636 -239.776)
		(size 0.7112)
		(drill 0.4064)
		(layers "F.Cu" "B.Cu")
		(net "GND")
	)
	(via
		(at 38.608 -431.06594)
		(size 0.7112)
		(drill 0.4064)
		(layers "F.Cu" "B.Cu")
		(net "GND")
	)
	(via
		(at 13.1318 -59.6392)
		(size 0.5588)
		(drill 0.3048)
		(layers "F.Cu" "B.Cu")
		(net "GND")
	)
	(via
		(at 12.192 -207.264)
		(size 0.7112)
		(drill 0.4064)
		(layers "F.Cu" "B.Cu")
		(net "GND")
	)
	(via
		(at 11.811 -377.1646)
		(size 0.7112)
		(drill 0.4064)
		(layers "F.Cu" "B.Cu")
		(net "GND")
	)
	(via
		(at 48.387 -26.67)
		(size 0.7112)
		(drill 0.4064)
		(layers "F.Cu" "B.Cu")
		(net "GND")
	)
	(via
		(at 44.704 -169.037)
		(size 0.7112)
		(drill 0.4064)
		(layers "F.Cu" "B.Cu")
		(net "GND")
	)
	(via
		(at 1.420876 -38.989)
		(size 0.7112)
		(drill 0.4064)
		(layers "F.Cu" "B.Cu")
		(net "GND")
	)
	(via
		(at 43.942 -470.56294)
		(size 0.7112)
		(drill 0.4064)
		(layers "F.Cu" "B.Cu")
		(net "GND")
	)
	(via
		(at 19.0246 -357.8352)
		(size 0.7112)
		(drill 0.4064)
		(layers "F.Cu" "B.Cu")
		(net "GND")
	)
	(via
		(at 9.398 -435.356)
		(size 0.7112)
		(drill 0.3556)
		(layers "F.Cu" "B.Cu")
		(net "GND")
	)
	(via
		(at 35.8902 -75.7174)
		(size 0.7112)
		(drill 0.4064)
		(layers "F.Cu" "B.Cu")
		(net "GND")
	)
	(via
		(at 21.717 -232.41)
		(size 0.7112)
		(drill 0.4064)
		(layers "F.Cu" "B.Cu")
		(net "GND")
	)
	(via
		(at 11.684 -211.836)
		(size 0.7112)
		(drill 0.4064)
		(layers "F.Cu" "B.Cu")
		(net "GND")
	)
	(via
		(at 14.1986 -477.901)
		(size 0.5588)
		(drill 0.3048)
		(layers "F.Cu" "B.Cu")
		(net "GND")
	)
	(via
		(at 3.556 -35.814)
		(size 0.7112)
		(drill 0.4064)
		(layers "F.Cu" "B.Cu")
		(net "GND")
	)
	(via
		(at 28.956 -349.504)
		(size 0.7112)
		(drill 0.4064)
		(layers "F.Cu" "B.Cu")
		(net "GND")
	)
	(via
		(at 30.353 -299.085)
		(size 0.7112)
		(drill 0.4064)
		(layers "F.Cu" "B.Cu")
		(net "GND")
	)
	(via
		(at 30.48 -281.432)
		(size 0.7112)
		(drill 0.4064)
		(layers "F.Cu" "B.Cu")
		(net "GND")
	)
	(via
		(at 47.117 -458.343)
		(size 0.7112)
		(drill 0.4064)
		(layers "F.Cu" "B.Cu")
		(net "GND")
	)
	(via
		(at 21.3868 -163.54171)
		(size 0.5588)
		(drill 0.3048)
		(layers "F.Cu" "B.Cu")
		(net "GND")
	)
	(via
		(at 3.3274 -442.6204)
		(size 0.7112)
		(drill 0.4064)
		(layers "F.Cu" "B.Cu")
		(net "GND")
	)
	(via
		(at 33.909 -146.177)
		(size 0.5588)
		(drill 0.3048)
		(layers "F.Cu" "B.Cu")
		(net "GND")
	)
	(via
		(at 15.621 -350.52)
		(size 0.7112)
		(drill 0.4064)
		(layers "F.Cu" "B.Cu")
		(net "GND")
	)
	(via
		(at 16.152876 -6.477)
		(size 0.7112)
		(drill 0.4064)
		(layers "F.Cu" "B.Cu")
		(net "GND")
	)
	(via
		(at 20.701 -212.725)
		(size 0.7112)
		(drill 0.4064)
		(layers "F.Cu" "B.Cu")
		(net "GND")
	)
	(via
		(at 30.48 -182.245)
		(size 0.7112)
		(drill 0.4064)
		(layers "F.Cu" "B.Cu")
		(net "GND")
	)
	(via
		(at 42.545 -435.864)
		(size 0.7112)
		(drill 0.4064)
		(layers "F.Cu" "B.Cu")
		(net "GND")
	)
	(via
		(at 48.895 -410.718)
		(size 0.7112)
		(drill 0.4064)
		(layers "F.Cu" "B.Cu")
		(net "GND")
	)
	(via
		(at 50.165 -451.231)
		(size 0.7112)
		(drill 0.4064)
		(layers "F.Cu" "B.Cu")
		(net "GND")
	)
	(via
		(at 31.242 -203.2)
		(size 0.7112)
		(drill 0.4064)
		(layers "F.Cu" "B.Cu")
		(net "GND")
	)
	(via
		(at 48.895 -418.592)
		(size 0.5588)
		(drill 0.3048)
		(layers "F.Cu" "B.Cu")
		(net "GND")
	)
	(via
		(at 9.3218 -448.2338)
		(size 0.7112)
		(drill 0.4064)
		(layers "F.Cu" "B.Cu")
		(net "GND")
	)
	(via
		(at 31.877 -239.776)
		(size 0.7112)
		(drill 0.4064)
		(layers "F.Cu" "B.Cu")
		(net "GND")
	)
	(via
		(at 41.91 -11.43)
		(size 0.7112)
		(drill 0.4064)
		(layers "F.Cu" "B.Cu")
		(net "GND")
	)
	(via
		(at 26.543 -278.13)
		(size 0.7112)
		(drill 0.4064)
		(layers "F.Cu" "B.Cu")
		(net "GND")
	)
	(via
		(at 40.767 -232.791)
		(size 0.7112)
		(drill 0.3556)
		(layers "F.Cu" "B.Cu")
		(net "GND")
	)
	(via
		(at 1.143 -491.744)
		(size 0.7112)
		(drill 0.4064)
		(layers "F.Cu" "B.Cu")
		(net "GND")
	)
	(via
		(at 50.927 -111.125)
		(size 0.7112)
		(drill 0.4064)
		(layers "F.Cu" "B.Cu")
		(net "GND")
	)
	(via
		(at 19.2024 -360.7562)
		(size 0.7112)
		(drill 0.4064)
		(layers "F.Cu" "B.Cu")
		(net "GND")
	)
	(via
		(at 49.911 -162.941)
		(size 0.7112)
		(drill 0.4064)
		(layers "F.Cu" "B.Cu")
		(net "GND")
	)
	(via
		(at 14.605 -250.0122)
		(size 0.5588)
		(drill 0.3048)
		(layers "F.Cu" "B.Cu")
		(net "GND")
	)
	(via
		(at 38.989 -145.887186)
		(size 0.7112)
		(drill 0.4064)
		(layers "F.Cu" "B.Cu")
		(net "GND")
	)
	(via
		(at 43.5864 -151.2316)
		(size 0.7112)
		(drill 0.4064)
		(layers "F.Cu" "B.Cu")
		(net "GND")
	)
	(via
		(at 8.6614 -143.9164)
		(size 0.7112)
		(drill 0.4064)
		(layers "F.Cu" "B.Cu")
		(net "GND")
	)
	(via
		(at 37.211 -33.492186)
		(size 0.7112)
		(drill 0.4064)
		(layers "F.Cu" "B.Cu")
		(net "GND")
	)
	(via
		(at 20.828 -204.851)
		(size 0.7112)
		(drill 0.4064)
		(layers "F.Cu" "B.Cu")
		(net "GND")
	)
	(via
		(at 48.7426 -62.1284)
		(size 0.7112)
		(drill 0.4064)
		(layers "F.Cu" "B.Cu")
		(net "GND")
	)
	(via
		(at 14.351 -238.76)
		(size 0.7112)
		(drill 0.4064)
		(layers "F.Cu" "B.Cu")
		(net "GND")
	)
	(via
		(at 33.4518 -145.0594)
		(size 0.7112)
		(drill 0.3556)
		(layers "F.Cu" "B.Cu")
		(net "GND")
	)
	(via
		(at 3.302 -61.976)
		(size 0.7112)
		(drill 0.4064)
		(layers "F.Cu" "B.Cu")
		(net "GND")
	)
	(via
		(at 1.166876 -351.028)
		(size 0.7112)
		(drill 0.4064)
		(layers "F.Cu" "B.Cu")
		(net "GND")
	)
	(via
		(at 43.307 -30.607)
		(size 0.7112)
		(drill 0.4064)
		(layers "F.Cu" "B.Cu")
		(net "GND")
	)
	(via
		(at 49.276 -159.639)
		(size 0.7112)
		(drill 0.4064)
		(layers "F.Cu" "B.Cu")
		(net "GND")
	)
	(via
		(at 13.462 -176.5554)
		(size 0.5588)
		(drill 0.3048)
		(layers "F.Cu" "B.Cu")
		(net "GND")
	)
	(via
		(at 14.1224 -350.9518)
		(size 0.7112)
		(drill 0.4064)
		(layers "F.Cu" "B.Cu")
		(net "GND")
	)
	(via
		(at 32.9692 -206.629)
		(size 0.7112)
		(drill 0.4064)
		(layers "F.Cu" "B.Cu")
		(net "GND")
	)
	(via
		(at 22.1742 -364.744)
		(size 0.7112)
		(drill 0.4064)
		(layers "F.Cu" "B.Cu")
		(net "GND")
	)
	(via
		(at 12.7 -334.772)
		(size 0.7112)
		(drill 0.4064)
		(layers "F.Cu" "B.Cu")
		(net "GND")
	)
	(via
		(at 26.5684 -488.5436)
		(size 0.5588)
		(drill 0.3048)
		(layers "F.Cu" "B.Cu")
		(net "GND")
	)
	(via
		(at 31.115 -177.927)
		(size 0.5588)
		(drill 0.3048)
		(layers "F.Cu" "B.Cu")
		(net "GND")
	)
	(via
		(at 48.387 -139.827)
		(size 0.7112)
		(drill 0.4064)
		(layers "F.Cu" "B.Cu")
		(net "GND")
	)
	(via
		(at 6.604 -256.54)
		(size 0.7112)
		(drill 0.4064)
		(layers "F.Cu" "B.Cu")
		(net "GND")
	)
	(via
		(at 42.0624 -160.088326)
		(size 0.7112)
		(drill 0.4064)
		(layers "F.Cu" "B.Cu")
		(net "GND")
	)
	(via
		(at 7.366 -424.434)
		(size 0.7112)
		(drill 0.4064)
		(layers "F.Cu" "B.Cu")
		(net "GND")
	)
	(via
		(at 45.72 -231.775)
		(size 0.5588)
		(drill 0.3048)
		(layers "F.Cu" "B.Cu")
		(net "GND")
	)
	(via
		(at 28.829 -183.134)
		(size 0.5588)
		(drill 0.3048)
		(layers "F.Cu" "B.Cu")
		(net "GND")
	)
	(via
		(at 13.081 -13.462)
		(size 0.7112)
		(drill 0.4064)
		(layers "F.Cu" "B.Cu")
		(net "GND")
	)
	(via
		(at 11.049 -411.6578)
		(size 0.5588)
		(drill 0.3048)
		(layers "F.Cu" "B.Cu")
		(net "GND")
	)
	(via
		(at 48.7172 -56.1594)
		(size 0.7112)
		(drill 0.4064)
		(layers "F.Cu" "B.Cu")
		(net "GND")
	)
	(via
		(at 30.48 -232.664)
		(size 0.7112)
		(drill 0.4064)
		(layers "F.Cu" "B.Cu")
		(net "GND")
	)
	(via
		(at 33.02 -189.484)
		(size 0.5588)
		(drill 0.3048)
		(layers "F.Cu" "B.Cu")
		(net "GND")
	)
	(via
		(at 27.559 -176.657)
		(size 0.7112)
		(drill 0.4064)
		(layers "F.Cu" "B.Cu")
		(net "GND")
	)
	(via
		(at 24.13 -34.036)
		(size 0.7112)
		(drill 0.4064)
		(layers "F.Cu" "B.Cu")
		(net "GND")
	)
	(via
		(at 17.8816 -366.903)
		(size 0.7112)
		(drill 0.4064)
		(layers "F.Cu" "B.Cu")
		(net "GND")
	)
	(via
		(at 40.005 -168.783)
		(size 0.5588)
		(drill 0.3048)
		(layers "F.Cu" "B.Cu")
		(net "GND")
	)
	(via
		(at 1.347216 -391.287)
		(size 0.7112)
		(drill 0.4064)
		(layers "F.Cu" "B.Cu")
		(net "GND")
	)
	(via
		(at 30.734 -291.465)
		(size 0.7112)
		(drill 0.3556)
		(layers "F.Cu" "B.Cu")
		(net "GND")
	)
	(via
		(at 3.556 -269.24)
		(size 0.7112)
		(drill 0.4064)
		(layers "F.Cu" "B.Cu")
		(net "GND")
	)
	(via
		(at 1.166876 -444.754)
		(size 0.7112)
		(drill 0.4064)
		(layers "F.Cu" "B.Cu")
		(net "GND")
	)
	(via
		(at 48.6664 -52.5526)
		(size 0.7112)
		(drill 0.4064)
		(layers "F.Cu" "B.Cu")
		(net "GND")
	)
	(via
		(at 11.684 -309.372)
		(size 0.7112)
		(drill 0.4064)
		(layers "F.Cu" "B.Cu")
		(net "GND")
	)
	(via
		(at 18.796 -11.43)
		(size 0.7112)
		(drill 0.4064)
		(layers "F.Cu" "B.Cu")
		(net "GND")
	)
	(via
		(at 23.8252 -353.8728)
		(size 0.7112)
		(drill 0.4064)
		(layers "F.Cu" "B.Cu")
		(net "GND")
	)
	(via
		(at 45.974 -185.166)
		(size 0.7112)
		(drill 0.4064)
		(layers "F.Cu" "B.Cu")
		(net "GND")
	)
	(via
		(at 46.101 -435.991)
		(size 0.7112)
		(drill 0.4064)
		(layers "F.Cu" "B.Cu")
		(net "GND")
	)
	(via
		(at 19.812 -223.139)
		(size 0.7112)
		(drill 0.4064)
		(layers "F.Cu" "B.Cu")
		(net "GND")
	)
	(via
		(at 26.289 -176.657)
		(size 0.7112)
		(drill 0.4064)
		(layers "F.Cu" "B.Cu")
		(net "GND")
	)
	(via
		(at 14.351 -449.4022)
		(size 0.7112)
		(drill 0.4064)
		(layers "F.Cu" "B.Cu")
		(net "GND")
	)
	(via
		(at 39.243 -235.331)
		(size 0.7112)
		(drill 0.4064)
		(layers "F.Cu" "B.Cu")
		(net "GND")
	)
	(via
		(at 28.067 -103.251)
		(size 0.7112)
		(drill 0.4064)
		(layers "F.Cu" "B.Cu")
		(net "GND")
	)
	(via
		(at 11.8618 -471.8558)
		(size 0.7112)
		(drill 0.4064)
		(layers "F.Cu" "B.Cu")
		(net "GND")
	)
	(via
		(at 8.636 -279.908)
		(size 0.7112)
		(drill 0.4064)
		(layers "F.Cu" "B.Cu")
		(net "GND")
	)
	(via
		(at 46.99 -171.069)
		(size 0.7112)
		(drill 0.4064)
		(layers "F.Cu" "B.Cu")
		(net "GND")
	)
	(via
		(at 16.256 -169.3164)
		(size 0.5588)
		(drill 0.3048)
		(layers "F.Cu" "B.Cu")
		(net "GND")
	)
	(via
		(at 39.7002 -222.8088)
		(size 0.7112)
		(drill 0.4064)
		(layers "F.Cu" "B.Cu")
		(net "GND")
	)
	(via
		(at 47.625 -280.289)
		(size 0.7112)
		(drill 0.4064)
		(layers "F.Cu" "B.Cu")
		(net "GND")
	)
	(via
		(at 1.347216 -382.0414)
		(size 0.7112)
		(drill 0.4064)
		(layers "F.Cu" "B.Cu")
		(net "GND")
	)
	(via
		(at 34.29 -12.7)
		(size 0.7112)
		(drill 0.4064)
		(layers "F.Cu" "B.Cu")
		(net "GND")
	)
	(via
		(at 20.32 -373.888)
		(size 0.5588)
		(drill 0.3048)
		(layers "F.Cu" "B.Cu")
		(net "GND")
	)
	(via
		(at 13.462 -1.27)
		(size 0.7112)
		(drill 0.4064)
		(layers "F.Cu" "B.Cu")
		(net "GND")
	)
	(via
		(at 29.083 -329.311)
		(size 0.7112)
		(drill 0.4064)
		(layers "F.Cu" "B.Cu")
		(net "GND")
	)
	(via
		(at 37.084 -209.296)
		(size 0.5588)
		(drill 0.3048)
		(layers "F.Cu" "B.Cu")
		(net "GND")
	)
	(via
		(at 11.938 -222.9104)
		(size 0.7112)
		(drill 0.4064)
		(layers "F.Cu" "B.Cu")
		(net "GND")
	)
	(via
		(at 6.604 -22.098)
		(size 0.7112)
		(drill 0.4064)
		(layers "F.Cu" "B.Cu")
		(net "GND")
	)
	(via
		(at 23.622 -478.663)
		(size 0.7112)
		(drill 0.3556)
		(layers "F.Cu" "B.Cu")
		(net "GND")
	)
	(via
		(at 48.768 -233.934)
		(size 0.7112)
		(drill 0.4064)
		(layers "F.Cu" "B.Cu")
		(net "GND")
	)
	(via
		(at 34.163 -213.487)
		(size 0.7112)
		(drill 0.4064)
		(layers "F.Cu" "B.Cu")
		(net "GND")
	)
	(via
		(at 46.228 -261.493)
		(size 0.7112)
		(drill 0.4064)
		(layers "F.Cu" "B.Cu")
		(net "GND")
	)
	(via
		(at 49.657 -257.683)
		(size 0.7112)
		(drill 0.4064)
		(layers "F.Cu" "B.Cu")
		(net "GND")
	)
	(via
		(at 11.303 -350.647)
		(size 0.5588)
		(drill 0.3048)
		(layers "F.Cu" "B.Cu")
		(net "GND")
	)
	(via
		(at 42.164 -274.32)
		(size 0.7112)
		(drill 0.4064)
		(layers "F.Cu" "B.Cu")
		(net "GND")
	)
	(via
		(at 42.418 -33.147)
		(size 0.7112)
		(drill 0.4064)
		(layers "F.Cu" "B.Cu")
		(net "GND")
	)
	(via
		(at 42.799 -433.07)
		(size 0.7112)
		(drill 0.4064)
		(layers "F.Cu" "B.Cu")
		(net "GND")
	)
	(via
		(at 4.064 -315.976)
		(size 0.7112)
		(drill 0.4064)
		(layers "F.Cu" "B.Cu")
		(net "GND")
	)
	(via
		(at 23.749 -376.6058)
		(size 0.7112)
		(drill 0.4064)
		(layers "F.Cu" "B.Cu")
		(net "GND")
	)
	(via
		(at 51.054 -109.347)
		(size 0.7112)
		(drill 0.4064)
		(layers "F.Cu" "B.Cu")
		(net "GND")
	)
	(via
		(at 51.181 -52.832)
		(size 0.7112)
		(drill 0.4064)
		(layers "F.Cu" "B.Cu")
		(net "GND")
	)
	(via
		(at 27.051 -256.159)
		(size 0.7112)
		(drill 0.4064)
		(layers "F.Cu" "B.Cu")
		(net "GND")
	)
	(via
		(at 1.293876 -70.612)
		(size 0.7112)
		(drill 0.4064)
		(layers "F.Cu" "B.Cu")
		(net "GND")
	)
	(via
		(at 11.1506 -34.8488)
		(size 0.7112)
		(drill 0.3556)
		(layers "F.Cu" "B.Cu")
		(net "GND")
	)
	(via
		(at 49.276 -226.949)
		(size 0.7112)
		(drill 0.4064)
		(layers "F.Cu" "B.Cu")
		(net "GND")
	)
	(via
		(at 4.064 -210.312)
		(size 0.7112)
		(drill 0.4064)
		(layers "F.Cu" "B.Cu")
		(net "GND")
	)
	(via
		(at 7.112 -326.644)
		(size 0.7112)
		(drill 0.4064)
		(layers "F.Cu" "B.Cu")
		(net "GND")
	)
	(via
		(at 37.338 -349.758)
		(size 0.7112)
		(drill 0.4064)
		(layers "F.Cu" "B.Cu")
		(net "GND")
	)
	(via
		(at 19.685 -230.378)
		(size 0.7112)
		(drill 0.4064)
		(layers "F.Cu" "B.Cu")
		(net "GND")
	)
	(via
		(at 35.814 -238.379)
		(size 0.7112)
		(drill 0.4064)
		(layers "F.Cu" "B.Cu")
		(net "GND")
	)
	(via
		(at 31.4452 -339.8266)
		(size 0.7112)
		(drill 0.4064)
		(layers "F.Cu" "B.Cu")
		(net "GND")
	)
	(via
		(at 11.5824 -210.185)
		(size 0.7112)
		(drill 0.4064)
		(layers "F.Cu" "B.Cu")
		(net "GND")
	)
	(via
		(at 11.176 -331.724)
		(size 0.7112)
		(drill 0.4064)
		(layers "F.Cu" "B.Cu")
		(net "GND")
	)
	(via
		(at 51.181 -251.714)
		(size 0.5588)
		(drill 0.3048)
		(layers "F.Cu" "B.Cu")
		(net "GND")
	)
	(via
		(at 6.617462 -238.314738)
		(size 0.7112)
		(drill 0.4064)
		(layers "F.Cu" "B.Cu")
		(net "GND")
	)
	(via
		(at 1.347216 -357.9876)
		(size 0.7112)
		(drill 0.4064)
		(layers "F.Cu" "B.Cu")
		(net "GND")
	)
	(via
		(at 3.556 -120.904)
		(size 0.5588)
		(drill 0.3048)
		(layers "F.Cu" "B.Cu")
		(net "GND")
	)
	(via
		(at 47.879 -92.4814)
		(size 0.7112)
		(drill 0.4064)
		(layers "F.Cu" "B.Cu")
		(net "GND")
	)
	(via
		(at 10.4394 -497.205)
		(size 0.7112)
		(drill 0.4064)
		(layers "F.Cu" "B.Cu")
		(net "GND")
	)
	(via
		(at 51.181 -175.641)
		(size 0.5588)
		(drill 0.3048)
		(layers "F.Cu" "B.Cu")
		(net "GND")
	)
	(via
		(at 10.922 -6.858)
		(size 0.7112)
		(drill 0.4064)
		(layers "F.Cu" "B.Cu")
		(net "GND")
	)
	(via
		(at 5.009134 -67.869562)
		(size 0.7112)
		(drill 0.4064)
		(layers "F.Cu" "B.Cu")
		(net "GND")
	)
	(via
		(at 11.4046 -433.5272)
		(size 0.7112)
		(drill 0.4064)
		(layers "F.Cu" "B.Cu")
		(net "GND")
	)
	(via
		(at 28.448 -317.627)
		(size 0.7112)
		(drill 0.4064)
		(layers "F.Cu" "B.Cu")
		(net "GND")
	)
	(via
		(at 24.8412 -337.2866)
		(size 0.7112)
		(drill 0.4064)
		(layers "F.Cu" "B.Cu")
		(net "GND")
	)
	(via
		(at 28.829 -189.738)
		(size 0.5588)
		(drill 0.3048)
		(layers "F.Cu" "B.Cu")
		(net "GND")
	)
	(via
		(at 1.524 -292.608)
		(size 0.7112)
		(drill 0.4064)
		(layers "F.Cu" "B.Cu")
		(net "GND")
	)
	(via
		(at 18.3642 -373.3292)
		(size 0.7112)
		(drill 0.4064)
		(layers "F.Cu" "B.Cu")
		(net "GND")
	)
	(via
		(at 33.909 -484.251)
		(size 0.5588)
		(drill 0.3048)
		(layers "F.Cu" "B.Cu")
		(net "GND")
	)
	(via
		(at 6.096 -299.72)
		(size 0.7112)
		(drill 0.4064)
		(layers "F.Cu" "B.Cu")
		(net "GND")
	)
	(via
		(at 1.166876 -429.514)
		(size 0.7112)
		(drill 0.4064)
		(layers "F.Cu" "B.Cu")
		(net "GND")
	)
	(via
		(at 10.9728 -415.2392)
		(size 0.7112)
		(drill 0.4064)
		(layers "F.Cu" "B.Cu")
		(net "GND")
	)
	(via
		(at 18.796 -287.528)
		(size 0.7112)
		(drill 0.4064)
		(layers "F.Cu" "B.Cu")
		(net "GND")
	)
	(via
		(at 26.797 -252.984)
		(size 0.7112)
		(drill 0.4064)
		(layers "F.Cu" "B.Cu")
		(net "GND")
	)
	(via
		(at 7.493 -13.462)
		(size 0.7112)
		(drill 0.4064)
		(layers "F.Cu" "B.Cu")
		(net "GND")
	)
	(via
		(at 3.048 -323.596)
		(size 0.7112)
		(drill 0.4064)
		(layers "F.Cu" "B.Cu")
		(net "GND")
	)
	(via
		(at 4.4958 -325.882)
		(size 0.7112)
		(drill 0.4064)
		(layers "F.Cu" "B.Cu")
		(net "GND")
	)
	(via
		(at 51.435 -299.466)
		(size 0.5588)
		(drill 0.3048)
		(layers "F.Cu" "B.Cu")
		(net "GND")
	)
	(via
		(at 47.625 -85.852)
		(size 0.7112)
		(drill 0.4064)
		(layers "F.Cu" "B.Cu")
		(net "GND")
	)
	(via
		(at 48.887634 -100.92817)
		(size 0.7112)
		(drill 0.4064)
		(layers "F.Cu" "B.Cu")
		(net "GND")
	)
	(via
		(at 34.798 -149.8346)
		(size 0.5588)
		(drill 0.3048)
		(layers "F.Cu" "B.Cu")
		(net "GND")
	)
	(via
		(at 6.858 -98.933)
		(size 0.7112)
		(drill 0.4064)
		(layers "F.Cu" "B.Cu")
		(net "GND")
	)
	(via
		(at 9.8298 -481.0252)
		(size 0.5588)
		(drill 0.3048)
		(layers "F.Cu" "B.Cu")
		(net "GND")
	)
	(via
		(at 1.524 -278.384)
		(size 0.7112)
		(drill 0.4064)
		(layers "F.Cu" "B.Cu")
		(net "GND")
	)
	(via
		(at 6.9596 -482.4476)
		(size 0.5588)
		(drill 0.3048)
		(layers "F.Cu" "B.Cu")
		(net "GND")
	)
	(via
		(at 48.641 -175.895)
		(size 0.7112)
		(drill 0.4064)
		(layers "F.Cu" "B.Cu")
		(net "GND")
	)
	(via
		(at 49.911 -405.13)
		(size 0.7112)
		(drill 0.4064)
		(layers "F.Cu" "B.Cu")
		(net "GND")
	)
	(via
		(at 29.972 -488.188)
		(size 0.7112)
		(drill 0.4064)
		(layers "F.Cu" "B.Cu")
		(net "GND")
	)
	(via
		(at 22.352 -148.971)
		(size 0.5588)
		(drill 0.3048)
		(layers "F.Cu" "B.Cu")
		(net "GND")
	)
	(via
		(at 46.863 -430.911)
		(size 0.7112)
		(drill 0.4064)
		(layers "F.Cu" "B.Cu")
		(net "GND")
	)
	(via
		(at 13.716 -300.736)
		(size 0.7112)
		(drill 0.4064)
		(layers "F.Cu" "B.Cu")
		(net "GND")
	)
	(via
		(at 50.8 -16.51)
		(size 0.7112)
		(drill 0.4064)
		(layers "F.Cu" "B.Cu")
		(net "GND")
	)
	(via
		(at 18.8214 -170.027092)
		(size 0.7112)
		(drill 0.4064)
		(layers "F.Cu" "B.Cu")
		(net "GND")
	)
	(via
		(at 25.7302 -99.0854)
		(size 0.7112)
		(drill 0.4064)
		(layers "F.Cu" "B.Cu")
		(net "GND")
	)
	(via
		(at 44.196 -211.963)
		(size 0.5588)
		(drill 0.3048)
		(layers "F.Cu" "B.Cu")
		(net "GND")
	)
	(via
		(at 8.636 -256.032)
		(size 0.7112)
		(drill 0.4064)
		(layers "F.Cu" "B.Cu")
		(net "GND")
	)
	(via
		(at 28.448 -316.103)
		(size 0.7112)
		(drill 0.4064)
		(layers "F.Cu" "B.Cu")
		(net "GND")
	)
	(via
		(at 5.0292 -334.1116)
		(size 0.7112)
		(drill 0.4064)
		(layers "F.Cu" "B.Cu")
		(net "GND")
	)
	(via
		(at 7.366 -467.614)
		(size 0.7112)
		(drill 0.4064)
		(layers "F.Cu" "B.Cu")
		(net "GND")
	)
	(via
		(at 49.276 -230.378)
		(size 0.7112)
		(drill 0.4064)
		(layers "F.Cu" "B.Cu")
		(net "GND")
	)
	(via
		(at 16.152876 -491.617)
		(size 0.7112)
		(drill 0.4064)
		(layers "F.Cu" "B.Cu")
		(net "GND")
	)
	(via
		(at 22.098 -150.114)
		(size 0.5588)
		(drill 0.3048)
		(layers "F.Cu" "B.Cu")
		(net "GND")
	)
	(via
		(at 30.353 -312.801)
		(size 0.7112)
		(drill 0.4064)
		(layers "F.Cu" "B.Cu")
		(net "GND")
	)
	(via
		(at 24.13 -39.37)
		(size 0.7112)
		(drill 0.4064)
		(layers "F.Cu" "B.Cu")
		(net "GND")
	)
	(via
		(at 7.112 -321.564)
		(size 0.7112)
		(drill 0.4064)
		(layers "F.Cu" "B.Cu")
		(net "GND")
	)
	(via
		(at 1.524 -268.732)
		(size 0.7112)
		(drill 0.4064)
		(layers "F.Cu" "B.Cu")
		(net "GND")
	)
	(via
		(at 42.164 -190.881)
		(size 0.5588)
		(drill 0.3048)
		(layers "F.Cu" "B.Cu")
		(net "GND")
	)
	(via
		(at 49.9872 -210.439)
		(size 0.7112)
		(drill 0.4064)
		(layers "F.Cu" "B.Cu")
		(net "GND")
	)
	(via
		(at 10.1092 -173.0756)
		(size 0.5588)
		(drill 0.3048)
		(layers "F.Cu" "B.Cu")
		(net "GND")
	)
	(via
		(at 38.862 -22.987)
		(size 0.7112)
		(drill 0.4064)
		(layers "F.Cu" "B.Cu")
		(net "GND")
	)
	(via
		(at 37.084 -226.822)
		(size 0.7112)
		(drill 0.4064)
		(layers "F.Cu" "B.Cu")
		(net "GND")
	)
	(via
		(at 34.925 -229.362)
		(size 0.7112)
		(drill 0.4064)
		(layers "F.Cu" "B.Cu")
		(net "GND")
	)
	(via
		(at 37.465 -310.261)
		(size 0.7112)
		(drill 0.4064)
		(layers "F.Cu" "B.Cu")
		(net "GND")
	)
	(via
		(at 13.6652 -255.5748)
		(size 0.5588)
		(drill 0.3048)
		(layers "F.Cu" "B.Cu")
		(net "GND")
	)
	(via
		(at 51.076606 -98.6536)
		(size 0.7112)
		(drill 0.4064)
		(layers "F.Cu" "B.Cu")
		(net "GND")
	)
	(via
		(at 41.148 -454.66)
		(size 0.7112)
		(drill 0.4064)
		(layers "F.Cu" "B.Cu")
		(net "GND")
	)
	(via
		(at 4.572 -220.98)
		(size 0.7112)
		(drill 0.4064)
		(layers "F.Cu" "B.Cu")
		(net "GND")
	)
	(via
		(at 19.8882 -211.4804)
		(size 0.7112)
		(drill 0.4064)
		(layers "F.Cu" "B.Cu")
		(net "GND")
	)
	(via
		(at 6.913372 -278.638)
		(size 0.7112)
		(drill 0.4064)
		(layers "F.Cu" "B.Cu")
		(net "GND")
	)
	(via
		(at 10.16 -288.544)
		(size 0.7112)
		(drill 0.4064)
		(layers "F.Cu" "B.Cu")
		(net "GND")
	)
	(via
		(at 10.668 -327.66)
		(size 0.7112)
		(drill 0.4064)
		(layers "F.Cu" "B.Cu")
		(net "GND")
	)
	(via
		(at 50.8 -35.56)
		(size 0.7112)
		(drill 0.4064)
		(layers "F.Cu" "B.Cu")
		(net "GND")
	)
	(via
		(at 1.293876 -227.965)
		(size 0.7112)
		(drill 0.4064)
		(layers "F.Cu" "B.Cu")
		(net "GND")
	)
	(via
		(at 50.419 -435.229)
		(size 0.7112)
		(drill 0.4064)
		(layers "F.Cu" "B.Cu")
		(net "GND")
	)
	(via
		(at 4.0894 -201.8284)
		(size 0.7112)
		(drill 0.4064)
		(layers "F.Cu" "B.Cu")
		(net "GND")
	)
	(via
		(at 24.892 -171.279058)
		(size 0.7112)
		(drill 0.4064)
		(layers "F.Cu" "B.Cu")
		(net "GND")
	)
	(via
		(at 4.064 -230.124)
		(size 0.7112)
		(drill 0.4064)
		(layers "F.Cu" "B.Cu")
		(net "GND")
	)
	(via
		(at 1.347216 -386.6134)
		(size 0.7112)
		(drill 0.4064)
		(layers "F.Cu" "B.Cu")
		(net "GND")
	)
	(via
		(at 30.3022 -302.6156)
		(size 0.7112)
		(drill 0.4064)
		(layers "F.Cu" "B.Cu")
		(net "GND")
	)
	(via
		(at 24.892 -177.419)
		(size 0.5588)
		(drill 0.3048)
		(layers "F.Cu" "B.Cu")
		(net "GND")
	)
	(via
		(at 8.001 -1.397)
		(size 0.7112)
		(drill 0.4064)
		(layers "F.Cu" "B.Cu")
		(net "GND")
	)
	(via
		(at 10.0076 -350.8502)
		(size 0.5588)
		(drill 0.3048)
		(layers "F.Cu" "B.Cu")
		(net "GND")
	)
	(via
		(at 37.084 -187.452)
		(size 0.5588)
		(drill 0.3048)
		(layers "F.Cu" "B.Cu")
		(net "GND")
	)
	(via
		(at 12.6238 -144.5006)
		(size 0.5588)
		(drill 0.3048)
		(layers "F.Cu" "B.Cu")
		(net "GND")
	)
	(via
		(at 35.179 -438.785)
		(size 0.7112)
		(drill 0.4064)
		(layers "F.Cu" "B.Cu")
		(net "GND")
	)
	(via
		(at 23.368 -315.341)
		(size 0.7112)
		(drill 0.4064)
		(layers "F.Cu" "B.Cu")
		(net "GND")
	)
	(via
		(at 31.8516 -251.968)
		(size 0.5588)
		(drill 0.3048)
		(layers "F.Cu" "B.Cu")
		(net "GND")
	)
	(via
		(at 1.347216 -139.3952)
		(size 0.5588)
		(drill 0.3048)
		(layers "F.Cu" "B.Cu")
		(net "GND")
	)
	(via
		(at 42.926 -202.057)
		(size 0.7112)
		(drill 0.4064)
		(layers "F.Cu" "B.Cu")
		(net "GND")
	)
	(via
		(at 23.241 -304.8)
		(size 0.7112)
		(drill 0.4064)
		(layers "F.Cu" "B.Cu")
		(net "GND")
	)
	(via
		(at 50.038 -178.816)
		(size 0.7112)
		(drill 0.4064)
		(layers "F.Cu" "B.Cu")
		(net "GND")
	)
	(via
		(at 23.4188 -140.6652)
		(size 0.5588)
		(drill 0.3048)
		(layers "F.Cu" "B.Cu")
		(net "GND")
	)
	(via
		(at 1.143 -253.238)
		(size 0.7112)
		(drill 0.4064)
		(layers "F.Cu" "B.Cu")
		(net "GND")
	)
	(via
		(at 15.875 -234.823)
		(size 0.7112)
		(drill 0.4064)
		(layers "F.Cu" "B.Cu")
		(net "GND")
	)
	(via
		(at 45.847 -28.448)
		(size 0.7112)
		(drill 0.4064)
		(layers "F.Cu" "B.Cu")
		(net "GND")
	)
	(via
		(at 26.289 -312.166)
		(size 0.7112)
		(drill 0.4064)
		(layers "F.Cu" "B.Cu")
		(net "GND")
	)
	(via
		(at 6.0198 -92.4306)
		(size 0.7112)
		(drill 0.4064)
		(layers "F.Cu" "B.Cu")
		(net "GND")
	)
	(via
		(at 8.128 -217.932)
		(size 0.7112)
		(drill 0.4064)
		(layers "F.Cu" "B.Cu")
		(net "GND")
	)
	(via
		(at 30.226 -171.0182)
		(size 0.7112)
		(drill 0.4064)
		(layers "F.Cu" "B.Cu")
		(net "GND")
	)
	(via
		(at 45.1358 -485.8512)
		(size 0.5588)
		(drill 0.3048)
		(layers "F.Cu" "B.Cu")
		(net "GND")
	)
	(via
		(at 3.2004 -455.3712)
		(size 0.7112)
		(drill 0.4064)
		(layers "F.Cu" "B.Cu")
		(net "GND")
	)
	(via
		(at 3.556 -275.844)
		(size 0.7112)
		(drill 0.4064)
		(layers "F.Cu" "B.Cu")
		(net "GND")
	)
	(via
		(at 6.858 -97.536)
		(size 0.7112)
		(drill 0.4064)
		(layers "F.Cu" "B.Cu")
		(net "GND")
	)
	(via
		(at 3.175 -497.586)
		(size 0.7112)
		(drill 0.4064)
		(layers "F.Cu" "B.Cu")
		(net "GND")
	)
	(via
		(at 49.911 -399.288)
		(size 0.5588)
		(drill 0.3048)
		(layers "F.Cu" "B.Cu")
		(net "GND")
	)
	(via
		(at 16.2814 -379.8316)
		(size 0.7112)
		(drill 0.4064)
		(layers "F.Cu" "B.Cu")
		(net "GND")
	)
	(via
		(at 31.4452 -346.9386)
		(size 0.7112)
		(drill 0.4064)
		(layers "F.Cu" "B.Cu")
		(net "GND")
	)
	(via
		(at 7.3152 -135.5598)
		(size 0.5588)
		(drill 0.3048)
		(layers "F.Cu" "B.Cu")
		(net "GND")
	)
	(via
		(at 48.895 -163.83)
		(size 0.7112)
		(drill 0.4064)
		(layers "F.Cu" "B.Cu")
		(net "GND")
	)
	(via
		(at 33.274 -38.1254)
		(size 0.7112)
		(drill 0.4064)
		(layers "F.Cu" "B.Cu")
		(net "GND")
	)
	(via
		(at 1.166876 -100.711)
		(size 0.7112)
		(drill 0.4064)
		(layers "F.Cu" "B.Cu")
		(net "GND")
	)
	(via
		(at 45.466 -456.819)
		(size 0.7112)
		(drill 0.4064)
		(layers "F.Cu" "B.Cu")
		(net "GND")
	)
	(via
		(at 34.0614 -171.323)
		(size 0.7112)
		(drill 0.4064)
		(layers "F.Cu" "B.Cu")
		(net "GND")
	)
	(via
		(at 1.1684 -377.1392)
		(size 0.7112)
		(drill 0.4064)
		(layers "F.Cu" "B.Cu")
		(net "GND")
	)
	(via
		(at 51.308 -93.091)
		(size 0.7112)
		(drill 0.4064)
		(layers "F.Cu" "B.Cu")
		(net "GND")
	)
	(via
		(at 40.767 -476.885)
		(size 0.7112)
		(drill 0.4064)
		(layers "F.Cu" "B.Cu")
		(net "GND")
	)
	(via
		(at 46.355 -189.23)
		(size 0.7112)
		(drill 0.4064)
		(layers "F.Cu" "B.Cu")
		(net "GND")
	)
	(via
		(at 21.1328 -369.697)
		(size 0.5588)
		(drill 0.3048)
		(layers "F.Cu" "B.Cu")
		(net "GND")
	)
	(via
		(at 26.289 -264.668)
		(size 0.7112)
		(drill 0.4064)
		(layers "F.Cu" "B.Cu")
		(net "GND")
	)
	(via
		(at 3.429 -70.866)
		(size 0.7112)
		(drill 0.4064)
		(layers "F.Cu" "B.Cu")
		(net "GND")
	)
	(via
		(at 23.368 -318.516)
		(size 0.7112)
		(drill 0.4064)
		(layers "F.Cu" "B.Cu")
		(net "GND")
	)
	(via
		(at 46.863 -223.266)
		(size 0.7112)
		(drill 0.4064)
		(layers "F.Cu" "B.Cu")
		(net "GND")
	)
	(via
		(at 20.096988 -143.6878)
		(size 0.7112)
		(drill 0.4064)
		(layers "F.Cu" "B.Cu")
		(net "GND")
	)
	(via
		(at 15.24 -303.276)
		(size 0.7112)
		(drill 0.4064)
		(layers "F.Cu" "B.Cu")
		(net "GND")
	)
	(via
		(at 46.355 -264.541)
		(size 0.7112)
		(drill 0.4064)
		(layers "F.Cu" "B.Cu")
		(net "GND")
	)
	(via
		(at 23.0632 -338.1248)
		(size 0.7112)
		(drill 0.4064)
		(layers "F.Cu" "B.Cu")
		(net "GND")
	)
	(via
		(at 42.4942 -166.0652)
		(size 0.7112)
		(drill 0.4064)
		(layers "F.Cu" "B.Cu")
		(net "GND")
	)
	(via
		(at 49.911 -408.051)
		(size 0.5588)
		(drill 0.3048)
		(layers "F.Cu" "B.Cu")
		(net "GND")
	)
	(via
		(at 1.347216 -111.887)
		(size 0.7112)
		(drill 0.4064)
		(layers "F.Cu" "B.Cu")
		(net "GND")
	)
	(via
		(at 37.084 -202.311)
		(size 0.5588)
		(drill 0.3048)
		(layers "F.Cu" "B.Cu")
		(net "GND")
	)
	(via
		(at 51.181 -345.313)
		(size 0.5588)
		(drill 0.3048)
		(layers "F.Cu" "B.Cu")
		(net "GND")
	)
	(via
		(at 31.369 -213.995)
		(size 0.7112)
		(drill 0.4064)
		(layers "F.Cu" "B.Cu")
		(net "GND")
	)
	(via
		(at 6.096 -214.884)
		(size 0.7112)
		(drill 0.4064)
		(layers "F.Cu" "B.Cu")
		(net "GND")
	)
	(via
		(at 20.701 -238.76)
		(size 0.7112)
		(drill 0.4064)
		(layers "F.Cu" "B.Cu")
		(net "GND")
	)
	(via
		(at 24.892 -325.628)
		(size 0.7112)
		(drill 0.4064)
		(layers "F.Cu" "B.Cu")
		(net "GND")
	)
	(via
		(at 42.291 -456.692)
		(size 0.7112)
		(drill 0.4064)
		(layers "F.Cu" "B.Cu")
		(net "GND")
	)
	(via
		(at 25.781 -103.251)
		(size 0.7112)
		(drill 0.4064)
		(layers "F.Cu" "B.Cu")
		(net "GND")
	)
	(via
		(at 51.308 -267.208)
		(size 0.5588)
		(drill 0.3048)
		(layers "F.Cu" "B.Cu")
		(net "GND")
	)
	(via
		(at 7.493 -92.583)
		(size 0.7112)
		(drill 0.4064)
		(layers "F.Cu" "B.Cu")
		(net "GND")
	)
	(via
		(at 35.7378 -146.4564)
		(size 0.7112)
		(drill 0.4064)
		(layers "F.Cu" "B.Cu")
		(net "GND")
	)
	(via
		(at 50.8 -25.4)
		(size 0.7112)
		(drill 0.4064)
		(layers "F.Cu" "B.Cu")
		(net "GND")
	)
	(via
		(at 29.1592 -255.27)
		(size 0.7112)
		(drill 0.4064)
		(layers "F.Cu" "B.Cu")
		(net "GND")
	)
	(via
		(at 6.8326 -393.1666)
		(size 0.7112)
		(drill 0.4064)
		(layers "F.Cu" "B.Cu")
		(net "GND")
	)
	(via
		(at 1.397 -68.453)
		(size 0.7112)
		(drill 0.4064)
		(layers "F.Cu" "B.Cu")
		(net "GND")
	)
	(via
		(at 33.5788 -361.8992)
		(size 0.7112)
		(drill 0.4064)
		(layers "F.Cu" "B.Cu")
		(net "GND")
	)
	(via
		(at 14.732 -317.5)
		(size 0.7112)
		(drill 0.4064)
		(layers "F.Cu" "B.Cu")
		(net "GND")
	)
	(via
		(at 3.556 -167.386)
		(size 0.7112)
		(drill 0.4064)
		(layers "F.Cu" "B.Cu")
		(net "GND")
	)
	(via
		(at 3.429 -77.089)
		(size 0.7112)
		(drill 0.4064)
		(layers "F.Cu" "B.Cu")
		(net "GND")
	)
	(via
		(at 29.083 -177.927)
		(size 0.5588)
		(drill 0.3048)
		(layers "F.Cu" "B.Cu")
		(net "GND")
	)
	(via
		(at 41.148 -260.858)
		(size 0.7112)
		(drill 0.3556)
		(layers "F.Cu" "B.Cu")
		(net "GND")
	)
	(via
		(at 37.084 -191.77)
		(size 0.5588)
		(drill 0.3048)
		(layers "F.Cu" "B.Cu")
		(net "GND")
	)
	(via
		(at 30.226 -322.326)
		(size 0.7112)
		(drill 0.4064)
		(layers "F.Cu" "B.Cu")
		(net "GND")
	)
	(via
		(at 25.527 -352.806)
		(size 0.7112)
		(drill 0.4064)
		(layers "F.Cu" "B.Cu")
		(net "GND")
	)
	(via
		(at 32.639 -22.606)
		(size 0.7112)
		(drill 0.4064)
		(layers "F.Cu" "B.Cu")
		(net "GND")
	)
	(via
		(at 31.496 -349.631)
		(size 0.7112)
		(drill 0.4064)
		(layers "F.Cu" "B.Cu")
		(net "GND")
	)
	(via
		(at 4.572 -183.896)
		(size 0.7112)
		(drill 0.4064)
		(layers "F.Cu" "B.Cu")
		(net "GND")
	)
	(via
		(at 13.1572 -312.8264)
		(size 0.7112)
		(drill 0.4064)
		(layers "F.Cu" "B.Cu")
		(net "GND")
	)
	(via
		(at 7.112 -476.631)
		(size 0.7112)
		(drill 0.4064)
		(layers "F.Cu" "B.Cu")
		(net "GND")
	)
	(via
		(at 23.368 -329.057)
		(size 0.7112)
		(drill 0.4064)
		(layers "F.Cu" "B.Cu")
		(net "GND")
	)
	(via
		(at 36.7284 -135.5852)
		(size 0.7112)
		(drill 0.4064)
		(layers "F.Cu" "B.Cu")
		(net "GND")
	)
	(via
		(at 14.605 -226.1362)
		(size 0.5588)
		(drill 0.3048)
		(layers "F.Cu" "B.Cu")
		(net "GND")
	)
	(via
		(at 12.7 -315.976)
		(size 0.7112)
		(drill 0.4064)
		(layers "F.Cu" "B.Cu")
		(net "GND")
	)
	(via
		(at 26.3398 -373.4562)
		(size 0.7112)
		(drill 0.4064)
		(layers "F.Cu" "B.Cu")
		(net "GND")
	)
	(via
		(at 29.21 -196.3928)
		(size 0.7112)
		(drill 0.4064)
		(layers "F.Cu" "B.Cu")
		(net "GND")
	)
	(via
		(at 13.462 -444.627)
		(size 0.7112)
		(drill 0.4064)
		(layers "F.Cu" "B.Cu")
		(net "GND")
	)
	(via
		(at 49.53 -269.494)
		(size 0.7112)
		(drill 0.4064)
		(layers "F.Cu" "B.Cu")
		(net "GND")
	)
	(via
		(at 29.972 -13.843)
		(size 0.7112)
		(drill 0.4064)
		(layers "F.Cu" "B.Cu")
		(net "GND")
	)
	(via
		(at 45.466 -255.27)
		(size 0.5588)
		(drill 0.3048)
		(layers "F.Cu" "B.Cu")
		(net "GND")
	)
	(via
		(at 19.3548 -363.3978)
		(size 0.7112)
		(drill 0.4064)
		(layers "F.Cu" "B.Cu")
		(net "GND")
	)
	(via
		(at 51.181 -157.861)
		(size 0.7112)
		(drill 0.4064)
		(layers "F.Cu" "B.Cu")
		(net "GND")
	)
	(via
		(at 50.292 -461.899)
		(size 0.7112)
		(drill 0.4064)
		(layers "F.Cu" "B.Cu")
		(net "GND")
	)
	(via
		(at 49.3776 -148.844)
		(size 0.7112)
		(drill 0.4064)
		(layers "F.Cu" "B.Cu")
		(net "GND")
	)
	(via
		(at 10.033 -357.6066)
		(size 0.7112)
		(drill 0.4064)
		(layers "F.Cu" "B.Cu")
		(net "GND")
	)
	(via
		(at 1.420876 -214.503)
		(size 0.7112)
		(drill 0.4064)
		(layers "F.Cu" "B.Cu")
		(net "GND")
	)
	(via
		(at 26.67 -243.332)
		(size 0.7112)
		(drill 0.4064)
		(layers "F.Cu" "B.Cu")
		(net "GND")
	)
	(via
		(at 29.76753 -369.84178)
		(size 0.7112)
		(drill 0.4064)
		(layers "F.Cu" "B.Cu")
		(net "GND")
	)
	(via
		(at 46.3804 -138.9126)
		(size 0.7112)
		(drill 0.4064)
		(layers "F.Cu" "B.Cu")
		(net "GND")
	)
	(via
		(at 32.258 -229.362)
		(size 0.7112)
		(drill 0.4064)
		(layers "F.Cu" "B.Cu")
		(net "GND")
	)
	(via
		(at 6.7564 -287.6296)
		(size 0.7112)
		(drill 0.4064)
		(layers "F.Cu" "B.Cu")
		(net "GND")
	)
	(via
		(at 15.113 -223.9264)
		(size 0.5588)
		(drill 0.3048)
		(layers "F.Cu" "B.Cu")
		(net "GND")
	)
	(via
		(at 43.18 -189.357)
		(size 0.5588)
		(drill 0.3048)
		(layers "F.Cu" "B.Cu")
		(net "GND")
	)
	(via
		(at 51.308 -233.172)
		(size 0.5588)
		(drill 0.3048)
		(layers "F.Cu" "B.Cu")
		(net "GND")
	)
	(via
		(at 9.7282 -396.6972)
		(size 0.7112)
		(drill 0.4064)
		(layers "F.Cu" "B.Cu")
		(net "GND")
	)
	(via
		(at 48.133 -30.48)
		(size 0.7112)
		(drill 0.4064)
		(layers "F.Cu" "B.Cu")
		(net "GND")
	)
	(via
		(at 37.338 -178.562)
		(size 0.5588)
		(drill 0.3048)
		(layers "F.Cu" "B.Cu")
		(net "GND")
	)
	(via
		(at 48.895 -413.131)
		(size 0.7112)
		(drill 0.4064)
		(layers "F.Cu" "B.Cu")
		(net "GND")
	)
	(via
		(at 51.076606 -77.597)
		(size 0.7112)
		(drill 0.4064)
		(layers "F.Cu" "B.Cu")
		(net "GND")
	)
	(via
		(at 1.347216 -235.204)
		(size 0.7112)
		(drill 0.4064)
		(layers "F.Cu" "B.Cu")
		(net "GND")
	)
	(via
		(at 42.037 -24.257)
		(size 0.7112)
		(drill 0.4064)
		(layers "F.Cu" "B.Cu")
		(net "GND")
	)
	(via
		(at 4.0894 -495.4778)
		(size 0.7112)
		(drill 0.4064)
		(layers "F.Cu" "B.Cu")
		(net "GND")
	)
	(via
		(at 1.166876 -297.053)
		(size 0.7112)
		(drill 0.4064)
		(layers "F.Cu" "B.Cu")
		(net "GND")
	)
	(via
		(at 29.591 -191.008)
		(size 0.7112)
		(drill 0.4064)
		(layers "F.Cu" "B.Cu")
		(net "GND")
	)
	(via
		(at 1.420876 -197.612)
		(size 0.7112)
		(drill 0.4064)
		(layers "F.Cu" "B.Cu")
		(net "GND")
	)
	(via
		(at 6.998462 -261.428738)
		(size 0.7112)
		(drill 0.4064)
		(layers "F.Cu" "B.Cu")
		(net "GND")
	)
	(via
		(at 1.166876 -106.934)
		(size 0.7112)
		(drill 0.4064)
		(layers "F.Cu" "B.Cu")
		(net "GND")
	)
	(via
		(at 8.636 -333.248)
		(size 0.7112)
		(drill 0.4064)
		(layers "F.Cu" "B.Cu")
		(net "GND")
	)
	(via
		(at 51.152806 -202.438)
		(size 0.5588)
		(drill 0.3048)
		(layers "F.Cu" "B.Cu")
		(net "GND")
	)
	(via
		(at 32.893 -201.295)
		(size 0.7112)
		(drill 0.4064)
		(layers "F.Cu" "B.Cu")
		(net "GND")
	)
	(via
		(at 28.708096 -368.828066)
		(size 0.7112)
		(drill 0.4064)
		(layers "F.Cu" "B.Cu")
		(net "GND")
	)
	(via
		(at 1.143 -43.307)
		(size 0.7112)
		(drill 0.4064)
		(layers "F.Cu" "B.Cu")
		(net "GND")
	)
	(via
		(at 1.347216 -400.3548)
		(size 0.7112)
		(drill 0.4064)
		(layers "F.Cu" "B.Cu")
		(net "GND")
	)
	(via
		(at 43.561 -208.153)
		(size 0.7112)
		(drill 0.4064)
		(layers "F.Cu" "B.Cu")
		(net "GND")
	)
	(via
		(at 8.7376 -24.2062)
		(size 0.7112)
		(drill 0.4064)
		(layers "F.Cu" "B.Cu")
		(net "GND")
	)
	(via
		(at 12.0904 -202.3872)
		(size 0.7112)
		(drill 0.4064)
		(layers "F.Cu" "B.Cu")
		(net "GND")
	)
	(via
		(at 51.435 -208.788)
		(size 0.5588)
		(drill 0.3048)
		(layers "F.Cu" "B.Cu")
		(net "GND")
	)
	(via
		(at 12.573 -382.27)
		(size 0.7112)
		(drill 0.4064)
		(layers "F.Cu" "B.Cu")
		(net "GND")
	)
	(via
		(at 23.495 -18.542)
		(size 0.5588)
		(drill 0.3048)
		(layers "F.Cu" "B.Cu")
		(net "GND")
	)
	(via
		(at 10.310876 -1.524)
		(size 0.7112)
		(drill 0.4064)
		(layers "F.Cu" "B.Cu")
		(net "GND")
	)
	(via
		(at 13.716 -489.839)
		(size 0.7112)
		(drill 0.4064)
		(layers "F.Cu" "B.Cu")
		(net "GND")
	)
	(via
		(at 28.829 -192.024)
		(size 0.5588)
		(drill 0.3048)
		(layers "F.Cu" "B.Cu")
		(net "GND")
	)
	(via
		(at 26.67 -39.37)
		(size 0.7112)
		(drill 0.4064)
		(layers "F.Cu" "B.Cu")
		(net "GND")
	)
	(via
		(at 3.556 -279.4)
		(size 0.7112)
		(drill 0.4064)
		(layers "F.Cu" "B.Cu")
		(net "GND")
	)
	(via
		(at 45.847 -151.13)
		(size 0.7112)
		(drill 0.4064)
		(layers "F.Cu" "B.Cu")
		(net "GND")
	)
	(via
		(at 40.259 -435.991)
		(size 0.7112)
		(drill 0.4064)
		(layers "F.Cu" "B.Cu")
		(net "GND")
	)
	(via
		(at 4.064 -247.904)
		(size 0.7112)
		(drill 0.4064)
		(layers "F.Cu" "B.Cu")
		(net "GND")
	)
	(via
		(at 10.16 -329.692)
		(size 0.7112)
		(drill 0.4064)
		(layers "F.Cu" "B.Cu")
		(net "GND")
	)
	(via
		(at 27.94 -360.172)
		(size 0.7112)
		(drill 0.4064)
		(layers "F.Cu" "B.Cu")
		(net "GND")
	)
	(via
		(at 51.054 -281.051)
		(size 0.7112)
		(drill 0.4064)
		(layers "F.Cu" "B.Cu")
		(net "GND")
	)
	(via
		(at 51.181 -135.89)
		(size 0.7112)
		(drill 0.4064)
		(layers "F.Cu" "B.Cu")
		(net "GND")
	)
	(via
		(at 36.703 -476.758)
		(size 0.7112)
		(drill 0.3556)
		(layers "F.Cu" "B.Cu")
		(net "GND")
	)
	(via
		(at 44.196 -257.1496)
		(size 0.7112)
		(drill 0.4064)
		(layers "F.Cu" "B.Cu")
		(net "GND")
	)
	(via
		(at 50.927 -49.7586)
		(size 0.7112)
		(drill 0.4064)
		(layers "F.Cu" "B.Cu")
		(net "GND")
	)
	(via
		(at 17.78 -232.283)
		(size 0.7112)
		(drill 0.4064)
		(layers "F.Cu" "B.Cu")
		(net "GND")
	)
	(via
		(at 26.797 -178.435)
		(size 0.5588)
		(drill 0.3048)
		(layers "F.Cu" "B.Cu")
		(net "GND")
	)
	(via
		(at 34.417 -235.585)
		(size 0.7112)
		(drill 0.4064)
		(layers "F.Cu" "B.Cu")
		(net "GND")
	)
	(via
		(at 21.2852 -353.5426)
		(size 0.7112)
		(drill 0.4064)
		(layers "F.Cu" "B.Cu")
		(net "GND")
	)
	(via
		(at 1.143 -261.493)
		(size 0.7112)
		(drill 0.4064)
		(layers "F.Cu" "B.Cu")
		(net "GND")
	)
	(via
		(at 48.895 -419.862)
		(size 0.5588)
		(drill 0.3048)
		(layers "F.Cu" "B.Cu")
		(net "GND")
	)
	(via
		(at 20.955 -206.756)
		(size 0.7112)
		(drill 0.4064)
		(layers "F.Cu" "B.Cu")
		(net "GND")
	)
	(via
		(at 7.747 -208.153)
		(size 0.7112)
		(drill 0.4064)
		(layers "F.Cu" "B.Cu")
		(net "GND")
	)
	(via
		(at 41.529 -204.597)
		(size 0.7112)
		(drill 0.4064)
		(layers "F.Cu" "B.Cu")
		(net "GND")
	)
	(via
		(at 51.308 -151.13)
		(size 0.7112)
		(drill 0.4064)
		(layers "F.Cu" "B.Cu")
		(net "GND")
	)
	(via
		(at 8.763 -498.6528)
		(size 0.7112)
		(drill 0.4064)
		(layers "F.Cu" "B.Cu")
		(net "GND")
	)
	(via
		(at 6.363462 -246.696738)
		(size 0.7112)
		(drill 0.4064)
		(layers "F.Cu" "B.Cu")
		(net "GND")
	)
	(via
		(at 34.29 -11.43)
		(size 0.7112)
		(drill 0.4064)
		(layers "F.Cu" "B.Cu")
		(net "GND")
	)
	(via
		(at 51.181 -184.531)
		(size 0.5588)
		(drill 0.3048)
		(layers "F.Cu" "B.Cu")
		(net "GND")
	)
	(via
		(at 6.7818 -388.5692)
		(size 0.5588)
		(drill 0.3048)
		(layers "F.Cu" "B.Cu")
		(net "GND")
	)
	(via
		(at 45.974 -266.954)
		(size 0.7112)
		(drill 0.4064)
		(layers "F.Cu" "B.Cu")
		(net "GND")
	)
	(via
		(at 29.845 -317.754)
		(size 0.7112)
		(drill 0.4064)
		(layers "F.Cu" "B.Cu")
		(net "GND")
	)
	(via
		(at 19.558 -219.202)
		(size 0.7112)
		(drill 0.4064)
		(layers "F.Cu" "B.Cu")
		(net "GND")
	)
	(via
		(at 4.064 -281.94)
		(size 0.7112)
		(drill 0.4064)
		(layers "F.Cu" "B.Cu")
		(net "GND")
	)
	(via
		(at 9.8552 -391.5918)
		(size 0.7112)
		(drill 0.4064)
		(layers "F.Cu" "B.Cu")
		(net "GND")
	)
	(via
		(at 15.494 -297.942)
		(size 0.7112)
		(drill 0.4064)
		(layers "F.Cu" "B.Cu")
		(net "GND")
	)
	(via
		(at 1.143 -26.797)
		(size 0.7112)
		(drill 0.4064)
		(layers "F.Cu" "B.Cu")
		(net "GND")
	)
	(via
		(at 16.383 -279.146)
		(size 0.5588)
		(drill 0.3048)
		(layers "F.Cu" "B.Cu")
		(net "GND")
	)
	(via
		(at 7.112 -251.968)
		(size 0.7112)
		(drill 0.4064)
		(layers "F.Cu" "B.Cu")
		(net "GND")
	)
	(via
		(at 33.2486 -65.8114)
		(size 0.7112)
		(drill 0.4064)
		(layers "F.Cu" "B.Cu")
		(net "GND")
	)
	(via
		(at 12.954 -134.493)
		(size 0.5588)
		(drill 0.3048)
		(layers "F.Cu" "B.Cu")
		(net "GND")
	)
	(via
		(at 23.241 -277.622)
		(size 0.7112)
		(drill 0.3556)
		(layers "F.Cu" "B.Cu")
		(net "GND")
	)
	(via
		(at 15.621 -488.315)
		(size 0.7112)
		(drill 0.4064)
		(layers "F.Cu" "B.Cu")
		(net "GND")
	)
	(via
		(at 36.957 -217.551)
		(size 0.7112)
		(drill 0.4064)
		(layers "F.Cu" "B.Cu")
		(net "GND")
	)
	(via
		(at 1.166876 -30.607)
		(size 0.7112)
		(drill 0.4064)
		(layers "F.Cu" "B.Cu")
		(net "GND")
	)
	(via
		(at 40.259 -273.2532)
		(size 0.7112)
		(drill 0.4064)
		(layers "F.Cu" "B.Cu")
		(net "GND")
	)
	(via
		(at 13.716 -337.82)
		(size 0.7112)
		(drill 0.4064)
		(layers "F.Cu" "B.Cu")
		(net "GND")
	)
	(via
		(at 48.006 -363.728)
		(size 0.7112)
		(drill 0.3556)
		(layers "F.Cu" "B.Cu")
		(net "GND")
	)
	(via
		(at 51.181 -482.727)
		(size 0.7112)
		(drill 0.4064)
		(layers "F.Cu" "B.Cu")
		(net "GND")
	)
	(via
		(at 39.116 -19.177)
		(size 0.7112)
		(drill 0.4064)
		(layers "F.Cu" "B.Cu")
		(net "GND")
	)
	(via
		(at 31.496 -336.296)
		(size 0.7112)
		(drill 0.4064)
		(layers "F.Cu" "B.Cu")
		(net "GND")
	)
	(via
		(at 16.129 -489.712)
		(size 0.7112)
		(drill 0.4064)
		(layers "F.Cu" "B.Cu")
		(net "GND")
	)
	(via
		(at 1.27 -125.73)
		(size 0.7112)
		(drill 0.4064)
		(layers "F.Cu" "B.Cu")
		(net "GND")
	)
	(via
		(at 4.064 -285.496)
		(size 0.7112)
		(drill 0.4064)
		(layers "F.Cu" "B.Cu")
		(net "GND")
	)
	(via
		(at 37.084 -198.755)
		(size 0.5588)
		(drill 0.3048)
		(layers "F.Cu" "B.Cu")
		(net "GND")
	)
	(via
		(at 17.7292 -145.8468)
		(size 0.7112)
		(drill 0.4064)
		(layers "F.Cu" "B.Cu")
		(net "GND")
	)
	(via
		(at 45.974 -181.737)
		(size 0.7112)
		(drill 0.4064)
		(layers "F.Cu" "B.Cu")
		(net "GND")
	)
	(via
		(at 26.162 -316.2046)
		(size 0.7112)
		(drill 0.4064)
		(layers "F.Cu" "B.Cu")
		(net "GND")
	)
	(via
		(at 23.8252 -350.4946)
		(size 0.7112)
		(drill 0.4064)
		(layers "F.Cu" "B.Cu")
		(net "GND")
	)
	(via
		(at 8.636 -237.363)
		(size 0.7112)
		(drill 0.4064)
		(layers "F.Cu" "B.Cu")
		(net "GND")
	)
	(via
		(at 15.3289 -38.5953)
		(size 0.5588)
		(drill 0.3048)
		(layers "F.Cu" "B.Cu")
		(net "GND")
	)
	(via
		(at 11.43 -362.712)
		(size 0.5588)
		(drill 0.3048)
		(layers "F.Cu" "B.Cu")
		(net "GND")
	)
	(via
		(at 51.435 -248.285)
		(size 0.5588)
		(drill 0.3048)
		(layers "F.Cu" "B.Cu")
		(net "GND")
	)
	(via
		(at 25.18918 -377.39066)
		(size 0.7112)
		(drill 0.4064)
		(layers "F.Cu" "B.Cu")
		(net "GND")
	)
	(segment
		(start 3.23469 -376.934476)
		(end 4.040124 -377.73991)
		(width 0.635)
		(layer "B.Cu")
		(net "GND")
	)
	(segment
		(start 41.143428 -294.999918)
		(end 45.500036 -294.999918)
		(width 0.635)
		(layer "B.Cu")
		(net "GND")
	)
	(segment
		(start 4.040124 -487.780076)
		(end 4.040124 -488.847384)
		(width 0.635)
		(layer "B.Cu")
		(net "GND")
	)
	(segment
		(start 39.459916 -46.199806)
		(end 40.539924 -46.199806)
		(width 0.635)
		(layer "B.Cu")
		(net "GND")
	)
	(segment
		(start 6.999986 -459.999842)
		(end 6.999986 -464.35645)
		(width 0.635)
		(layer "B.Cu")
		(net "GND")
	)
	(segment
		(start 39.459916 -41.119806)
		(end 40.539924 -41.119806)
		(width 0.635)
		(layer "B.Cu")
		(net "GND")
	)
	(segment
		(start 45.619924 -43.659806)
		(end 45.619924 -44.739814)
		(width 0.635)
		(layer "B.Cu")
		(net "GND")
	)
	(segment
		(start 2.972816 -487.780076)
		(end 4.040124 -487.780076)
		(width 0.635)
		(layer "B.Cu")
		(net "GND")
	)
	(segment
		(start 43.079924 -45.119798)
		(end 43.079924 -46.199806)
		(width 0.635)
		(layer "B.Cu")
		(net "GND")
	)
	(segment
		(start 45.449998 -337.49996)
		(end 45.449998 -342.618568)
		(width 0.635)
		(layer "B.Cu")
		(net "GND")
	)
	(segment
		(start 37.999924 -47.659798)
		(end 37.999924 -48.739806)
		(width 0.635)
		(layer "B.Cu")
		(net "GND")
	)
	(segment
		(start 41.999916 -43.659806)
		(end 43.079924 -43.659806)
		(width 0.635)
		(layer "B.Cu")
		(net "GND")
	)
	(segment
		(start 28.120086 -41.119806)
		(end 29.200094 -41.119806)
		(width 0.635)
		(layer "B.Cu")
		(net "GND")
	)
	(segment
		(start 25.580086 -42.579798)
		(end 25.580086 -43.659806)
		(width 0.635)
		(layer "B.Cu")
		(net "GND")
	)
	(segment
		(start 4.040124 -311.740042)
		(end 4.040124 -312.80735)
		(width 0.635)
		(layer "B.Cu")
		(net "GND")
	)
	(segment
		(start 37.999924 -48.739806)
		(end 39.079932 -48.739806)
		(width 0.635)
		(layer "B.Cu")
		(net "GND")
	)
	(segment
		(start 40.539924 -42.579798)
		(end 40.539924 -43.659806)
		(width 0.635)
		(layer "B.Cu")
		(net "GND")
	)
	(segment
		(start 25.580086 -41.119806)
		(end 25.580086 -42.199814)
		(width 0.635)
		(layer "B.Cu")
		(net "GND")
	)
	(segment
		(start 45.499782 -144.999964)
		(end 49.85639 -144.999964)
		(width 0.635)
		(layer "B.Cu")
		(net "GND")
	)
	(segment
		(start 40.539924 -48.739806)
		(end 40.539924 -49.819814)
		(width 0.635)
		(layer "B.Cu")
		(net "GND")
	)
	(segment
		(start 40.539924 -46.199806)
		(end 41.619932 -46.199806)
		(width 0.635)
		(layer "B.Cu")
		(net "GND")
	)
	(segment
		(start 41.999916 -46.199806)
		(end 43.079924 -46.199806)
		(width 0.635)
		(layer "B.Cu")
		(net "GND")
	)
	(segment
		(start 37.999924 -46.199806)
		(end 37.999924 -47.279814)
		(width 0.635)
		(layer "B.Cu")
		(net "GND")
	)
	(segment
		(start 41.143428 -19.99996)
		(end 45.500036 -19.99996)
		(width 0.635)
		(layer "B.Cu")
		(net "GND")
	)
	(segment
		(start 45.619924 -46.199806)
		(end 45.619924 -47.279814)
		(width 0.635)
		(layer "B.Cu")
		(net "GND")
	)
	(segment
		(start 40.539924 -41.119806)
		(end 41.619932 -41.119806)
		(width 0.635)
		(layer "B.Cu")
		(net "GND")
	)
	(segment
		(start 23.040086 -41.119806)
		(end 24.120094 -41.119806)
		(width 0.635)
		(layer "B.Cu")
		(net "GND")
	)
	(segment
		(start 20.500086 -40.039798)
		(end 20.500086 -41.119806)
		(width 0.635)
		(layer "B.Cu")
		(net "GND")
	)
	(segment
		(start 39.459916 -51.919886)
		(end 40.539924 -51.919886)
		(width 0.635)
		(layer "B.Cu")
		(net "GND")
	)
	(segment
		(start 40.539924 -45.119798)
		(end 40.539924 -46.199806)
		(width 0.635)
		(layer "B.Cu")
		(net "GND")
	)
	(segment
		(start 45.500036 -475.643448)
		(end 45.500036 -480.000056)
		(width 0.635)
		(layer "B.Cu")
		(net "GND")
	)
	(segment
		(start 40.999918 -438.831482)
		(end 40.999918 -443.95009)
		(width 0.635)
		(layer "B.Cu")
		(net "GND")
	)
	(segment
		(start 4.499864 -340.000082)
		(end 8.856472 -340.000082)
		(width 0.635)
		(layer "B.Cu")
		(net "GND")
	)
	(segment
		(start 28.120086 -41.119806)
		(end 28.120086 -42.199814)
		(width 0.635)
		(layer "B.Cu")
		(net "GND")
	)
	(segment
		(start 19.420078 -43.659806)
		(end 20.500086 -43.659806)
		(width 0.635)
		(layer "B.Cu")
		(net "GND")
	)
	(segment
		(start 43.079924 -47.659798)
		(end 43.079924 -48.739806)
		(width 0.635)
		(layer "B.Cu")
		(net "GND")
	)
	(segment
		(start 4.499864 -335.643474)
		(end 4.499864 -340.000082)
		(width 0.635)
		(layer "B.Cu")
		(net "GND")
	)
	(segment
		(start 28.120086 -43.659806)
		(end 29.200094 -43.659806)
		(width 0.635)
		(layer "B.Cu")
		(net "GND")
	)
	(segment
		(start 19.685508 -42.845228)
		(end 20.500086 -43.659806)
		(width 0.635)
		(layer "B.Cu")
		(net "GND")
	)
	(segment
		(start 45.499782 -144.999964)
		(end 45.499782 -149.356572)
		(width 0.635)
		(layer "B.Cu")
		(net "GND")
	)
	(segment
		(start 43.079924 -41.119806)
		(end 44.159932 -41.119806)
		(width 0.635)
		(layer "B.Cu")
		(net "GND")
	)
	(segment
		(start 45.619924 -46.199806)
		(end 46.699932 -46.199806)
		(width 0.635)
		(layer "B.Cu")
		(net "GND")
	)
	(segment
		(start 44.539916 -43.659806)
		(end 45.619924 -43.659806)
		(width 0.635)
		(layer "B.Cu")
		(net "GND")
	)
	(segment
		(start 40.539924 -62.079886)
		(end 40.539924 -63.159894)
		(width 0.635)
		(layer "B.Cu")
		(net "GND")
	)
	(segment
		(start 40.539924 -46.199806)
		(end 40.539924 -47.279814)
		(width 0.635)
		(layer "B.Cu")
		(net "GND")
	)
	(segment
		(start 40.539924 -41.119806)
		(end 40.539924 -42.199814)
		(width 0.635)
		(layer "B.Cu")
		(net "GND")
	)
	(segment
		(start 28.120086 -40.039798)
		(end 28.120086 -41.119806)
		(width 0.635)
		(layer "B.Cu")
		(net "GND")
	)
	(segment
		(start 36.919916 -41.119806)
		(end 37.999924 -41.119806)
		(width 0.635)
		(layer "B.Cu")
		(net "GND")
	)
	(segment
		(start 36.919916 -48.739806)
		(end 37.999924 -48.739806)
		(width 0.635)
		(layer "B.Cu")
		(net "GND")
	)
	(segment
		(start 40.539924 -43.659806)
		(end 40.539924 -44.739814)
		(width 0.635)
		(layer "B.Cu")
		(net "GND")
	)
	(segment
		(start 37.999924 -41.119806)
		(end 37.999924 -42.199814)
		(width 0.635)
		(layer "B.Cu")
		(net "GND")
	)
	(segment
		(start 23.040086 -41.119806)
		(end 23.040086 -42.199814)
		(width 0.635)
		(layer "B.Cu")
		(net "GND")
	)
	(segment
		(start 45.619924 -48.739806)
		(end 45.619924 -49.819814)
		(width 0.635)
		(layer "B.Cu")
		(net "GND")
	)
	(segment
		(start 43.079924 -43.659806)
		(end 43.079924 -44.739814)
		(width 0.635)
		(layer "B.Cu")
		(net "GND")
	)
	(segment
		(start 43.079924 -43.659806)
		(end 44.159932 -43.659806)
		(width 0.635)
		(layer "B.Cu")
		(net "GND")
	)
	(segment
		(start 36.919916 -46.199806)
		(end 37.999924 -46.199806)
		(width 0.635)
		(layer "B.Cu")
		(net "GND")
	)
	(segment
		(start 40.539924 -51.919886)
		(end 41.619932 -51.919886)
		(width 0.635)
		(layer "B.Cu")
		(net "GND")
	)
	(segment
		(start 40.999918 -463.049874)
		(end 40.999918 -468.168482)
		(width 0.635)
		(layer "B.Cu")
		(net "GND")
	)
	(segment
		(start 6.999986 -39.99992)
		(end 6.999986 -44.356528)
		(width 0.635)
		(layer "B.Cu")
		(net "GND")
	)
	(segment
		(start 6.999986 -35.643312)
		(end 6.999986 -39.99992)
		(width 0.635)
		(layer "B.Cu")
		(net "GND")
	)
	(segment
		(start 43.079924 -42.579798)
		(end 43.079924 -43.659806)
		(width 0.635)
		(layer "B.Cu")
		(net "GND")
	)
	(segment
		(start 43.079924 -40.039798)
		(end 43.079924 -41.119806)
		(width 0.635)
		(layer "B.Cu")
		(net "GND")
	)
	(segment
		(start 37.999924 -40.039798)
		(end 37.999924 -41.119806)
		(width 0.635)
		(layer "B.Cu")
		(net "GND")
	)
	(segment
		(start 39.459916 -48.739806)
		(end 40.539924 -48.739806)
		(width 0.635)
		(layer "B.Cu")
		(net "GND")
	)
	(segment
		(start 41.999916 -48.739806)
		(end 43.079924 -48.739806)
		(width 0.635)
		(layer "B.Cu")
		(net "GND")
	)
	(segment
		(start 40.999918 -443.95009)
		(end 40.999918 -449.068698)
		(width 0.635)
		(layer "B.Cu")
		(net "GND")
	)
	(segment
		(start 4.040124 -198.419974)
		(end 5.107432 -198.419974)
		(width 0.635)
		(layer "B.Cu")
		(net "GND")
	)
	(segment
		(start 43.079924 -41.119806)
		(end 43.079924 -42.199814)
		(width 0.635)
		(layer "B.Cu")
		(net "GND")
	)
	(segment
		(start 43.079924 -48.739806)
		(end 43.079924 -49.819814)
		(width 0.635)
		(layer "B.Cu")
		(net "GND")
	)
	(segment
		(start 40.539924 -40.039798)
		(end 40.539924 -41.119806)
		(width 0.635)
		(layer "B.Cu")
		(net "GND")
	)
	(segment
		(start 45.619924 -47.659798)
		(end 45.619924 -48.739806)
		(width 0.635)
		(layer "B.Cu")
		(net "GND")
	)
	(segment
		(start 45.500036 -15.643352)
		(end 45.500036 -19.99996)
		(width 0.635)
		(layer "B.Cu")
		(net "GND")
	)
	(segment
		(start 40.999918 -443.95009)
		(end 46.118526 -443.95009)
		(width 0.635)
		(layer "B.Cu")
		(net "GND")
	)
	(segment
		(start 45.500036 -19.99996)
		(end 45.500036 -24.356568)
		(width 0.635)
		(layer "B.Cu")
		(net "GND")
	)
	(segment
		(start 25.580086 -41.119806)
		(end 26.660094 -41.119806)
		(width 0.635)
		(layer "B.Cu")
		(net "GND")
	)
	(segment
		(start 6.999986 -159.999934)
		(end 6.999986 -164.356542)
		(width 0.635)
		(layer "B.Cu")
		(net "GND")
	)
	(segment
		(start 45.619924 -41.119806)
		(end 45.619924 -42.199814)
		(width 0.635)
		(layer "B.Cu")
		(net "GND")
	)
	(segment
		(start 40.33139 -337.49996)
		(end 45.449998 -337.49996)
		(width 0.635)
		(layer "B.Cu")
		(net "GND")
	)
	(segment
		(start 23.040086 -42.579798)
		(end 23.040086 -43.659806)
		(width 0.635)
		(layer "B.Cu")
		(net "GND")
	)
	(segment
		(start 45.619924 -48.739806)
		(end 46.699932 -48.739806)
		(width 0.635)
		(layer "B.Cu")
		(net "GND")
	)
	(segment
		(start 25.580086 -43.659806)
		(end 26.660094 -43.659806)
		(width 0.635)
		(layer "B.Cu")
		(net "GND")
	)
	(segment
		(start 45.619924 -43.659806)
		(end 46.699932 -43.659806)
		(width 0.635)
		(layer "B.Cu")
		(net "GND")
	)
	(segment
		(start 36.919916 -43.659806)
		(end 37.999924 -43.659806)
		(width 0.635)
		(layer "B.Cu")
		(net "GND")
	)
	(segment
		(start 41.999916 -41.119806)
		(end 43.079924 -41.119806)
		(width 0.635)
		(layer "B.Cu")
		(net "GND")
	)
	(segment
		(start 41.143428 -480.000056)
		(end 45.500036 -480.000056)
		(width 0.635)
		(layer "B.Cu")
		(net "GND")
	)
	(segment
		(start 4.040124 -487.780076)
		(end 5.107432 -487.780076)
		(width 0.635)
		(layer "B.Cu")
		(net "GND")
	)
	(segment
		(start 2.643378 -459.999842)
		(end 6.999986 -459.999842)
		(width 0.635)
		(layer "B.Cu")
		(net "GND")
	)
	(segment
		(start 37.999924 -46.199806)
		(end 39.079932 -46.199806)
		(width 0.635)
		(layer "B.Cu")
		(net "GND")
	)
	(segment
		(start 4.040124 -22.37994)
		(end 4.040124 -23.447248)
		(width 0.635)
		(layer "B.Cu")
		(net "GND")
	)
	(segment
		(start 40.999918 -457.931266)
		(end 40.999918 -463.049874)
		(width 0.635)
		(layer "B.Cu")
		(net "GND")
	)
	(segment
		(start 4.040124 -22.37994)
		(end 5.107432 -22.37994)
		(width 0.635)
		(layer "B.Cu")
		(net "GND")
	)
	(segment
		(start 45.499782 -140.643356)
		(end 45.499782 -144.999964)
		(width 0.635)
		(layer "B.Cu")
		(net "GND")
	)
	(segment
		(start 40.539924 -47.659798)
		(end 40.539924 -48.739806)
		(width 0.635)
		(layer "B.Cu")
		(net "GND")
	)
	(segment
		(start 24.500078 -41.119806)
		(end 25.580086 -41.119806)
		(width 0.635)
		(layer "B.Cu")
		(net "GND")
	)
	(segment
		(start 4.040124 -198.419974)
		(end 4.040124 -199.487282)
		(width 0.635)
		(layer "B.Cu")
		(net "GND")
	)
	(segment
		(start 6.999986 -39.99992)
		(end 11.356594 -39.99992)
		(width 0.635)
		(layer "B.Cu")
		(net "GND")
	)
	(segment
		(start 37.999924 -43.659806)
		(end 37.999924 -44.739814)
		(width 0.635)
		(layer "B.Cu")
		(net "GND")
	)
	(segment
		(start 27.040078 -43.659806)
		(end 28.120086 -43.659806)
		(width 0.635)
		(layer "B.Cu")
		(net "GND")
	)
	(segment
		(start 4.040124 -21.312632)
		(end 4.040124 -22.37994)
		(width 0.635)
		(layer "B.Cu")
		(net "GND")
	)
	(segment
		(start 40.539924 -48.739806)
		(end 41.619932 -48.739806)
		(width 0.635)
		(layer "B.Cu")
		(net "GND")
	)
	(segment
		(start 45.500036 -480.000056)
		(end 45.500036 -484.356664)
		(width 0.635)
		(layer "B.Cu")
		(net "GND")
	)
	(segment
		(start 4.040124 -197.352666)
		(end 4.040124 -198.419974)
		(width 0.635)
		(layer "B.Cu")
		(net "GND")
	)
	(segment
		(start 40.539924 -50.839878)
		(end 40.539924 -51.919886)
		(width 0.635)
		(layer "B.Cu")
		(net "GND")
	)
	(segment
		(start 45.500036 -19.99996)
		(end 49.856644 -19.99996)
		(width 0.635)
		(layer "B.Cu")
		(net "GND")
	)
	(segment
		(start 2.643378 -39.99992)
		(end 6.999986 -39.99992)
		(width 0.635)
		(layer "B.Cu")
		(net "GND")
	)
	(segment
		(start 4.040124 -310.672734)
		(end 4.040124 -311.740042)
		(width 0.635)
		(layer "B.Cu")
		(net "GND")
	)
	(segment
		(start 25.580086 -40.039798)
		(end 25.580086 -41.119806)
		(width 0.635)
		(layer "B.Cu")
		(net "GND")
	)
	(segment
		(start 2.972816 -198.419974)
		(end 4.040124 -198.419974)
		(width 0.635)
		(layer "B.Cu")
		(net "GND")
	)
	(segment
		(start 4.040124 -376.672602)
		(end 4.040124 -377.73991)
		(width 0.635)
		(layer "B.Cu")
		(net "GND")
	)
	(segment
		(start 24.500078 -43.659806)
		(end 25.580086 -43.659806)
		(width 0.635)
		(layer "B.Cu")
		(net "GND")
	)
	(segment
		(start 21.960078 -41.119806)
		(end 23.040086 -41.119806)
		(width 0.635)
		(layer "B.Cu")
		(net "GND")
	)
	(segment
		(start 40.539924 -43.659806)
		(end 41.619932 -43.659806)
		(width 0.635)
		(layer "B.Cu")
		(net "GND")
	)
	(segment
		(start 23.040086 -62.079886)
		(end 24.120094 -62.079886)
		(width 0.635)
		(layer "B.Cu")
		(net "GND")
	)
	(segment
		(start 6.999986 -459.999842)
		(end 11.356594 -459.999842)
		(width 0.635)
		(layer "B.Cu")
		(net "GND")
	)
	(segment
		(start 45.500036 -480.000056)
		(end 49.856644 -480.000056)
		(width 0.635)
		(layer "B.Cu")
		(net "GND")
	)
	(segment
		(start 2.972816 -22.37994)
		(end 4.040124 -22.37994)
		(width 0.635)
		(layer "B.Cu")
		(net "GND")
	)
	(segment
		(start 4.040124 -311.740042)
		(end 5.107432 -311.740042)
		(width 0.635)
		(layer "B.Cu")
		(net "GND")
	)
	(segment
		(start 43.079924 -46.199806)
		(end 44.159932 -46.199806)
		(width 0.635)
		(layer "B.Cu")
		(net "GND")
	)
	(segment
		(start 43.079924 -48.739806)
		(end 44.159932 -48.739806)
		(width 0.635)
		(layer "B.Cu")
		(net "GND")
	)
	(segment
		(start 45.619924 -42.579798)
		(end 45.619924 -43.659806)
		(width 0.635)
		(layer "B.Cu")
		(net "GND")
	)
	(segment
		(start 41.143174 -144.999964)
		(end 45.499782 -144.999964)
		(width 0.635)
		(layer "B.Cu")
		(net "GND")
	)
	(segment
		(start 2.972816 -311.740042)
		(end 4.040124 -311.740042)
		(width 0.635)
		(layer "B.Cu")
		(net "GND")
	)
	(segment
		(start 39.459916 -43.659806)
		(end 40.539924 -43.659806)
		(width 0.635)
		(layer "B.Cu")
		(net "GND")
	)
	(segment
		(start 28.120086 -42.579798)
		(end 28.120086 -43.659806)
		(width 0.635)
		(layer "B.Cu")
		(net "GND")
	)
	(segment
		(start 37.999924 -42.579798)
		(end 37.999924 -43.659806)
		(width 0.635)
		(layer "B.Cu")
		(net "GND")
	)
	(segment
		(start 23.040086 -43.659806)
		(end 24.120094 -43.659806)
		(width 0.635)
		(layer "B.Cu")
		(net "GND")
	)
	(segment
		(start 35.88131 -443.95009)
		(end 40.999918 -443.95009)
		(width 0.635)
		(layer "B.Cu")
		(net "GND")
	)
	(segment
		(start 44.539916 -41.119806)
		(end 45.619924 -41.119806)
		(width 0.635)
		(layer "B.Cu")
		(net "GND")
	)
	(segment
		(start 20.500086 -41.119806)
		(end 21.580094 -41.119806)
		(width 0.635)
		(layer "B.Cu")
		(net "GND")
	)
	(segment
		(start 6.999986 -455.643234)
		(end 6.999986 -459.999842)
		(width 0.635)
		(layer "B.Cu")
		(net "GND")
	)
	(segment
		(start 43.079924 -46.199806)
		(end 43.079924 -47.279814)
		(width 0.635)
		(layer "B.Cu")
		(net "GND")
	)
	(segment
		(start 23.040086 -62.079886)
		(end 23.040086 -63.159894)
		(width 0.635)
		(layer "B.Cu")
		(net "GND")
	)
	(segment
		(start 4.499864 -340.000082)
		(end 4.499864 -344.35669)
		(width 0.635)
		(layer "B.Cu")
		(net "GND")
	)
	(segment
		(start 37.999924 -45.119798)
		(end 37.999924 -46.199806)
		(width 0.635)
		(layer "B.Cu")
		(net "GND")
	)
	(segment
		(start 37.999924 -48.739806)
		(end 37.999924 -49.819814)
		(width 0.635)
		(layer "B.Cu")
		(net "GND")
	)
	(segment
		(start 35.88131 -463.049874)
		(end 40.999918 -463.049874)
		(width 0.635)
		(layer "B.Cu")
		(net "GND")
	)
	(segment
		(start 39.459916 -62.079886)
		(end 40.539924 -62.079886)
		(width 0.635)
		(layer "B.Cu")
		(net "GND")
	)
	(segment
		(start 45.449998 -337.49996)
		(end 50.568606 -337.49996)
		(width 0.635)
		(layer "B.Cu")
		(net "GND")
	)
	(segment
		(start 45.500036 -290.64331)
		(end 45.500036 -294.999918)
		(width 0.635)
		(layer "B.Cu")
		(net "GND")
	)
	(segment
		(start 4.040124 -486.712768)
		(end 4.040124 -487.780076)
		(width 0.635)
		(layer "B.Cu")
		(net "GND")
	)
	(segment
		(start 40.999918 -463.049874)
		(end 46.118526 -463.049874)
		(width 0.635)
		(layer "B.Cu")
		(net "GND")
	)
	(segment
		(start 44.539916 -48.739806)
		(end 45.619924 -48.739806)
		(width 0.635)
		(layer "B.Cu")
		(net "GND")
	)
	(segment
		(start 45.500036 -294.999918)
		(end 45.500036 -299.356526)
		(width 0.635)
		(layer "B.Cu")
		(net "GND")
	)
	(segment
		(start 27.040078 -41.119806)
		(end 28.120086 -41.119806)
		(width 0.635)
		(layer "B.Cu")
		(net "GND")
	)
	(segment
		(start 45.619924 -45.119798)
		(end 45.619924 -46.199806)
		(width 0.635)
		(layer "B.Cu")
		(net "GND")
	)
	(segment
		(start 45.500036 -294.999918)
		(end 49.856644 -294.999918)
		(width 0.635)
		(layer "B.Cu")
		(net "GND")
	)
	(segment
		(start 6.999986 -155.643326)
		(end 6.999986 -159.999934)
		(width 0.635)
		(layer "B.Cu")
		(net "GND")
	)
	(segment
		(start 45.619924 -40.039798)
		(end 45.619924 -41.119806)
		(width 0.635)
		(layer "B.Cu")
		(net "GND")
	)
	(segment
		(start 23.040086 -40.039798)
		(end 23.040086 -41.119806)
		(width 0.635)
		(layer "B.Cu")
		(net "GND")
	)
	(segment
		(start 45.619924 -41.119806)
		(end 46.699932 -41.119806)
		(width 0.635)
		(layer "B.Cu")
		(net "GND")
	)
	(segment
		(start 37.999924 -41.119806)
		(end 39.079932 -41.119806)
		(width 0.635)
		(layer "B.Cu")
		(net "GND")
	)
	(segment
		(start 37.999924 -43.659806)
		(end 39.079932 -43.659806)
		(width 0.635)
		(layer "B.Cu")
		(net "GND")
	)
	(segment
		(start 44.539916 -46.199806)
		(end 45.619924 -46.199806)
		(width 0.635)
		(layer "B.Cu")
		(net "GND")
	)
	(segment
		(start 45.449998 -332.381352)
		(end 45.449998 -337.49996)
		(width 0.635)
		(layer "B.Cu")
		(net "GND")
	)
	(segment
		(start 25.8826 -165.5826)
		(end 25.8826 -166.1414)
		(width 0.1397)
		(layer "F.Cu")
		(net "NCT7904D_PWM4")
	)
	(segment
		(start 27.373834 -164.091366)
		(end 25.8826 -165.5826)
		(width 0.1397)
		(layer "F.Cu")
		(net "NCT7904D_PWM4")
	)
	(segment
		(start 27.61234 -164.091366)
		(end 27.373834 -164.091366)
		(width 0.1397)
		(layer "F.Cu")
		(net "NCT7904D_PWM4")
	)
	(segment
		(start 26.6446 -167.3225)
		(end 28.2321 -167.3225)
		(width 0.1397)
		(layer "F.Cu")
		(net "NCT7904D_PWM3")
	)
	(segment
		(start 28.61183 -165.164262)
		(end 28.61183 -164.091366)
		(width 0.1397)
		(layer "F.Cu")
		(net "NCT7904D_PWM3")
	)
	(segment
		(start 28.09875 -165.677342)
		(end 28.61183 -165.164262)
		(width 0.1397)
		(layer "F.Cu")
		(net "NCT7904D_PWM3")
	)
	(segment
		(start 28.2321 -167.3225)
		(end 28.2956 -167.259)
		(width 0.1397)
		(layer "F.Cu")
		(net "NCT7904D_PWM3")
	)
	(segment
		(start 28.2956 -166.5224)
		(end 28.09875 -166.32555)
		(width 0.1397)
		(layer "F.Cu")
		(net "NCT7904D_PWM3")
	)
	(segment
		(start 28.2956 -167.259)
		(end 28.2956 -166.5224)
		(width 0.1397)
		(layer "F.Cu")
		(net "NCT7904D_PWM3")
	)
	(segment
		(start 28.09875 -166.32555)
		(end 28.09875 -165.677342)
		(width 0.1397)
		(layer "F.Cu")
		(net "NCT7904D_PWM3")
	)
	(via
		(at 28.2956 -167.259)
		(size 0.7112)
		(drill 0.3556)
		(layers "F.Cu" "B.Cu")
		(net "NCT7904D_PWM3")
	)
	(segment
		(start 30.2641 -166.8145)
		(end 30.3022 -166.7764)
		(width 0.1397)
		(layer "F.Cu")
		(net "NCT7904D_PWM2")
	)
	(segment
		(start 29.3624 -166.8145)
		(end 30.2641 -166.8145)
		(width 0.1397)
		(layer "F.Cu")
		(net "NCT7904D_PWM2")
	)
	(segment
		(start 29.3116 -166.7637)
		(end 29.3116 -165.721792)
		(width 0.1397)
		(layer "F.Cu")
		(net "NCT7904D_PWM2")
	)
	(segment
		(start 29.3116 -165.721792)
		(end 29.61132 -165.422072)
		(width 0.1397)
		(layer "F.Cu")
		(net "NCT7904D_PWM2")
	)
	(segment
		(start 29.61132 -165.422072)
		(end 29.61132 -164.091366)
		(width 0.1397)
		(layer "F.Cu")
		(net "NCT7904D_PWM2")
	)
	(segment
		(start 29.3624 -166.8145)
		(end 29.3116 -166.7637)
		(width 0.1397)
		(layer "F.Cu")
		(net "NCT7904D_PWM2")
	)
	(via
		(at 30.3022 -166.7764)
		(size 0.7112)
		(drill 0.3556)
		(layers "F.Cu" "B.Cu")
		(net "NCT7904D_PWM2")
	)
	(segment
		(start 31.010352 -169.141648)
		(end 31.010352 -166.702994)
		(width 0.1397)
		(layer "F.Cu")
		(net "NCT7904D_PWM1")
	)
	(segment
		(start 31.010352 -166.702994)
		(end 30.61208 -166.304722)
		(width 0.1397)
		(layer "F.Cu")
		(net "NCT7904D_PWM1")
	)
	(segment
		(start 30.6959 -169.4561)
		(end 31.010352 -169.141648)
		(width 0.1397)
		(layer "F.Cu")
		(net "NCT7904D_PWM1")
	)
	(segment
		(start 29.5402 -169.4561)
		(end 30.6959 -169.4561)
		(width 0.1397)
		(layer "F.Cu")
		(net "NCT7904D_PWM1")
	)
	(segment
		(start 30.61208 -166.304722)
		(end 30.61208 -164.091366)
		(width 0.1397)
		(layer "F.Cu")
		(net "NCT7904D_PWM1")
	)
	(via
		(at 31.010352 -169.141648)
		(size 0.7112)
		(drill 0.3556)
		(layers "F.Cu" "B.Cu")
		(net "NCT7904D_PWM1")
	)
	(segment
		(start 4.040124 -19.83994)
		(end 5.107432 -19.83994)
		(width 0.635)
		(layer "F.Cu")
		(net "P12V_FAN6")
	)
	(segment
		(start 4.040124 -19.83994)
		(end 4.040124 -20.907248)
		(width 0.635)
		(layer "F.Cu")
		(net "P12V_FAN6")
	)
	(segment
		(start 2.972816 -19.83994)
		(end 4.040124 -19.83994)
		(width 0.635)
		(layer "F.Cu")
		(net "P12V_FAN6")
	)
	(segment
		(start 4.040124 -18.772632)
		(end 4.040124 -19.83994)
		(width 0.635)
		(layer "F.Cu")
		(net "P12V_FAN6")
	)
	(segment
		(start 25.527 -360.045)
		(end 25.2984 -359.8164)
		(width 0.254)
		(layer "F.Cu")
		(net "ADM1276_UV")
	)
	(segment
		(start 25.781 -372.618)
		(end 27.813 -372.618)
		(width 0.254)
		(layer "F.Cu")
		(net "ADM1276_UV")
	)
	(segment
		(start 27.813 -372.618)
		(end 28.418028 -372.012972)
		(width 0.254)
		(layer "F.Cu")
		(net "ADM1276_UV")
	)
	(segment
		(start 22.2885 -376.936)
		(end 22.2885 -375.2977)
		(width 0.254)
		(layer "F.Cu")
		(net "ADM1276_UV")
	)
	(segment
		(start 22.2885 -375.2977)
		(end 22.3012 -375.285)
		(width 0.254)
		(layer "F.Cu")
		(net "ADM1276_UV")
	)
	(segment
		(start 23.1775 -368.554)
		(end 22.0726 -368.554)
		(width 0.254)
		(layer "F.Cu")
		(net "ADM1276_UV")
	)
	(segment
		(start 28.418028 -372.012972)
		(end 28.418028 -371.2464)
		(width 0.254)
		(layer "F.Cu")
		(net "ADM1276_UV")
	)
	(segment
		(start 22.733 -374.8405)
		(end 23.749 -374.8405)
		(width 0.254)
		(layer "F.Cu")
		(net "ADM1276_UV")
	)
	(segment
		(start 23.749 -374.65)
		(end 25.781 -372.618)
		(width 0.254)
		(layer "F.Cu")
		(net "ADM1276_UV")
	)
	(segment
		(start 25.527 -360.7435)
		(end 25.527 -360.045)
		(width 0.254)
		(layer "F.Cu")
		(net "ADM1276_UV")
	)
	(segment
		(start 25.2984 -359.8164)
		(end 25.2984 -359.791)
		(width 0.254)
		(layer "F.Cu")
		(net "ADM1276_UV")
	)
	(segment
		(start 22.3012 -375.2723)
		(end 22.733 -374.8405)
		(width 0.254)
		(layer "F.Cu")
		(net "ADM1276_UV")
	)
	(segment
		(start 23.749 -374.8405)
		(end 23.749 -374.65)
		(width 0.254)
		(layer "F.Cu")
		(net "ADM1276_UV")
	)
	(segment
		(start 22.3012 -375.285)
		(end 22.3012 -375.2723)
		(width 0.254)
		(layer "F.Cu")
		(net "ADM1276_UV")
	)
	(segment
		(start 23.1902 -378.1044)
		(end 22.2885 -377.2027)
		(width 0.254)
		(layer "F.Cu")
		(net "ADM1276_UV")
	)
	(segment
		(start 22.2885 -377.2027)
		(end 22.2885 -376.936)
		(width 0.254)
		(layer "F.Cu")
		(net "ADM1276_UV")
	)
	(via
		(at 22.7584 -371.856)
		(size 0.7112)
		(drill 0.3556)
		(layers "F.Cu" "B.Cu")
		(net "ADM1276_UV")
	)
	(via
		(at 23.1902 -378.1044)
		(size 0.7112)
		(drill 0.4064)
		(layers "F.Cu" "B.Cu")
		(net "ADM1276_UV")
	)
	(via
		(at 22.0726 -368.554)
		(size 0.7112)
		(drill 0.4064)
		(layers "F.Cu" "B.Cu")
		(net "ADM1276_UV")
	)
	(via
		(at 25.2984 -359.791)
		(size 0.7112)
		(drill 0.4064)
		(layers "F.Cu" "B.Cu")
		(net "ADM1276_UV")
	)
	(segment
		(start 22.0726 -368.554)
		(end 22.7584 -369.2398)
		(width 0.254)
		(layer "B.Cu")
		(net "ADM1276_UV")
	)
	(segment
		(start 22.7584 -371.856)
		(end 22.7584 -377.6726)
		(width 0.254)
		(layer "B.Cu")
		(net "ADM1276_UV")
	)
	(segment
		(start 22.86 -359.791)
		(end 21.4884 -361.1626)
		(width 0.254)
		(layer "B.Cu")
		(net "ADM1276_UV")
	)
	(segment
		(start 22.7584 -377.6726)
		(end 23.1902 -378.1044)
		(width 0.254)
		(layer "B.Cu")
		(net "ADM1276_UV")
	)
	(segment
		(start 25.2984 -359.791)
		(end 22.86 -359.791)
		(width 0.254)
		(layer "B.Cu")
		(net "ADM1276_UV")
	)
	(segment
		(start 22.7584 -369.2398)
		(end 22.7584 -371.856)
		(width 0.254)
		(layer "B.Cu")
		(net "ADM1276_UV")
	)
	(segment
		(start 21.4884 -367.9698)
		(end 22.0726 -368.554)
		(width 0.254)
		(layer "B.Cu")
		(net "ADM1276_UV")
	)
	(segment
		(start 21.4884 -361.1626)
		(end 21.4884 -367.9698)
		(width 0.254)
		(layer "B.Cu")
		(net "ADM1276_UV")
	)
	(segment
		(start 4.040124 -194.812666)
		(end 4.040124 -195.879974)
		(width 0.635)
		(layer "F.Cu")
		(net "P12V_FAN4")
	)
	(segment
		(start 4.040124 -195.879974)
		(end 4.040124 -196.947282)
		(width 0.635)
		(layer "F.Cu")
		(net "P12V_FAN4")
	)
	(segment
		(start 2.972816 -195.879974)
		(end 4.040124 -195.879974)
		(width 0.635)
		(layer "F.Cu")
		(net "P12V_FAN4")
	)
	(segment
		(start 4.040124 -195.879974)
		(end 5.107432 -195.879974)
		(width 0.635)
		(layer "F.Cu")
		(net "P12V_FAN4")
	)
	(via
		(at 16.51 -194.564)
		(size 0.7112)
		(drill 0.3556)
		(layers "F.Cu" "B.Cu")
		(net "P12V_FAN4")
	)
	(via
		(at 16.51 -196.85)
		(size 0.7112)
		(drill 0.3556)
		(layers "F.Cu" "B.Cu")
		(net "P12V_FAN4")
	)
	(segment
		(start 2.972816 -375.19991)
		(end 4.040124 -375.19991)
		(width 0.635)
		(layer "F.Cu")
		(net "P12V_FAN2")
	)
	(segment
		(start 4.040124 -374.132602)
		(end 4.040124 -375.19991)
		(width 0.635)
		(layer "F.Cu")
		(net "P12V_FAN2")
	)
	(segment
		(start 4.040124 -375.19991)
		(end 5.107432 -375.19991)
		(width 0.635)
		(layer "F.Cu")
		(net "P12V_FAN2")
	)
	(segment
		(start 4.040124 -375.19991)
		(end 4.040124 -376.267218)
		(width 0.635)
		(layer "F.Cu")
		(net "P12V_FAN2")
	)
	(via
		(at 18.034 -313.0804)
		(size 0.7112)
		(drill 0.3556)
		(layers "F.Cu" "B.Cu")
		(net "P12V_FAN2")
	)
	(segment
		(start 4.040124 -129.880106)
		(end 5.107432 -129.880106)
		(width 0.635)
		(layer "F.Cu")
		(net "P12V_FAN5")
	)
	(segment
		(start 4.040124 -129.880106)
		(end 4.040124 -130.947414)
		(width 0.635)
		(layer "F.Cu")
		(net "P12V_FAN5")
	)
	(segment
		(start 2.972816 -129.880106)
		(end 4.040124 -129.880106)
		(width 0.635)
		(layer "F.Cu")
		(net "P12V_FAN5")
	)
	(via
		(at 2.794 -146.812)
		(size 0.7112)
		(drill 0.3556)
		(layers "F.Cu" "B.Cu")
		(net "P12V_FAN5")
	)
	(via
		(at 6.9342 -150.622)
		(size 0.7112)
		(drill 0.3556)
		(layers "F.Cu" "B.Cu")
		(net "P12V_FAN5")
	)
	(via
		(at 9.398 -153.67)
		(size 0.7112)
		(drill 0.3556)
		(layers "F.Cu" "B.Cu")
		(net "P12V_FAN5")
	)
	(segment
		(start 4.040124 -309.200042)
		(end 4.040124 -310.26735)
		(width 0.635)
		(layer "F.Cu")
		(net "P12V_FAN3")
	)
	(segment
		(start 4.040124 -308.132734)
		(end 4.040124 -309.200042)
		(width 0.635)
		(layer "F.Cu")
		(net "P12V_FAN3")
	)
	(segment
		(start 2.972816 -309.200042)
		(end 4.040124 -309.200042)
		(width 0.635)
		(layer "F.Cu")
		(net "P12V_FAN3")
	)
	(segment
		(start 4.040124 -309.200042)
		(end 5.107432 -309.200042)
		(width 0.635)
		(layer "F.Cu")
		(net "P12V_FAN3")
	)
	(via
		(at 13.2334 -287.7058)
		(size 0.7112)
		(drill 0.3556)
		(layers "F.Cu" "B.Cu")
		(net "P12V_FAN3")
	)
	(segment
		(start 4.040124 -484.172768)
		(end 4.040124 -485.240076)
		(width 0.635)
		(layer "F.Cu")
		(net "P12V_FAN1")
	)
	(segment
		(start 4.040124 -485.240076)
		(end 5.107432 -485.240076)
		(width 0.635)
		(layer "F.Cu")
		(net "P12V_FAN1")
	)
	(segment
		(start 4.040124 -485.240076)
		(end 4.040124 -486.307384)
		(width 0.635)
		(layer "F.Cu")
		(net "P12V_FAN1")
	)
	(segment
		(start 2.972816 -485.240076)
		(end 4.040124 -485.240076)
		(width 0.635)
		(layer "F.Cu")
		(net "P12V_FAN1")
	)
	(via
		(at 16.764 -486.918)
		(size 0.7112)
		(drill 0.3556)
		(layers "F.Cu" "B.Cu")
		(net "P12V_FAN1")
	)
	(via
		(at 20.828 -486.41)
		(size 0.7112)
		(drill 0.3556)
		(layers "F.Cu" "B.Cu")
		(net "P12V_FAN1")
	)
	(segment
		(start 24.257 -371.0305)
		(end 22.9743 -371.0305)
		(width 0.254)
		(layer "F.Cu")
		(net "ADM1276_OV")
	)
	(segment
		(start 22.7203 -371.2845)
		(end 22.733 -371.2718)
		(width 0.254)
		(layer "F.Cu")
		(net "ADM1276_OV")
	)
	(segment
		(start 21.209 -371.2845)
		(end 22.7203 -371.2845)
		(width 0.254)
		(layer "F.Cu")
		(net "ADM1276_OV")
	)
	(segment
		(start 26.513028 -370.107972)
		(end 27.2796 -370.107972)
		(width 0.254)
		(layer "F.Cu")
		(net "ADM1276_OV")
	)
	(segment
		(start 24.257 -371.0305)
		(end 25.654 -371.0305)
		(width 0.254)
		(layer "F.Cu")
		(net "ADM1276_OV")
	)
	(segment
		(start 22.9743 -371.0305)
		(end 22.733 -371.2718)
		(width 0.254)
		(layer "F.Cu")
		(net "ADM1276_OV")
	)
	(segment
		(start 25.654 -371.0305)
		(end 25.654 -370.967)
		(width 0.254)
		(layer "F.Cu")
		(net "ADM1276_OV")
	)
	(segment
		(start 25.654 -370.967)
		(end 26.513028 -370.107972)
		(width 0.254)
		(layer "F.Cu")
		(net "ADM1276_OV")
	)
	(via
		(at 25.654 -371.0305)
		(size 0.7112)
		(drill 0.3556)
		(layers "F.Cu" "B.Cu")
		(net "ADM1276_OV")
	)
	(segment
		(start 44.704 -124.701808)
		(end 44.704 -124.3584)
		(width 0.508)
		(layer "F.Cu")
		(net "P12V")
	)
	(segment
		(start 12.6746 -224.4852)
		(end 13.1826 -224.4852)
		(width 0.508)
		(layer "F.Cu")
		(net "P12V")
	)
	(segment
		(start 5.4864 -84.7852)
		(end 5.4864 -84.3788)
		(width 0.508)
		(layer "F.Cu")
		(net "P12V")
	)
	(segment
		(start 40.4495 -149.86)
		(end 39.6875 -149.098)
		(width 0.508)
		(layer "F.Cu")
		(net "P12V")
	)
	(segment
		(start 10.5664 -453.136)
		(end 10.668 -453.2376)
		(width 0.508)
		(layer "F.Cu")
		(net "P12V")
	)
	(segment
		(start 13.1826 -224.4852)
		(end 14.1478 -223.52)
		(width 0.508)
		(layer "F.Cu")
		(net "P12V")
	)
	(segment
		(start 39.9923 -146.9771)
		(end 39.2684 -147.701)
		(width 0.508)
		(layer "F.Cu")
		(net "P12V")
	)
	(segment
		(start 18.3261 -256.667)
		(end 18.6563 -256.9972)
		(width 0.508)
		(layer "F.Cu")
		(net "P12V")
	)
	(segment
		(start 40.753792 -124.676408)
		(end 42.799 -122.6312)
		(width 0.508)
		(layer "F.Cu")
		(net "P12V")
	)
	(segment
		(start 42.799 -122.6312)
		(end 42.9768 -122.6312)
		(width 0.508)
		(layer "F.Cu")
		(net "P12V")
	)
	(segment
		(start 40.753792 -124.701808)
		(end 40.753792 -124.676408)
		(width 0.508)
		(layer "F.Cu")
		(net "P12V")
	)
	(segment
		(start 23.7617 -134.7343)
		(end 23.1902 -134.1628)
		(width 0.508)
		(layer "F.Cu")
		(net "P12V")
	)
	(segment
		(start 18.3515 -298.4754)
		(end 18.3515 -297.7261)
		(width 0.508)
		(layer "F.Cu")
		(net "P12V")
	)
	(segment
		(start 9.8806 -63.627)
		(end 9.8806 -62.7126)
		(width 0.508)
		(layer "F.Cu")
		(net "P12V")
	)
	(segment
		(start 13.2588 -62.1538)
		(end 12.064746 -62.1538)
		(width 0.508)
		(layer "F.Cu")
		(net "P12V")
	)
	(segment
		(start 16.256 -249.047)
		(end 16.2433 -249.0343)
		(width 0.508)
		(layer "F.Cu")
		(net "P12V")
	)
	(segment
		(start 24.4094 -134.7343)
		(end 23.7617 -134.7343)
		(width 0.508)
		(layer "F.Cu")
		(net "P12V")
	)
	(segment
		(start 12.064746 -62.1538)
		(end 12.064492 -62.153546)
		(width 0.508)
		(layer "F.Cu")
		(net "P12V")
	)
	(segment
		(start 42.1894 -134.0866)
		(end 43.0403 -134.0866)
		(width 0.508)
		(layer "F.Cu")
		(net "P12V")
	)
	(segment
		(start 17.526 -184.6072)
		(end 17.526 -184.658)
		(width 0.508)
		(layer "F.Cu")
		(net "P12V")
	)
	(segment
		(start 3.5814 -418.7952)
		(end 2.667 -418.7952)
		(width 0.508)
		(layer "F.Cu")
		(net "P12V")
	)
	(segment
		(start 17.895316 -15.247874)
		(end 17.895316 -16.053816)
		(width 0.508)
		(layer "F.Cu")
		(net "P12V")
	)
	(segment
		(start 9.7028 -450.6976)
		(end 9.8552 -450.85)
		(width 0.508)
		(layer "F.Cu")
		(net "P12V")
	)
	(segment
		(start 9.906 -146.7739)
		(end 9.398 -146.7739)
		(width 0.508)
		(layer "F.Cu")
		(net "P12V")
	)
	(segment
		(start 8.0264 -260.1722)
		(end 8.4836 -259.715)
		(width 0.508)
		(layer "F.Cu")
		(net "P12V")
	)
	(segment
		(start 16.1036 -147.5486)
		(end 16.1036 -147.6756)
		(width 0.508)
		(layer "F.Cu")
		(net "P12V")
	)
	(segment
		(start 19.2405 -259.334)
		(end 19.2659 -259.3086)
		(width 0.508)
		(layer "F.Cu")
		(net "P12V")
	)
	(segment
		(start 12.2936 -445.0461)
		(end 12.2682 -445.0715)
		(width 0.508)
		(layer "F.Cu")
		(net "P12V")
	)
	(segment
		(start 23.1775 -179.8066)
		(end 23.1775 -178.9938)
		(width 0.508)
		(layer "F.Cu")
		(net "P12V")
	)
	(segment
		(start 40.132 -146.9771)
		(end 39.9923 -146.9771)
		(width 0.508)
		(layer "F.Cu")
		(net "P12V")
	)
	(segment
		(start 17.25803 -13.462)
		(end 16.383 -13.462)
		(width 0.508)
		(layer "F.Cu")
		(net "P12V")
	)
	(segment
		(start 4.1148 -420.9034)
		(end 4.1148 -419.3286)
		(width 0.508)
		(layer "F.Cu")
		(net "P12V")
	)
	(segment
		(start 40.132 -124.701808)
		(end 40.753792 -124.701808)
		(width 0.508)
		(layer "F.Cu")
		(net "P12V")
	)
	(segment
		(start 3.5306 -433.2732)
		(end 3.5306 -433.3748)
		(width 0.508)
		(layer "F.Cu")
		(net "P12V")
	)
	(segment
		(start 4.1148 -419.3286)
		(end 3.5814 -418.7952)
		(width 0.508)
		(layer "F.Cu")
		(net "P12V")
	)
	(segment
		(start 22.822408 -124.828808)
		(end 20.828 -122.8344)
		(width 0.508)
		(layer "F.Cu")
		(net "P12V")
	)
	(segment
		(start 17.271492 -13.475462)
		(end 17.25803 -13.462)
		(width 0.508)
		(layer "F.Cu")
		(net "P12V")
	)
	(segment
		(start 40.4495 -149.9235)
		(end 40.4495 -149.86)
		(width 0.508)
		(layer "F.Cu")
		(net "P12V")
	)
	(segment
		(start 22.86 -124.828808)
		(end 22.822408 -124.828808)
		(width 0.508)
		(layer "F.Cu")
		(net "P12V")
	)
	(segment
		(start 16.2433 -249.0343)
		(end 14.5034 -249.0343)
		(width 0.508)
		(layer "F.Cu")
		(net "P12V")
	)
	(segment
		(start 8.4836 -259.715)
		(end 9.906 -259.715)
		(width 0.508)
		(layer "F.Cu")
		(net "P12V")
	)
	(segment
		(start 12.064492 -62.889892)
		(end 12.319 -63.1444)
		(width 0.508)
		(layer "F.Cu")
		(net "P12V")
	)
	(segment
		(start 19.2405 -261.6454)
		(end 19.7485 -262.1534)
		(width 0.508)
		(layer "F.Cu")
		(net "P12V")
	)
	(segment
		(start 17.526 -184.658)
		(end 17.4625 -184.7215)
		(width 0.508)
		(layer "F.Cu")
		(net "P12V")
	)
	(segment
		(start 8.6741 -450.6976)
		(end 9.7028 -450.6976)
		(width 0.508)
		(layer "F.Cu")
		(net "P12V")
	)
	(segment
		(start 10.795 -64.5414)
		(end 9.8806 -63.627)
		(width 0.508)
		(layer "F.Cu")
		(net "P12V")
	)
	(segment
		(start 18.288 -124.828808)
		(end 18.833592 -124.828808)
		(width 0.508)
		(layer "F.Cu")
		(net "P12V")
	)
	(segment
		(start 10.5664 -445.5795)
		(end 10.5664 -443.7126)
		(width 0.508)
		(layer "F.Cu")
		(net "P12V")
	)
	(segment
		(start 9.7663 -454.1393)
		(end 9.7663 -454.2028)
		(width 0.508)
		(layer "F.Cu")
		(net "P12V")
	)
	(segment
		(start 18.3261 -255.0922)
		(end 18.3261 -256.667)
		(width 0.508)
		(layer "F.Cu")
		(net "P12V")
	)
	(segment
		(start 15.4813 -146.6088)
		(end 15.4813 -146.9263)
		(width 0.508)
		(layer "F.Cu")
		(net "P12V")
	)
	(segment
		(start 12.2936 -443.7126)
		(end 12.2936 -445.0461)
		(width 0.508)
		(layer "F.Cu")
		(net "P12V")
	)
	(segment
		(start 44.704 -124.3584)
		(end 42.9768 -122.6312)
		(width 0.508)
		(layer "F.Cu")
		(net "P12V")
	)
	(segment
		(start 14.8209 -150.622)
		(end 14.8209 -148.336)
		(width 0.508)
		(layer "F.Cu")
		(net "P12V")
	)
	(segment
		(start 5.4864 -84.3788)
		(end 6.4262 -83.439)
		(width 0.508)
		(layer "F.Cu")
		(net "P12V")
	)
	(segment
		(start 8.4963 -144.9832)
		(end 8.4963 -145.8722)
		(width 0.508)
		(layer "F.Cu")
		(net "P12V")
	)
	(segment
		(start 15.4432 -148.336)
		(end 16.1036 -147.6756)
		(width 0.508)
		(layer "F.Cu")
		(net "P12V")
	)
	(segment
		(start 17.4625 -184.7215)
		(end 17.4625 -185.42)
		(width 0.508)
		(layer "F.Cu")
		(net "P12V")
	)
	(segment
		(start 18.3515 -297.7261)
		(end 18.0594 -297.434)
		(width 0.508)
		(layer "F.Cu")
		(net "P12V")
	)
	(segment
		(start 14.8209 -148.336)
		(end 15.4432 -148.336)
		(width 0.508)
		(layer "F.Cu")
		(net "P12V")
	)
	(segment
		(start 12.064492 -62.153546)
		(end 12.064492 -62.889892)
		(width 0.508)
		(layer "F.Cu")
		(net "P12V")
	)
	(segment
		(start 8.8011 -452.374)
		(end 9.5631 -453.136)
		(width 0.508)
		(layer "F.Cu")
		(net "P12V")
	)
	(segment
		(start 19.2405 -260.4516)
		(end 19.2405 -259.334)
		(width 0.508)
		(layer "F.Cu")
		(net "P12V")
	)
	(segment
		(start 10.668 -453.2376)
		(end 9.7663 -454.1393)
		(width 0.508)
		(layer "F.Cu")
		(net "P12V")
	)
	(segment
		(start 4.0132 -431.5968)
		(end 4.0132 -432.7906)
		(width 0.508)
		(layer "F.Cu")
		(net "P12V")
	)
	(segment
		(start 4.0132 -432.7906)
		(end 3.5306 -433.2732)
		(width 0.508)
		(layer "F.Cu")
		(net "P12V")
	)
	(segment
		(start 19.2659 -257.6068)
		(end 18.6563 -256.9972)
		(width 0.508)
		(layer "F.Cu")
		(net "P12V")
	)
	(segment
		(start 17.119092 -17.158462)
		(end 16.256 -17.158462)
		(width 0.508)
		(layer "F.Cu")
		(net "P12V")
	)
	(segment
		(start 17.895316 -16.053816)
		(end 17.9705 -16.129)
		(width 0.508)
		(layer "F.Cu")
		(net "P12V")
	)
	(segment
		(start 18.833592 -124.828808)
		(end 20.828 -122.8344)
		(width 0.508)
		(layer "F.Cu")
		(net "P12V")
	)
	(segment
		(start 9.398 -146.7739)
		(end 8.4963 -145.8722)
		(width 0.508)
		(layer "F.Cu")
		(net "P12V")
	)
	(segment
		(start 15.4813 -146.9263)
		(end 16.1036 -147.5486)
		(width 0.508)
		(layer "F.Cu")
		(net "P12V")
	)
	(segment
		(start 43.0403 -134.0866)
		(end 43.3324 -134.3787)
		(width 0.508)
		(layer "F.Cu")
		(net "P12V")
	)
	(segment
		(start 19.2659 -259.3086)
		(end 19.2659 -257.6068)
		(width 0.508)
		(layer "F.Cu")
		(net "P12V")
	)
	(segment
		(start 19.2405 -260.4516)
		(end 19.2405 -261.6454)
		(width 0.508)
		(layer "F.Cu")
		(net "P12V")
	)
	(segment
		(start 9.5631 -453.136)
		(end 10.5664 -453.136)
		(width 0.508)
		(layer "F.Cu")
		(net "P12V")
	)
	(via
		(at 27.686 -19.431)
		(size 0.5588)
		(drill 0.3048)
		(layers "F.Cu" "B.Cu")
		(net "P12V")
	)
	(via
		(at 21.6408 -384.81)
		(size 0.7112)
		(drill 0.4064)
		(layers "F.Cu" "B.Cu")
		(net "P12V")
	)
	(via
		(at 11.811 -129.794)
		(size 0.5588)
		(drill 0.3048)
		(layers "F.Cu" "B.Cu")
		(net "P12V")
	)
	(via
		(at 27.178 -202.7428)
		(size 0.7112)
		(drill 0.4064)
		(layers "F.Cu" "B.Cu")
		(net "P12V")
	)
	(via
		(at 28.1432 -124.1044)
		(size 0.7112)
		(drill 0.4064)
		(layers "F.Cu" "B.Cu")
		(net "P12V")
	)
	(via
		(at 29.464 -400.304)
		(size 0.7112)
		(drill 0.4064)
		(layers "F.Cu" "B.Cu")
		(net "P12V")
	)
	(via
		(at 18.288 -130.7592)
		(size 0.7112)
		(drill 0.4064)
		(layers "F.Cu" "B.Cu")
		(net "P12V")
	)
	(via
		(at 23.876 -384.556)
		(size 0.7112)
		(drill 0.4064)
		(layers "F.Cu" "B.Cu")
		(net "P12V")
	)
	(via
		(at 2.667 -418.7952)
		(size 0.5588)
		(drill 0.3048)
		(layers "F.Cu" "B.Cu")
		(net "P12V")
	)
	(via
		(at 13.589 -385.826)
		(size 0.7112)
		(drill 0.4064)
		(layers "F.Cu" "B.Cu")
		(net "P12V")
	)
	(via
		(at 29.4386 -398.7038)
		(size 0.7112)
		(drill 0.4064)
		(layers "F.Cu" "B.Cu")
		(net "P12V")
	)
	(via
		(at 34.544 -390.144)
		(size 0.7112)
		(drill 0.4064)
		(layers "F.Cu" "B.Cu")
		(net "P12V")
	)
	(via
		(at 25.019 -18.542)
		(size 0.5588)
		(drill 0.3048)
		(layers "F.Cu" "B.Cu")
		(net "P12V")
	)
	(via
		(at 44.323 -383.413)
		(size 0.7112)
		(drill 0.4064)
		(layers "F.Cu" "B.Cu")
		(net "P12V")
	)
	(via
		(at 24.7015 -259.969)
		(size 0.7112)
		(drill 0.4064)
		(layers "F.Cu" "B.Cu")
		(net "P12V")
	)
	(via
		(at 29.21 -123.4694)
		(size 0.7112)
		(drill 0.3556)
		(layers "F.Cu" "B.Cu")
		(net "P12V")
	)
	(via
		(at 42.1894 -134.0866)
		(size 0.5588)
		(drill 0.3048)
		(layers "F.Cu" "B.Cu")
		(net "P12V")
	)
	(via
		(at 25.4 -123.952)
		(size 0.7112)
		(drill 0.4064)
		(layers "F.Cu" "B.Cu")
		(net "P12V")
	)
	(via
		(at 47.371 -126.492)
		(size 0.7112)
		(drill 0.4064)
		(layers "F.Cu" "B.Cu")
		(net "P12V")
	)
	(via
		(at 25.3492 -122.428)
		(size 0.7112)
		(drill 0.4064)
		(layers "F.Cu" "B.Cu")
		(net "P12V")
	)
	(via
		(at 28.1432 -127.1524)
		(size 0.7112)
		(drill 0.4064)
		(layers "F.Cu" "B.Cu")
		(net "P12V")
	)
	(via
		(at 17.895316 -15.247874)
		(size 0.5588)
		(drill 0.3048)
		(layers "F.Cu" "B.Cu")
		(net "P12V")
	)
	(via
		(at 12.319 -63.1444)
		(size 0.5588)
		(drill 0.3048)
		(layers "F.Cu" "B.Cu")
		(net "P12V")
	)
	(via
		(at 11.007598 -165.13683)
		(size 0.7112)
		(drill 0.3556)
		(layers "F.Cu" "B.Cu")
		(net "P12V")
	)
	(via
		(at 47.371 -128.524)
		(size 0.7112)
		(drill 0.4064)
		(layers "F.Cu" "B.Cu")
		(net "P12V")
	)
	(via
		(at 34.544 -394.97)
		(size 0.7112)
		(drill 0.4064)
		(layers "F.Cu" "B.Cu")
		(net "P12V")
	)
	(via
		(at 39.9034 -127)
		(size 0.7112)
		(drill 0.4064)
		(layers "F.Cu" "B.Cu")
		(net "P12V")
	)
	(via
		(at 28.321 -390.525)
		(size 0.7112)
		(drill 0.4064)
		(layers "F.Cu" "B.Cu")
		(net "P12V")
	)
	(via
		(at 25.4 -125.476)
		(size 0.7112)
		(drill 0.4064)
		(layers "F.Cu" "B.Cu")
		(net "P12V")
	)
	(via
		(at 51.076606 -132.969)
		(size 0.7112)
		(drill 0.4064)
		(layers "F.Cu" "B.Cu")
		(net "P12V")
	)
	(via
		(at 32.766 -393.446)
		(size 0.7112)
		(drill 0.4064)
		(layers "F.Cu" "B.Cu")
		(net "P12V")
	)
	(via
		(at 13.7922 -391.4648)
		(size 0.7112)
		(drill 0.4064)
		(layers "F.Cu" "B.Cu")
		(net "P12V")
	)
	(via
		(at 19.812 -130.7592)
		(size 0.7112)
		(drill 0.4064)
		(layers "F.Cu" "B.Cu")
		(net "P12V")
	)
	(via
		(at 28.1432 -125.6284)
		(size 0.7112)
		(drill 0.4064)
		(layers "F.Cu" "B.Cu")
		(net "P12V")
	)
	(via
		(at 30.988 -400.304)
		(size 0.7112)
		(drill 0.4064)
		(layers "F.Cu" "B.Cu")
		(net "P12V")
	)
	(via
		(at 25.4 -127)
		(size 0.7112)
		(drill 0.4064)
		(layers "F.Cu" "B.Cu")
		(net "P12V")
	)
	(via
		(at 30.988 -390.652)
		(size 0.7112)
		(drill 0.4064)
		(layers "F.Cu" "B.Cu")
		(net "P12V")
	)
	(via
		(at 14.859 -385.826)
		(size 0.7112)
		(drill 0.4064)
		(layers "F.Cu" "B.Cu")
		(net "P12V")
	)
	(via
		(at 9.930384 -171.428918)
		(size 0.7112)
		(drill 0.4064)
		(layers "F.Cu" "B.Cu")
		(net "P12V")
	)
	(via
		(at 18.2372 -128.7526)
		(size 0.7112)
		(drill 0.4064)
		(layers "F.Cu" "B.Cu")
		(net "P12V")
	)
	(via
		(at 43.18 -391.414)
		(size 0.7112)
		(drill 0.4064)
		(layers "F.Cu" "B.Cu")
		(net "P12V")
	)
	(via
		(at 27.813 -15.748)
		(size 0.5588)
		(drill 0.3048)
		(layers "F.Cu" "B.Cu")
		(net "P12V")
	)
	(via
		(at 29.845 -385.953)
		(size 0.7112)
		(drill 0.3556)
		(layers "F.Cu" "B.Cu")
		(net "P12V")
	)
	(via
		(at 36.576 -123.490228)
		(size 0.7112)
		(drill 0.4064)
		(layers "F.Cu" "B.Cu")
		(net "P12V")
	)
	(via
		(at 50.673 -124.3076)
		(size 0.7112)
		(drill 0.4064)
		(layers "F.Cu" "B.Cu")
		(net "P12V")
	)
	(via
		(at 28.956 -394.208)
		(size 0.7112)
		(drill 0.4064)
		(layers "F.Cu" "B.Cu")
		(net "P12V")
	)
	(via
		(at 39.37 -285.75)
		(size 0.7112)
		(drill 0.4064)
		(layers "F.Cu" "B.Cu")
		(net "P12V")
	)
	(via
		(at 19.939 -128.7018)
		(size 0.7112)
		(drill 0.4064)
		(layers "F.Cu" "B.Cu")
		(net "P12V")
	)
	(via
		(at 21.209 -273.431)
		(size 0.7112)
		(drill 0.4064)
		(layers "F.Cu" "B.Cu")
		(net "P12V")
	)
	(via
		(at 32.512 -398.272)
		(size 0.7112)
		(drill 0.4064)
		(layers "F.Cu" "B.Cu")
		(net "P12V")
	)
	(via
		(at 24.257 -184.912)
		(size 0.7112)
		(drill 0.3556)
		(layers "F.Cu" "B.Cu")
		(net "P12V")
	)
	(via
		(at 33.528 -480.568)
		(size 0.7112)
		(drill 0.4064)
		(layers "F.Cu" "B.Cu")
		(net "P12V")
	)
	(via
		(at 11.684 -124.587)
		(size 0.7112)
		(drill 0.4064)
		(layers "F.Cu" "B.Cu")
		(net "P12V")
	)
	(via
		(at 30.48 -129.413)
		(size 0.7112)
		(drill 0.4064)
		(layers "F.Cu" "B.Cu")
		(net "P12V")
	)
	(via
		(at 17.526 -184.6072)
		(size 0.5588)
		(drill 0.3048)
		(layers "F.Cu" "B.Cu")
		(net "P12V")
	)
	(via
		(at 18.0594 -297.434)
		(size 0.5588)
		(drill 0.3048)
		(layers "F.Cu" "B.Cu")
		(net "P12V")
	)
	(via
		(at 24.638 -286.385)
		(size 0.7112)
		(drill 0.4064)
		(layers "F.Cu" "B.Cu")
		(net "P12V")
	)
	(via
		(at 19.8628 -127.254)
		(size 0.7112)
		(drill 0.4064)
		(layers "F.Cu" "B.Cu")
		(net "P12V")
	)
	(via
		(at 30.48 -131.445)
		(size 0.7112)
		(drill 0.4064)
		(layers "F.Cu" "B.Cu")
		(net "P12V")
	)
	(via
		(at 37.592 -391.668)
		(size 0.7112)
		(drill 0.4064)
		(layers "F.Cu" "B.Cu")
		(net "P12V")
	)
	(via
		(at 23.241 -22.479)
		(size 0.5588)
		(drill 0.3048)
		(layers "F.Cu" "B.Cu")
		(net "P12V")
	)
	(via
		(at 32.766 -131.445)
		(size 0.7112)
		(drill 0.4064)
		(layers "F.Cu" "B.Cu")
		(net "P12V")
	)
	(via
		(at 27.148028 -201.727054)
		(size 0.7112)
		(drill 0.4064)
		(layers "F.Cu" "B.Cu")
		(net "P12V")
	)
	(via
		(at 34.671 -123.317)
		(size 0.7112)
		(drill 0.4064)
		(layers "F.Cu" "B.Cu")
		(net "P12V")
	)
	(via
		(at 21.209 -272.288)
		(size 0.7112)
		(drill 0.4064)
		(layers "F.Cu" "B.Cu")
		(net "P12V")
	)
	(via
		(at 35.524694 -479.923094)
		(size 0.7112)
		(drill 0.3556)
		(layers "F.Cu" "B.Cu")
		(net "P12V")
	)
	(via
		(at 8.0264 -260.1722)
		(size 0.7112)
		(drill 0.4064)
		(layers "F.Cu" "B.Cu")
		(net "P12V")
	)
	(via
		(at 20.828 -122.8344)
		(size 0.7112)
		(drill 0.4064)
		(layers "F.Cu" "B.Cu")
		(net "P12V")
	)
	(via
		(at 37.6682 -372.11)
		(size 0.7112)
		(drill 0.4064)
		(layers "F.Cu" "B.Cu")
		(net "P12V")
	)
	(via
		(at 32.766 -396.875)
		(size 0.7112)
		(drill 0.4064)
		(layers "F.Cu" "B.Cu")
		(net "P12V")
	)
	(via
		(at 10.5664 -443.7126)
		(size 0.7112)
		(drill 0.4064)
		(layers "F.Cu" "B.Cu")
		(net "P12V")
	)
	(via
		(at 26.924 -286.385)
		(size 0.7112)
		(drill 0.4064)
		(layers "F.Cu" "B.Cu")
		(net "P12V")
	)
	(via
		(at 30.226 -388.493)
		(size 0.7112)
		(drill 0.4064)
		(layers "F.Cu" "B.Cu")
		(net "P12V")
	)
	(via
		(at 37.592 -388.112)
		(size 0.7112)
		(drill 0.4064)
		(layers "F.Cu" "B.Cu")
		(net "P12V")
	)
	(via
		(at 31.623 -480.670362)
		(size 0.7112)
		(drill 0.4064)
		(layers "F.Cu" "B.Cu")
		(net "P12V")
	)
	(via
		(at 21.463 -130.6576)
		(size 0.7112)
		(drill 0.4064)
		(layers "F.Cu" "B.Cu")
		(net "P12V")
	)
	(via
		(at 21.59 -128.6256)
		(size 0.7112)
		(drill 0.4064)
		(layers "F.Cu" "B.Cu")
		(net "P12V")
	)
	(via
		(at 32.766 -389.89)
		(size 0.7112)
		(drill 0.4064)
		(layers "F.Cu" "B.Cu")
		(net "P12V")
	)
	(via
		(at 44.069 -128.524)
		(size 0.7112)
		(drill 0.4064)
		(layers "F.Cu" "B.Cu")
		(net "P12V")
	)
	(via
		(at 34.798 -129.54)
		(size 0.7112)
		(drill 0.4064)
		(layers "F.Cu" "B.Cu")
		(net "P12V")
	)
	(via
		(at 16.1036 -147.6756)
		(size 0.5588)
		(drill 0.3048)
		(layers "F.Cu" "B.Cu")
		(net "P12V")
	)
	(via
		(at 27.178 -203.8096)
		(size 0.7112)
		(drill 0.4064)
		(layers "F.Cu" "B.Cu")
		(net "P12V")
	)
	(via
		(at 16.256 -17.158462)
		(size 0.5588)
		(drill 0.3048)
		(layers "F.Cu" "B.Cu")
		(net "P12V")
	)
	(via
		(at 16.383 -13.462)
		(size 0.5588)
		(drill 0.3048)
		(layers "F.Cu" "B.Cu")
		(net "P12V")
	)
	(via
		(at 28.1432 -128.6764)
		(size 0.7112)
		(drill 0.4064)
		(layers "F.Cu" "B.Cu")
		(net "P12V")
	)
	(via
		(at 47.371 -131.826)
		(size 0.7112)
		(drill 0.4064)
		(layers "F.Cu" "B.Cu")
		(net "P12V")
	)
	(via
		(at 29.21 -19.431)
		(size 0.5588)
		(drill 0.3048)
		(layers "F.Cu" "B.Cu")
		(net "P12V")
	)
	(via
		(at 34.798 -127.381)
		(size 0.7112)
		(drill 0.4064)
		(layers "F.Cu" "B.Cu")
		(net "P12V")
	)
	(via
		(at 50.8762 -126.5174)
		(size 0.7112)
		(drill 0.4064)
		(layers "F.Cu" "B.Cu")
		(net "P12V")
	)
	(via
		(at 12.2936 -443.7126)
		(size 0.7112)
		(drill 0.4064)
		(layers "F.Cu" "B.Cu")
		(net "P12V")
	)
	(via
		(at 29.704792 -480.568)
		(size 0.7112)
		(drill 0.4064)
		(layers "F.Cu" "B.Cu")
		(net "P12V")
	)
	(via
		(at 25.4 -130.048)
		(size 0.7112)
		(drill 0.4064)
		(layers "F.Cu" "B.Cu")
		(net "P12V")
	)
	(via
		(at 20.1676 -132.5372)
		(size 0.7112)
		(drill 0.4064)
		(layers "F.Cu" "B.Cu")
		(net "P12V")
	)
	(via
		(at 23.876 -395.224)
		(size 0.7112)
		(drill 0.4064)
		(layers "F.Cu" "B.Cu")
		(net "P12V")
	)
	(via
		(at 32.766 -125.349)
		(size 0.7112)
		(drill 0.4064)
		(layers "F.Cu" "B.Cu")
		(net "P12V")
	)
	(via
		(at 32.766 -123.317)
		(size 0.7112)
		(drill 0.4064)
		(layers "F.Cu" "B.Cu")
		(net "P12V")
	)
	(via
		(at 25.4 -128.524)
		(size 0.7112)
		(drill 0.4064)
		(layers "F.Cu" "B.Cu")
		(net "P12V")
	)
	(via
		(at 24.765 -287.655)
		(size 0.7112)
		(drill 0.4064)
		(layers "F.Cu" "B.Cu")
		(net "P12V")
	)
	(via
		(at 37.592 -393.7)
		(size 0.7112)
		(drill 0.4064)
		(layers "F.Cu" "B.Cu")
		(net "P12V")
	)
	(via
		(at 39.37 -287.147)
		(size 0.7112)
		(drill 0.4064)
		(layers "F.Cu" "B.Cu")
		(net "P12V")
	)
	(via
		(at 23.241 -23.495)
		(size 0.5588)
		(drill 0.3048)
		(layers "F.Cu" "B.Cu")
		(net "P12V")
	)
	(via
		(at 23.876 -396.748)
		(size 0.7112)
		(drill 0.4064)
		(layers "F.Cu" "B.Cu")
		(net "P12V")
	)
	(via
		(at 42.392092 -398.043908)
		(size 0.7112)
		(drill 0.4064)
		(layers "F.Cu" "B.Cu")
		(net "P12V")
	)
	(via
		(at 34.798 -476.885)
		(size 0.7112)
		(drill 0.3556)
		(layers "F.Cu" "B.Cu")
		(net "P12V")
	)
	(via
		(at 8.4963 -145.8722)
		(size 0.5588)
		(drill 0.3048)
		(layers "F.Cu" "B.Cu")
		(net "P12V")
	)
	(via
		(at 43.053 -396.621)
		(size 0.7112)
		(drill 0.4064)
		(layers "F.Cu" "B.Cu")
		(net "P12V")
	)
	(via
		(at 44.196 -384.937)
		(size 0.7112)
		(drill 0.4064)
		(layers "F.Cu" "B.Cu")
		(net "P12V")
	)
	(via
		(at 28.956 -395.732)
		(size 0.7112)
		(drill 0.4064)
		(layers "F.Cu" "B.Cu")
		(net "P12V")
	)
	(via
		(at 30.988 -392.684)
		(size 0.7112)
		(drill 0.4064)
		(layers "F.Cu" "B.Cu")
		(net "P12V")
	)
	(via
		(at 43.18 -393.319)
		(size 0.7112)
		(drill 0.4064)
		(layers "F.Cu" "B.Cu")
		(net "P12V")
	)
	(via
		(at 25.273 -15.494)
		(size 0.5588)
		(drill 0.3048)
		(layers "F.Cu" "B.Cu")
		(net "P12V")
	)
	(via
		(at 25.908 -395.224)
		(size 0.7112)
		(drill 0.4064)
		(layers "F.Cu" "B.Cu")
		(net "P12V")
	)
	(via
		(at 10.16 -167.386)
		(size 0.7112)
		(drill 0.4064)
		(layers "F.Cu" "B.Cu")
		(net "P12V")
	)
	(via
		(at 50.7492 -128.524)
		(size 0.7112)
		(drill 0.4064)
		(layers "F.Cu" "B.Cu")
		(net "P12V")
	)
	(via
		(at 30.988 -397.256)
		(size 0.7112)
		(drill 0.4064)
		(layers "F.Cu" "B.Cu")
		(net "P12V")
	)
	(via
		(at 20.32 -389.0264)
		(size 0.7112)
		(drill 0.4064)
		(layers "F.Cu" "B.Cu")
		(net "P12V")
	)
	(via
		(at 28.1432 -130.2004)
		(size 0.7112)
		(drill 0.4064)
		(layers "F.Cu" "B.Cu")
		(net "P12V")
	)
	(via
		(at 23.876 -393.7)
		(size 0.7112)
		(drill 0.4064)
		(layers "F.Cu" "B.Cu")
		(net "P12V")
	)
	(via
		(at 48.768 -126.492)
		(size 0.7112)
		(drill 0.4064)
		(layers "F.Cu" "B.Cu")
		(net "P12V")
	)
	(via
		(at 23.622 -27.178)
		(size 0.5588)
		(drill 0.3048)
		(layers "F.Cu" "B.Cu")
		(net "P12V")
	)
	(via
		(at 24.257 -270.256)
		(size 0.7112)
		(drill 0.4064)
		(layers "F.Cu" "B.Cu")
		(net "P12V")
	)
	(via
		(at 43.18 -394.97)
		(size 0.7112)
		(drill 0.4064)
		(layers "F.Cu" "B.Cu")
		(net "P12V")
	)
	(via
		(at 36.576 -131.445)
		(size 0.7112)
		(drill 0.4064)
		(layers "F.Cu" "B.Cu")
		(net "P12V")
	)
	(via
		(at 23.876 -398.272)
		(size 0.7112)
		(drill 0.4064)
		(layers "F.Cu" "B.Cu")
		(net "P12V")
	)
	(via
		(at 30.988 -394.208)
		(size 0.7112)
		(drill 0.4064)
		(layers "F.Cu" "B.Cu")
		(net "P12V")
	)
	(via
		(at 16.764 -129.667)
		(size 0.7112)
		(drill 0.3556)
		(layers "F.Cu" "B.Cu")
		(net "P12V")
	)
	(via
		(at 14.605 -396.748)
		(size 0.7112)
		(drill 0.4064)
		(layers "F.Cu" "B.Cu")
		(net "P12V")
	)
	(via
		(at 34.798 -125.222)
		(size 0.7112)
		(drill 0.4064)
		(layers "F.Cu" "B.Cu")
		(net "P12V")
	)
	(via
		(at 48.768 -124.46)
		(size 0.7112)
		(drill 0.4064)
		(layers "F.Cu" "B.Cu")
		(net "P12V")
	)
	(via
		(at 29.337 -15.113)
		(size 0.5588)
		(drill 0.3048)
		(layers "F.Cu" "B.Cu")
		(net "P12V")
	)
	(via
		(at 22.098 -270.256)
		(size 0.7112)
		(drill 0.4064)
		(layers "F.Cu" "B.Cu")
		(net "P12V")
	)
	(via
		(at 38.1 -398.78)
		(size 0.7112)
		(drill 0.4064)
		(layers "F.Cu" "B.Cu")
		(net "P12V")
	)
	(via
		(at 32.766 -132.969)
		(size 0.7112)
		(drill 0.4064)
		(layers "F.Cu" "B.Cu")
		(net "P12V")
	)
	(via
		(at 44.4246 -132.9182)
		(size 0.7112)
		(drill 0.4064)
		(layers "F.Cu" "B.Cu")
		(net "P12V")
	)
	(via
		(at 25.908 -392.176)
		(size 0.7112)
		(drill 0.4064)
		(layers "F.Cu" "B.Cu")
		(net "P12V")
	)
	(via
		(at 15.113 -391.414)
		(size 0.7112)
		(drill 0.4064)
		(layers "F.Cu" "B.Cu")
		(net "P12V")
	)
	(via
		(at 39.2684 -147.701)
		(size 0.5588)
		(drill 0.3048)
		(layers "F.Cu" "B.Cu")
		(net "P12V")
	)
	(via
		(at 49.1744 -131.8514)
		(size 0.7112)
		(drill 0.4064)
		(layers "F.Cu" "B.Cu")
		(net "P12V")
	)
	(via
		(at 50.165 -122.301)
		(size 0.7112)
		(drill 0.3556)
		(layers "F.Cu" "B.Cu")
		(net "P12V")
	)
	(via
		(at 44.1198 -130.5306)
		(size 0.7112)
		(drill 0.4064)
		(layers "F.Cu" "B.Cu")
		(net "P12V")
	)
	(via
		(at 48.768 -128.524)
		(size 0.7112)
		(drill 0.4064)
		(layers "F.Cu" "B.Cu")
		(net "P12V")
	)
	(via
		(at 13.2334 -130.3274)
		(size 0.5588)
		(drill 0.3048)
		(layers "F.Cu" "B.Cu")
		(net "P12V")
	)
	(via
		(at 23.2156 -270.2814)
		(size 0.7112)
		(drill 0.4064)
		(layers "F.Cu" "B.Cu")
		(net "P12V")
	)
	(via
		(at 10.795 -64.5414)
		(size 0.5588)
		(drill 0.3048)
		(layers "F.Cu" "B.Cu")
		(net "P12V")
	)
	(via
		(at 18.3134 -132.5372)
		(size 0.7112)
		(drill 0.4064)
		(layers "F.Cu" "B.Cu")
		(net "P12V")
	)
	(via
		(at 32.766 -129.413)
		(size 0.7112)
		(drill 0.4064)
		(layers "F.Cu" "B.Cu")
		(net "P12V")
	)
	(via
		(at 9.8552 -450.85)
		(size 0.7112)
		(drill 0.4064)
		(layers "F.Cu" "B.Cu")
		(net "P12V")
	)
	(via
		(at 30.48 -132.969)
		(size 0.7112)
		(drill 0.4064)
		(layers "F.Cu" "B.Cu")
		(net "P12V")
	)
	(via
		(at 34.925 -131.445)
		(size 0.7112)
		(drill 0.4064)
		(layers "F.Cu" "B.Cu")
		(net "P12V")
	)
	(via
		(at 36.576 -129.413)
		(size 0.5588)
		(drill 0.3048)
		(layers "F.Cu" "B.Cu")
		(net "P12V")
	)
	(via
		(at 28.1432 -122.5804)
		(size 0.7112)
		(drill 0.4064)
		(layers "F.Cu" "B.Cu")
		(net "P12V")
	)
	(via
		(at 44.196 -386.588)
		(size 0.7112)
		(drill 0.4064)
		(layers "F.Cu" "B.Cu")
		(net "P12V")
	)
	(via
		(at 25.908 -396.748)
		(size 0.7112)
		(drill 0.4064)
		(layers "F.Cu" "B.Cu")
		(net "P12V")
	)
	(via
		(at 47.371 -130.429)
		(size 0.7112)
		(drill 0.4064)
		(layers "F.Cu" "B.Cu")
		(net "P12V")
	)
	(via
		(at 32.766 -391.795)
		(size 0.7112)
		(drill 0.4064)
		(layers "F.Cu" "B.Cu")
		(net "P12V")
	)
	(via
		(at 36.576 -127.381)
		(size 0.7112)
		(drill 0.4064)
		(layers "F.Cu" "B.Cu")
		(net "P12V")
	)
	(via
		(at 18.2626 -127.254)
		(size 0.7112)
		(drill 0.4064)
		(layers "F.Cu" "B.Cu")
		(net "P12V")
	)
	(via
		(at 12.7254 -125.222)
		(size 0.7112)
		(drill 0.4064)
		(layers "F.Cu" "B.Cu")
		(net "P12V")
	)
	(via
		(at 30.48 -123.317)
		(size 0.7112)
		(drill 0.4064)
		(layers "F.Cu" "B.Cu")
		(net "P12V")
	)
	(via
		(at 30.48 -127.381)
		(size 0.7112)
		(drill 0.4064)
		(layers "F.Cu" "B.Cu")
		(net "P12V")
	)
	(via
		(at 14.478 -398.399)
		(size 0.7112)
		(drill 0.4064)
		(layers "F.Cu" "B.Cu")
		(net "P12V")
	)
	(via
		(at 23.1775 -178.9938)
		(size 0.5588)
		(drill 0.3048)
		(layers "F.Cu" "B.Cu")
		(net "P12V")
	)
	(via
		(at 18.288 -384.556)
		(size 0.7112)
		(drill 0.4064)
		(layers "F.Cu" "B.Cu")
		(net "P12V")
	)
	(via
		(at 14.1478 -223.52)
		(size 0.5588)
		(drill 0.3048)
		(layers "F.Cu" "B.Cu")
		(net "P12V")
	)
	(via
		(at 18.7706 -390.1186)
		(size 0.7112)
		(drill 0.4064)
		(layers "F.Cu" "B.Cu")
		(net "P12V")
	)
	(via
		(at 22.733 -12.573)
		(size 0.5588)
		(drill 0.3048)
		(layers "F.Cu" "B.Cu")
		(net "P12V")
	)
	(via
		(at 30.988 -395.732)
		(size 0.7112)
		(drill 0.4064)
		(layers "F.Cu" "B.Cu")
		(net "P12V")
	)
	(via
		(at 30.48 -125.349)
		(size 0.7112)
		(drill 0.4064)
		(layers "F.Cu" "B.Cu")
		(net "P12V")
	)
	(via
		(at 24.638 -13.081)
		(size 0.5588)
		(drill 0.3048)
		(layers "F.Cu" "B.Cu")
		(net "P12V")
	)
	(via
		(at 51.1048 -131.8768)
		(size 0.7112)
		(drill 0.4064)
		(layers "F.Cu" "B.Cu")
		(net "P12V")
	)
	(via
		(at 21.209 -271.018)
		(size 0.7112)
		(drill 0.4064)
		(layers "F.Cu" "B.Cu")
		(net "P12V")
	)
	(via
		(at 13.1318 -132.715)
		(size 0.7112)
		(drill 0.4064)
		(layers "F.Cu" "B.Cu")
		(net "P12V")
	)
	(via
		(at 34.544 -388.112)
		(size 0.7112)
		(drill 0.4064)
		(layers "F.Cu" "B.Cu")
		(net "P12V")
	)
	(via
		(at 32.766 -127.381)
		(size 0.7112)
		(drill 0.4064)
		(layers "F.Cu" "B.Cu")
		(net "P12V")
	)
	(via
		(at 10.668 -453.2376)
		(size 0.7112)
		(drill 0.4064)
		(layers "F.Cu" "B.Cu")
		(net "P12V")
	)
	(via
		(at 20.851876 -282.575)
		(size 0.5588)
		(drill 0.3048)
		(layers "F.Cu" "B.Cu")
		(net "P12V")
	)
	(via
		(at 36.576 -125.349)
		(size 0.7112)
		(drill 0.4064)
		(layers "F.Cu" "B.Cu")
		(net "P12V")
	)
	(via
		(at 48.3108 -132.9436)
		(size 0.7112)
		(drill 0.4064)
		(layers "F.Cu" "B.Cu")
		(net "P12V")
	)
	(via
		(at 10.993374 -171.447714)
		(size 0.7112)
		(drill 0.4064)
		(layers "F.Cu" "B.Cu")
		(net "P12V")
	)
	(via
		(at 50.8254 -130.4544)
		(size 0.7112)
		(drill 0.4064)
		(layers "F.Cu" "B.Cu")
		(net "P12V")
	)
	(via
		(at 25.908 -393.7)
		(size 0.7112)
		(drill 0.4064)
		(layers "F.Cu" "B.Cu")
		(net "P12V")
	)
	(via
		(at 3.5306 -433.3748)
		(size 0.7112)
		(drill 0.4064)
		(layers "F.Cu" "B.Cu")
		(net "P12V")
	)
	(via
		(at 26.543 -25.654)
		(size 0.5588)
		(drill 0.3048)
		(layers "F.Cu" "B.Cu")
		(net "P12V")
	)
	(via
		(at 5.4864 -84.7852)
		(size 0.5588)
		(drill 0.3048)
		(layers "F.Cu" "B.Cu")
		(net "P12V")
	)
	(via
		(at 40.9956 -392.049)
		(size 0.7112)
		(drill 0.4064)
		(layers "F.Cu" "B.Cu")
		(net "P12V")
	)
	(via
		(at 10.795 -125.222)
		(size 0.7112)
		(drill 0.4064)
		(layers "F.Cu" "B.Cu")
		(net "P12V")
	)
	(via
		(at 23.114 -24.638)
		(size 0.5588)
		(drill 0.3048)
		(layers "F.Cu" "B.Cu")
		(net "P12V")
	)
	(via
		(at 39.37 -284.48)
		(size 0.7112)
		(drill 0.4064)
		(layers "F.Cu" "B.Cu")
		(net "P12V")
	)
	(via
		(at 42.799 -389.509)
		(size 0.7112)
		(drill 0.4064)
		(layers "F.Cu" "B.Cu")
		(net "P12V")
	)
	(via
		(at 24.892 -397.4338)
		(size 0.7112)
		(drill 0.3556)
		(layers "F.Cu" "B.Cu")
		(net "P12V")
	)
	(via
		(at 37.592 -395.732)
		(size 0.7112)
		(drill 0.4064)
		(layers "F.Cu" "B.Cu")
		(net "P12V")
	)
	(via
		(at 28.956 -397.256)
		(size 0.7112)
		(drill 0.4064)
		(layers "F.Cu" "B.Cu")
		(net "P12V")
	)
	(via
		(at 30.9372 -398.761966)
		(size 0.7112)
		(drill 0.4064)
		(layers "F.Cu" "B.Cu")
		(net "P12V")
	)
	(via
		(at 39.8272 -130.9116)
		(size 0.7112)
		(drill 0.4064)
		(layers "F.Cu" "B.Cu")
		(net "P12V")
	)
	(via
		(at 48.768 -130.429)
		(size 0.7112)
		(drill 0.4064)
		(layers "F.Cu" "B.Cu")
		(net "P12V")
	)
	(via
		(at 16.256 -249.047)
		(size 0.7112)
		(drill 0.4064)
		(layers "F.Cu" "B.Cu")
		(net "P12V")
	)
	(via
		(at 23.241 -261.747)
		(size 0.7112)
		(drill 0.3556)
		(layers "F.Cu" "B.Cu")
		(net "P12V")
	)
	(via
		(at 39.8272 -128.7526)
		(size 0.7112)
		(drill 0.4064)
		(layers "F.Cu" "B.Cu")
		(net "P12V")
	)
	(via
		(at 28.956 -392.684)
		(size 0.7112)
		(drill 0.4064)
		(layers "F.Cu" "B.Cu")
		(net "P12V")
	)
	(via
		(at 31.623 -387.096)
		(size 0.7112)
		(drill 0.4064)
		(layers "F.Cu" "B.Cu")
		(net "P12V")
	)
	(via
		(at 28.448 -25.654)
		(size 0.5588)
		(drill 0.3048)
		(layers "F.Cu" "B.Cu")
		(net "P12V")
	)
	(via
		(at 22.3266 -386.9436)
		(size 0.7112)
		(drill 0.4064)
		(layers "F.Cu" "B.Cu")
		(net "P12V")
	)
	(via
		(at 27.686 -205.613)
		(size 0.7112)
		(drill 0.3556)
		(layers "F.Cu" "B.Cu")
		(net "P12V")
	)
	(via
		(at 44.323 -381.889)
		(size 0.7112)
		(drill 0.4064)
		(layers "F.Cu" "B.Cu")
		(net "P12V")
	)
	(via
		(at 11.684 -131.064)
		(size 0.5588)
		(drill 0.3048)
		(layers "F.Cu" "B.Cu")
		(net "P12V")
	)
	(via
		(at 39.116 -397.256)
		(size 0.7112)
		(drill 0.4064)
		(layers "F.Cu" "B.Cu")
		(net "P12V")
	)
	(via
		(at 37.592 -397.256)
		(size 0.7112)
		(drill 0.4064)
		(layers "F.Cu" "B.Cu")
		(net "P12V")
	)
	(via
		(at 13.843 -399.796)
		(size 0.7112)
		(drill 0.4064)
		(layers "F.Cu" "B.Cu")
		(net "P12V")
	)
	(via
		(at 25.908 -398.272)
		(size 0.7112)
		(drill 0.4064)
		(layers "F.Cu" "B.Cu")
		(net "P12V")
	)
	(via
		(at 37.846 -132.715)
		(size 0.7112)
		(drill 0.3556)
		(layers "F.Cu" "B.Cu")
		(net "P12V")
	)
	(via
		(at 34.544 -391.668)
		(size 0.7112)
		(drill 0.4064)
		(layers "F.Cu" "B.Cu")
		(net "P12V")
	)
	(via
		(at 34.544 -393.192)
		(size 0.7112)
		(drill 0.4064)
		(layers "F.Cu" "B.Cu")
		(net "P12V")
	)
	(via
		(at 12.61491 -163.304982)
		(size 0.7112)
		(drill 0.3556)
		(layers "F.Cu" "B.Cu")
		(net "P12V")
	)
	(via
		(at 23.8506 -28.3972)
		(size 0.5588)
		(drill 0.3048)
		(layers "F.Cu" "B.Cu")
		(net "P12V")
	)
	(via
		(at 39.624 -398.78)
		(size 0.7112)
		(drill 0.4064)
		(layers "F.Cu" "B.Cu")
		(net "P12V")
	)
	(via
		(at 40.9702 -397.0274)
		(size 0.7112)
		(drill 0.4064)
		(layers "F.Cu" "B.Cu")
		(net "P12V")
	)
	(via
		(at 25.4 -131.8514)
		(size 0.7112)
		(drill 0.4064)
		(layers "F.Cu" "B.Cu")
		(net "P12V")
	)
	(via
		(at 34.544 -396.748)
		(size 0.7112)
		(drill 0.4064)
		(layers "F.Cu" "B.Cu")
		(net "P12V")
	)
	(via
		(at 23.622 -385.7498)
		(size 0.7112)
		(drill 0.4064)
		(layers "F.Cu" "B.Cu")
		(net "P12V")
	)
	(via
		(at 25.781 -286.385)
		(size 0.7112)
		(drill 0.4064)
		(layers "F.Cu" "B.Cu")
		(net "P12V")
	)
	(via
		(at 40.4495 -149.9235)
		(size 0.5588)
		(drill 0.3048)
		(layers "F.Cu" "B.Cu")
		(net "P12V")
	)
	(via
		(at 23.749 -25.781)
		(size 0.5588)
		(drill 0.3048)
		(layers "F.Cu" "B.Cu")
		(net "P12V")
	)
	(via
		(at 42.9768 -122.6312)
		(size 0.7112)
		(drill 0.4064)
		(layers "F.Cu" "B.Cu")
		(net "P12V")
	)
	(via
		(at 38.1 -400.304)
		(size 0.7112)
		(drill 0.4064)
		(layers "F.Cu" "B.Cu")
		(net "P12V")
	)
	(via
		(at 26.797 -185.928)
		(size 0.7112)
		(drill 0.3556)
		(layers "F.Cu" "B.Cu")
		(net "P12V")
	)
	(via
		(at 34.925 -132.969)
		(size 0.7112)
		(drill 0.4064)
		(layers "F.Cu" "B.Cu")
		(net "P12V")
	)
	(via
		(at 32.766 -395.097)
		(size 0.7112)
		(drill 0.4064)
		(layers "F.Cu" "B.Cu")
		(net "P12V")
	)
	(via
		(at 21.717 -256.413)
		(size 0.7112)
		(drill 0.3556)
		(layers "F.Cu" "B.Cu")
		(net "P12V")
	)
	(via
		(at 34.544 -398.272)
		(size 0.7112)
		(drill 0.4064)
		(layers "F.Cu" "B.Cu")
		(net "P12V")
	)
	(via
		(at 23.1902 -134.1628)
		(size 0.5588)
		(drill 0.3048)
		(layers "F.Cu" "B.Cu")
		(net "P12V")
	)
	(via
		(at 42.799 -387.604)
		(size 0.7112)
		(drill 0.4064)
		(layers "F.Cu" "B.Cu")
		(net "P12V")
	)
	(via
		(at 39.624 -400.304)
		(size 0.7112)
		(drill 0.4064)
		(layers "F.Cu" "B.Cu")
		(net "P12V")
	)
	(via
		(at 44.0944 -126.6952)
		(size 0.7112)
		(drill 0.4064)
		(layers "F.Cu" "B.Cu")
		(net "P12V")
	)
	(segment
		(start 42.9768 -124.4092)
		(end 42.1894 -125.1966)
		(width 0.508)
		(layer "B.Cu")
		(net "P12V")
	)
	(segment
		(start 23.622 -127.367792)
		(end 20.828 -124.573792)
		(width 0.508)
		(layer "B.Cu")
		(net "P12V")
	)
	(segment
		(start 23.1902 -134.162546)
		(end 23.622 -133.730746)
		(width 0.508)
		(layer "B.Cu")
		(net "P12V")
	)
	(segment
		(start 42.1894 -125.1966)
		(end 42.1894 -134.0866)
		(width 0.508)
		(layer "B.Cu")
		(net "P12V")
	)
	(segment
		(start 23.622 -133.730746)
		(end 23.622 -127.367792)
		(width 0.508)
		(layer "B.Cu")
		(net "P12V")
	)
	(segment
		(start 20.828 -124.573792)
		(end 20.828 -122.8344)
		(width 0.508)
		(layer "B.Cu")
		(net "P12V")
	)
	(segment
		(start 42.9768 -122.6312)
		(end 42.9768 -124.4092)
		(width 0.508)
		(layer "B.Cu")
		(net "P12V")
	)
	(segment
		(start 23.1902 -134.1628)
		(end 23.1902 -134.162546)
		(width 0.508)
		(layer "B.Cu")
		(net "P12V")
	)
	(segment
		(start 22.71649 -161.297366)
		(end 22.71649 -160.721548)
		(width 0.1397)
		(layer "F.Cu")
		(net "NCT7904_GND")
	)
	(segment
		(start 23.638002 -159.784034)
		(end 23.638002 -159.800036)
		(width 0.1397)
		(layer "F.Cu")
		(net "NCT7904_GND")
	)
	(segment
		(start 22.71649 -160.721548)
		(end 23.638002 -159.800036)
		(width 0.1397)
		(layer "F.Cu")
		(net "NCT7904_GND")
	)
	(segment
		(start 23.82266 -159.599376)
		(end 23.638002 -159.784034)
		(width 0.1397)
		(layer "F.Cu")
		(net "NCT7904_GND")
	)
	(segment
		(start 26.12009 -159.599376)
		(end 23.82266 -159.599376)
		(width 0.1397)
		(layer "F.Cu")
		(net "NCT7904_GND")
	)
	(via
		(at 23.638002 -159.800036)
		(size 0.7112)
		(drill 0.3556)
		(layers "F.Cu" "B.Cu")
		(net "NCT7904_GND")
	)
	(segment
		(start 28.405582 -373.295418)
		(end 28.405582 -372.965218)
		(width 0.254)
		(layer "F.Cu")
		(net "ADM1276_VCC")
	)
	(segment
		(start 27.11958 -374.58142)
		(end 27.11958 -376.08256)
		(width 0.254)
		(layer "F.Cu")
		(net "ADM1276_VCC")
	)
	(segment
		(start 27.11958 -376.08256)
		(end 27.11958 -377.44908)
		(width 0.254)
		(layer "F.Cu")
		(net "ADM1276_VCC")
	)
	(segment
		(start 28.405582 -373.320818)
		(end 28.405582 -373.295418)
		(width 0.254)
		(layer "F.Cu")
		(net "ADM1276_VCC")
	)
	(segment
		(start 27.2034 -374.523)
		(end 28.405582 -373.320818)
		(width 0.254)
		(layer "F.Cu")
		(net "ADM1276_VCC")
	)
	(segment
		(start 27.178 -374.523)
		(end 27.11958 -374.58142)
		(width 0.254)
		(layer "F.Cu")
		(net "ADM1276_VCC")
	)
	(segment
		(start 27.178 -374.523)
		(end 27.2034 -374.523)
		(width 0.254)
		(layer "F.Cu")
		(net "ADM1276_VCC")
	)
	(segment
		(start 27.11958 -377.44908)
		(end 27.305 -377.6345)
		(width 0.254)
		(layer "F.Cu")
		(net "ADM1276_VCC")
	)
	(segment
		(start 28.405582 -372.965218)
		(end 29.068014 -372.302786)
		(width 0.254)
		(layer "F.Cu")
		(net "ADM1276_VCC")
	)
	(segment
		(start 29.068014 -372.302786)
		(end 29.068014 -371.2464)
		(width 0.254)
		(layer "F.Cu")
		(net "ADM1276_VCC")
	)
	(via
		(at 28.405582 -373.295418)
		(size 0.7112)
		(drill 0.3556)
		(layers "F.Cu" "B.Cu")
		(net "ADM1276_VCC")
	)
	(segment
		(start 25.0952 -157.5054)
		(end 25.188926 -157.599126)
		(width 0.1397)
		(layer "F.Cu")
		(net "NCT7904_CASEOPEN")
	)
	(segment
		(start 25.292812 -153.820114)
		(end 25.292812 -153.865834)
		(width 0.1397)
		(layer "F.Cu")
		(net "NCT7904_CASEOPEN")
	)
	(segment
		(start 25.292812 -153.865834)
		(end 25.0952 -154.063446)
		(width 0.1397)
		(layer "F.Cu")
		(net "NCT7904_CASEOPEN")
	)
	(segment
		(start 25.097232 -153.624534)
		(end 25.292812 -153.820114)
		(width 0.1397)
		(layer "F.Cu")
		(net "NCT7904_CASEOPEN")
	)
	(segment
		(start 24.70531 -151.770334)
		(end 25.097232 -152.162256)
		(width 0.1397)
		(layer "F.Cu")
		(net "NCT7904_CASEOPEN")
	)
	(segment
		(start 25.188926 -157.599126)
		(end 26.12009 -157.599126)
		(width 0.1397)
		(layer "F.Cu")
		(net "NCT7904_CASEOPEN")
	)
	(segment
		(start 25.097232 -152.162256)
		(end 25.097232 -153.624534)
		(width 0.1397)
		(layer "F.Cu")
		(net "NCT7904_CASEOPEN")
	)
	(segment
		(start 25.0952 -154.063446)
		(end 25.0952 -157.5054)
		(width 0.1397)
		(layer "F.Cu")
		(net "NCT7904_CASEOPEN")
	)
	(via
		(at 25.292812 -153.865834)
		(size 0.7112)
		(drill 0.3556)
		(layers "F.Cu" "B.Cu")
		(net "NCT7904_CASEOPEN")
	)
	(segment
		(start 11.4935 -146.5453)
		(end 11.4554 -146.5834)
		(width 0.1397)
		(layer "F.Cu")
		(net "FANIN_10")
	)
	(segment
		(start 14.4272 -146.5453)
		(end 12.5984 -146.5453)
		(width 0.1397)
		(layer "F.Cu")
		(net "FANIN_10")
	)
	(segment
		(start 27.4828 -166.57955)
		(end 27.4828 -165.664642)
		(width 0.1397)
		(layer "F.Cu")
		(net "FANIN_10")
	)
	(segment
		(start 28.11145 -165.035992)
		(end 28.11145 -164.091366)
		(width 0.1397)
		(layer "F.Cu")
		(net "FANIN_10")
	)
	(segment
		(start 27.4828 -165.664642)
		(end 28.11145 -165.035992)
		(width 0.1397)
		(layer "F.Cu")
		(net "FANIN_10")
	)
	(segment
		(start 12.5984 -146.5453)
		(end 11.4935 -146.5453)
		(width 0.1397)
		(layer "F.Cu")
		(net "FANIN_10")
	)
	(via
		(at 14.4272 -146.5453)
		(size 0.7112)
		(drill 0.4064)
		(layers "F.Cu" "B.Cu")
		(net "FANIN_10")
	)
	(via
		(at 27.0256 -164.6682)
		(size 0.7112)
		(drill 0.3556)
		(layers "F.Cu" "B.Cu")
		(net "FANIN_10")
	)
	(via
		(at 27.4828 -166.57955)
		(size 0.7112)
		(drill 0.4064)
		(layers "F.Cu" "B.Cu")
		(net "FANIN_10")
	)
	(segment
		(start 27.4828 -166.57955)
		(end 27.4828 -165.1)
		(width 0.1397)
		(layer "B.Cu")
		(net "FANIN_10")
	)
	(segment
		(start 17.8562 -155.2448)
		(end 27.0256 -164.4142)
		(width 0.1397)
		(layer "B.Cu")
		(net "FANIN_10")
	)
	(segment
		(start 14.4272 -147.9804)
		(end 17.8562 -151.4094)
		(width 0.1397)
		(layer "B.Cu")
		(net "FANIN_10")
	)
	(segment
		(start 27.0256 -164.4142)
		(end 27.0256 -164.6682)
		(width 0.1397)
		(layer "B.Cu")
		(net "FANIN_10")
	)
	(segment
		(start 17.8562 -151.4094)
		(end 17.8562 -155.2448)
		(width 0.1397)
		(layer "B.Cu")
		(net "FANIN_10")
	)
	(segment
		(start 27.4828 -165.1)
		(end 27.051 -164.6682)
		(width 0.1397)
		(layer "B.Cu")
		(net "FANIN_10")
	)
	(segment
		(start 14.4272 -146.5453)
		(end 14.4272 -147.9804)
		(width 0.1397)
		(layer "B.Cu")
		(net "FANIN_10")
	)
	(segment
		(start 27.051 -164.6682)
		(end 27.0256 -164.6682)
		(width 0.1397)
		(layer "B.Cu")
		(net "FANIN_10")
	)
	(segment
		(start 18.5166 -151.4602)
		(end 19.558 -151.4602)
		(width 0.1397)
		(layer "F.Cu")
		(net "FANIN_9")
	)
	(segment
		(start 19.9136 -151.1046)
		(end 19.9136 -150.1267)
		(width 0.1397)
		(layer "F.Cu")
		(net "FANIN_9")
	)
	(segment
		(start 19.9009 -150.114)
		(end 19.9136 -150.1267)
		(width 0.1397)
		(layer "F.Cu")
		(net "FANIN_9")
	)
	(segment
		(start 28.6512 -165.753542)
		(end 29.11221 -165.292532)
		(width 0.1397)
		(layer "F.Cu")
		(net "FANIN_9")
	)
	(segment
		(start 28.6512 -165.989)
		(end 28.6512 -165.753542)
		(width 0.1397)
		(layer "F.Cu")
		(net "FANIN_9")
	)
	(segment
		(start 29.11221 -165.292532)
		(end 29.11221 -164.091366)
		(width 0.1397)
		(layer "F.Cu")
		(net "FANIN_9")
	)
	(segment
		(start 18.7198 -150.114)
		(end 19.9009 -150.114)
		(width 0.1397)
		(layer "F.Cu")
		(net "FANIN_9")
	)
	(segment
		(start 19.558 -151.4602)
		(end 19.9136 -151.1046)
		(width 0.1397)
		(layer "F.Cu")
		(net "FANIN_9")
	)
	(segment
		(start 18.415 -151.3586)
		(end 18.5166 -151.4602)
		(width 0.1397)
		(layer "F.Cu")
		(net "FANIN_9")
	)
	(via
		(at 28.6512 -165.989)
		(size 0.7112)
		(drill 0.4064)
		(layers "F.Cu" "B.Cu")
		(net "FANIN_9")
	)
	(via
		(at 18.415 -151.3586)
		(size 0.7112)
		(drill 0.4064)
		(layers "F.Cu" "B.Cu")
		(net "FANIN_9")
	)
	(via
		(at 21.0566 -157.6324)
		(size 0.7112)
		(drill 0.3556)
		(layers "F.Cu" "B.Cu")
		(net "FANIN_9")
	)
	(segment
		(start 21.0566 -157.6324)
		(end 20.9296 -157.6324)
		(width 0.1397)
		(layer "B.Cu")
		(net "FANIN_9")
	)
	(segment
		(start 21.0566 -157.6578)
		(end 21.0566 -157.6324)
		(width 0.1397)
		(layer "B.Cu")
		(net "FANIN_9")
	)
	(segment
		(start 18.5928 -151.5364)
		(end 18.415 -151.3586)
		(width 0.1397)
		(layer "B.Cu")
		(net "FANIN_9")
	)
	(segment
		(start 20.9296 -157.6324)
		(end 18.5928 -155.2956)
		(width 0.1397)
		(layer "B.Cu")
		(net "FANIN_9")
	)
	(segment
		(start 18.5928 -155.2956)
		(end 18.5928 -151.5364)
		(width 0.1397)
		(layer "B.Cu")
		(net "FANIN_9")
	)
	(segment
		(start 28.6512 -165.989)
		(end 28.6512 -165.2524)
		(width 0.1397)
		(layer "B.Cu")
		(net "FANIN_9")
	)
	(segment
		(start 28.6512 -165.2524)
		(end 21.0566 -157.6578)
		(width 0.1397)
		(layer "B.Cu")
		(net "FANIN_9")
	)
	(segment
		(start 45.81271 -164.038534)
		(end 45.81271 -164.24529)
		(width 0.1397)
		(layer "F.Cu")
		(net "OSC_TRI_S")
	)
	(segment
		(start 43.52798 -165.14318)
		(end 44.2214 -165.8366)
		(width 0.1397)
		(layer "F.Cu")
		(net "OSC_TRI_S")
	)
	(segment
		(start 45.81271 -164.24529)
		(end 44.2214 -165.8366)
		(width 0.1397)
		(layer "F.Cu")
		(net "OSC_TRI_S")
	)
	(segment
		(start 43.52798 -164.043106)
		(end 43.52798 -165.14318)
		(width 0.1397)
		(layer "F.Cu")
		(net "OSC_TRI_S")
	)
	(via
		(at 44.2214 -165.8366)
		(size 0.7112)
		(drill 0.3556)
		(layers "F.Cu" "B.Cu")
		(net "OSC_TRI_S")
	)
	(segment
		(start 25.5524 -170.3324)
		(end 24.1681 -170.3324)
		(width 0.1397)
		(layer "F.Cu")
		(net "PWM_EXP_2B")
	)
	(segment
		(start 16.408654 -36.96335)
		(end 18.891504 -39.4462)
		(width 0.1397)
		(layer "F.Cu")
		(net "PWM_EXP_2B")
	)
	(segment
		(start 18.891504 -39.4462)
		(end 19.1262 -39.4462)
		(width 0.1397)
		(layer "F.Cu")
		(net "PWM_EXP_2B")
	)
	(segment
		(start 24.1681 -170.3324)
		(end 24.0665 -170.434)
		(width 0.1397)
		(layer "F.Cu")
		(net "PWM_EXP_2B")
	)
	(segment
		(start 14.80185 -36.96335)
		(end 16.408654 -36.96335)
		(width 0.1397)
		(layer "F.Cu")
		(net "PWM_EXP_2B")
	)
	(segment
		(start 12.680696 -38.928294)
		(end 12.836906 -38.928294)
		(width 0.1397)
		(layer "F.Cu")
		(net "PWM_EXP_2B")
	)
	(segment
		(start 12.836906 -38.928294)
		(end 14.80185 -36.96335)
		(width 0.1397)
		(layer "F.Cu")
		(net "PWM_EXP_2B")
	)
	(segment
		(start 23.674324 -172.06341)
		(end 23.674324 -170.826176)
		(width 0.1397)
		(layer "F.Cu")
		(net "PWM_EXP_2B")
	)
	(segment
		(start 23.674324 -170.826176)
		(end 24.0665 -170.434)
		(width 0.1397)
		(layer "F.Cu")
		(net "PWM_EXP_2B")
	)
	(via
		(at 25.5524 -166.7764)
		(size 0.7112)
		(drill 0.3556)
		(layers "F.Cu" "B.Cu")
		(net "PWM_EXP_2B")
	)
	(via
		(at 19.1262 -39.4462)
		(size 0.5588)
		(drill 0.3048)
		(layers "F.Cu" "B.Cu")
		(net "PWM_EXP_2B")
	)
	(via
		(at 12.680696 -38.928294)
		(size 0.5588)
		(drill 0.3048)
		(layers "F.Cu" "B.Cu")
		(net "PWM_EXP_2B")
	)
	(via
		(at 25.5524 -170.3324)
		(size 0.7112)
		(drill 0.4064)
		(layers "F.Cu" "B.Cu")
		(net "PWM_EXP_2B")
	)
	(segment
		(start 11.01725 -51.78425)
		(end 12.03833 -52.80533)
		(width 0.1397)
		(layer "B.Cu")
		(net "PWM_EXP_2B")
	)
	(segment
		(start 12.680696 -38.928294)
		(end 12.680696 -42.259504)
		(width 0.1397)
		(layer "B.Cu")
		(net "PWM_EXP_2B")
	)
	(segment
		(start 8.800592 -109.8169)
		(end 8.800592 -112.0267)
		(width 0.1397)
		(layer "B.Cu")
		(net "PWM_EXP_2B")
	)
	(segment
		(start 8.800846 -112.026954)
		(end 8.800846 -112.229646)
		(width 0.1397)
		(layer "B.Cu")
		(net "PWM_EXP_2B")
	)
	(segment
		(start 11.01725 -47.80915)
		(end 11.01725 -51.78425)
		(width 0.1397)
		(layer "B.Cu")
		(net "PWM_EXP_2B")
	)
	(segment
		(start 26.035 -167.259)
		(end 26.035 -169.8498)
		(width 0.1397)
		(layer "B.Cu")
		(net "PWM_EXP_2B")
	)
	(segment
		(start 8.800846 -91.884754)
		(end 8.800846 -109.816646)
		(width 0.1397)
		(layer "B.Cu")
		(net "PWM_EXP_2B")
	)
	(segment
		(start 11.8999 -146.0881)
		(end 17.3736 -151.5618)
		(width 0.1397)
		(layer "B.Cu")
		(net "PWM_EXP_2B")
	)
	(segment
		(start 8.826246 -124.060458)
		(end 8.826246 -124.428504)
		(width 0.1397)
		(layer "B.Cu")
		(net "PWM_EXP_2B")
	)
	(segment
		(start 12.680696 -42.259504)
		(end 12.1412 -42.799)
		(width 0.1397)
		(layer "B.Cu")
		(net "PWM_EXP_2B")
	)
	(segment
		(start 29.2862 -44.704)
		(end 22.782022 -44.704)
		(width 0.1397)
		(layer "B.Cu")
		(net "PWM_EXP_2B")
	)
	(segment
		(start 21.4376 -43.295062)
		(end 20.881594 -42.739056)
		(width 0.1397)
		(layer "B.Cu")
		(net "PWM_EXP_2B")
	)
	(segment
		(start 9.2456 -67.8942)
		(end 9.2456 -91.44)
		(width 0.1397)
		(layer "B.Cu")
		(net "PWM_EXP_2B")
	)
	(segment
		(start 12.03833 -52.80533)
		(end 12.03833 -60.96)
		(width 0.1397)
		(layer "B.Cu")
		(net "PWM_EXP_2B")
	)
	(segment
		(start 36.502086 -51.919886)
		(end 29.2862 -44.704)
		(width 0.1397)
		(layer "B.Cu")
		(net "PWM_EXP_2B")
	)
	(segment
		(start 26.035 -169.8498)
		(end 25.5524 -170.3324)
		(width 0.1397)
		(layer "B.Cu")
		(net "PWM_EXP_2B")
	)
	(segment
		(start 9.8552 -67.2846)
		(end 9.2456 -67.8942)
		(width 0.1397)
		(layer "B.Cu")
		(net "PWM_EXP_2B")
	)
	(segment
		(start 8.800846 -112.229646)
		(end 10.070084 -113.498884)
		(width 0.1397)
		(layer "B.Cu")
		(net "PWM_EXP_2B")
	)
	(segment
		(start 17.3736 -155.4226)
		(end 25.5524 -163.6014)
		(width 0.1397)
		(layer "B.Cu")
		(net "PWM_EXP_2B")
	)
	(segment
		(start 20.817078 -42.739056)
		(end 19.1262 -41.048178)
		(width 0.1397)
		(layer "B.Cu")
		(net "PWM_EXP_2B")
	)
	(segment
		(start 19.1262 -41.048178)
		(end 19.1262 -39.4462)
		(width 0.1397)
		(layer "B.Cu")
		(net "PWM_EXP_2B")
	)
	(segment
		(start 8.800846 -109.816646)
		(end 8.800592 -109.8169)
		(width 0.1397)
		(layer "B.Cu")
		(net "PWM_EXP_2B")
	)
	(segment
		(start 11.8999 -136.5631)
		(end 11.8999 -146.0881)
		(width 0.1397)
		(layer "B.Cu")
		(net "PWM_EXP_2B")
	)
	(segment
		(start 10.070084 -122.079512)
		(end 8.825992 -123.323604)
		(width 0.1397)
		(layer "B.Cu")
		(net "PWM_EXP_2B")
	)
	(segment
		(start 12.03833 -60.96)
		(end 9.8552 -63.14313)
		(width 0.1397)
		(layer "B.Cu")
		(net "PWM_EXP_2B")
	)
	(segment
		(start 8.800592 -112.0267)
		(end 8.800846 -112.026954)
		(width 0.1397)
		(layer "B.Cu")
		(net "PWM_EXP_2B")
	)
	(segment
		(start 8.8265 -124.428758)
		(end 8.8265 -133.4897)
		(width 0.1397)
		(layer "B.Cu")
		(net "PWM_EXP_2B")
	)
	(segment
		(start 37.999924 -51.919886)
		(end 36.502086 -51.919886)
		(width 0.1397)
		(layer "B.Cu")
		(net "PWM_EXP_2B")
	)
	(segment
		(start 9.8552 -63.14313)
		(end 9.8552 -67.2846)
		(width 0.1397)
		(layer "B.Cu")
		(net "PWM_EXP_2B")
	)
	(segment
		(start 21.4376 -43.359578)
		(end 21.4376 -43.295062)
		(width 0.1397)
		(layer "B.Cu")
		(net "PWM_EXP_2B")
	)
	(segment
		(start 8.825992 -123.323604)
		(end 8.825992 -124.060204)
		(width 0.1397)
		(layer "B.Cu")
		(net "PWM_EXP_2B")
	)
	(segment
		(start 8.825992 -124.060204)
		(end 8.826246 -124.060458)
		(width 0.1397)
		(layer "B.Cu")
		(net "PWM_EXP_2B")
	)
	(segment
		(start 10.070084 -113.498884)
		(end 10.070084 -122.079512)
		(width 0.1397)
		(layer "B.Cu")
		(net "PWM_EXP_2B")
	)
	(segment
		(start 25.5524 -163.6014)
		(end 25.5524 -166.7764)
		(width 0.1397)
		(layer "B.Cu")
		(net "PWM_EXP_2B")
	)
	(segment
		(start 8.826246 -124.428504)
		(end 8.8265 -124.428758)
		(width 0.1397)
		(layer "B.Cu")
		(net "PWM_EXP_2B")
	)
	(segment
		(start 8.8265 -133.4897)
		(end 11.8999 -136.5631)
		(width 0.1397)
		(layer "B.Cu")
		(net "PWM_EXP_2B")
	)
	(segment
		(start 25.5524 -166.7764)
		(end 26.035 -167.259)
		(width 0.1397)
		(layer "B.Cu")
		(net "PWM_EXP_2B")
	)
	(segment
		(start 9.2456 -91.44)
		(end 8.800846 -91.884754)
		(width 0.1397)
		(layer "B.Cu")
		(net "PWM_EXP_2B")
	)
	(segment
		(start 17.3736 -151.5618)
		(end 17.3736 -155.4226)
		(width 0.1397)
		(layer "B.Cu")
		(net "PWM_EXP_2B")
	)
	(segment
		(start 12.1412 -46.6852)
		(end 11.01725 -47.80915)
		(width 0.1397)
		(layer "B.Cu")
		(net "PWM_EXP_2B")
	)
	(segment
		(start 20.881594 -42.739056)
		(end 20.817078 -42.739056)
		(width 0.1397)
		(layer "B.Cu")
		(net "PWM_EXP_2B")
	)
	(segment
		(start 12.1412 -42.799)
		(end 12.1412 -46.6852)
		(width 0.1397)
		(layer "B.Cu")
		(net "PWM_EXP_2B")
	)
	(segment
		(start 22.782022 -44.704)
		(end 21.4376 -43.359578)
		(width 0.1397)
		(layer "B.Cu")
		(net "PWM_EXP_2B")
	)
	(segment
		(start 30.658308 -175.475138)
		(end 31.645352 -175.475138)
		(width 0.1397)
		(layer "F.Cu")
		(net "PWM_EXP_2A")
	)
	(segment
		(start 28.779724 -175.87341)
		(end 30.260036 -175.87341)
		(width 0.1397)
		(layer "F.Cu")
		(net "PWM_EXP_2A")
	)
	(segment
		(start 31.645352 -175.475138)
		(end 31.980124 -175.80991)
		(width 0.1397)
		(layer "F.Cu")
		(net "PWM_EXP_2A")
	)
	(segment
		(start 30.260036 -175.87341)
		(end 30.658308 -175.475138)
		(width 0.1397)
		(layer "F.Cu")
		(net "PWM_EXP_2A")
	)
	(via
		(at 30.658308 -175.475138)
		(size 0.7112)
		(drill 0.4064)
		(layers "F.Cu" "B.Cu")
		(net "PWM_EXP_2A")
	)
	(segment
		(start 13.16355 -72.1614)
		(end 13.16355 -68.90385)
		(width 0.1397)
		(layer "B.Cu")
		(net "PWM_EXP_2A")
	)
	(segment
		(start 21.420836 -62.461394)
		(end 21.420836 -62.396878)
		(width 0.1397)
		(layer "B.Cu")
		(net "PWM_EXP_2A")
	)
	(segment
		(start 20.8534 -148.195792)
		(end 20.8534 -146.2532)
		(width 0.1397)
		(layer "B.Cu")
		(net "PWM_EXP_2A")
	)
	(segment
		(start 12.3698 -72.95515)
		(end 13.16355 -72.1614)
		(width 0.1397)
		(layer "B.Cu")
		(net "PWM_EXP_2A")
	)
	(segment
		(start 30.658308 -175.475138)
		(end 31.41345 -174.719996)
		(width 0.1397)
		(layer "B.Cu")
		(net "PWM_EXP_2A")
	)
	(segment
		(start 22.57425 -149.916642)
		(end 20.8534 -148.195792)
		(width 0.1397)
		(layer "B.Cu")
		(net "PWM_EXP_2A")
	)
	(segment
		(start 31.41345 -169.11955)
		(end 33.36925 -167.16375)
		(width 0.1397)
		(layer "B.Cu")
		(net "PWM_EXP_2A")
	)
	(segment
		(start 17.17675 -63.493396)
		(end 17.671796 -62.99835)
		(width 0.1397)
		(layer "B.Cu")
		(net "PWM_EXP_2A")
	)
	(segment
		(start 15.4559 -140.8557)
		(end 15.4559 -124.51715)
		(width 0.1397)
		(layer "B.Cu")
		(net "PWM_EXP_2A")
	)
	(segment
		(start 22.908514 -60.9092)
		(end 35.3822 -60.9092)
		(width 0.1397)
		(layer "B.Cu")
		(net "PWM_EXP_2A")
	)
	(segment
		(start 12.172696 -92.99575)
		(end 12.17295 -92.99575)
		(width 0.1397)
		(layer "B.Cu")
		(net "PWM_EXP_2A")
	)
	(segment
		(start 12.17295 -92.99575)
		(end 12.3698 -92.7989)
		(width 0.1397)
		(layer "B.Cu")
		(net "PWM_EXP_2A")
	)
	(segment
		(start 21.420836 -62.396878)
		(end 22.908514 -60.9092)
		(width 0.1397)
		(layer "B.Cu")
		(net "PWM_EXP_2A")
	)
	(segment
		(start 22.57425 -150.32355)
		(end 22.57425 -149.916642)
		(width 0.1397)
		(layer "B.Cu")
		(net "PWM_EXP_2A")
	)
	(segment
		(start 20.881594 -63.000636)
		(end 21.420836 -62.461394)
		(width 0.1397)
		(layer "B.Cu")
		(net "PWM_EXP_2A")
	)
	(segment
		(start 12.3698 -92.7989)
		(end 12.3698 -72.95515)
		(width 0.1397)
		(layer "B.Cu")
		(net "PWM_EXP_2A")
	)
	(segment
		(start 31.41345 -174.719996)
		(end 31.41345 -169.11955)
		(width 0.1397)
		(layer "B.Cu")
		(net "PWM_EXP_2A")
	)
	(segment
		(start 13.1953 -122.25655)
		(end 13.1953 -112.020604)
		(width 0.1397)
		(layer "B.Cu")
		(net "PWM_EXP_2A")
	)
	(segment
		(start 39.57701 -60.5028)
		(end 40.539924 -59.539886)
		(width 0.1397)
		(layer "B.Cu")
		(net "PWM_EXP_2A")
	)
	(segment
		(start 11.912346 -110.36935)
		(end 11.9126 -110.369096)
		(width 0.1397)
		(layer "B.Cu")
		(net "PWM_EXP_2A")
	)
	(segment
		(start 35.7886 -60.5028)
		(end 39.57701 -60.5028)
		(width 0.1397)
		(layer "B.Cu")
		(net "PWM_EXP_2A")
	)
	(segment
		(start 17.671796 -62.99835)
		(end 20.116292 -62.99835)
		(width 0.1397)
		(layer "B.Cu")
		(net "PWM_EXP_2A")
	)
	(segment
		(start 13.1953 -112.020604)
		(end 11.912346 -110.73765)
		(width 0.1397)
		(layer "B.Cu")
		(net "PWM_EXP_2A")
	)
	(segment
		(start 33.36925 -167.16375)
		(end 33.36925 -165.093142)
		(width 0.1397)
		(layer "B.Cu")
		(net "PWM_EXP_2A")
	)
	(segment
		(start 20.118578 -63.000636)
		(end 20.881594 -63.000636)
		(width 0.1397)
		(layer "B.Cu")
		(net "PWM_EXP_2A")
	)
	(segment
		(start 11.912346 -110.73765)
		(end 11.912346 -110.36935)
		(width 0.1397)
		(layer "B.Cu")
		(net "PWM_EXP_2A")
	)
	(segment
		(start 33.36925 -165.093142)
		(end 22.02307 -153.746962)
		(width 0.1397)
		(layer "B.Cu")
		(net "PWM_EXP_2A")
	)
	(segment
		(start 13.16355 -68.90385)
		(end 17.17675 -64.89065)
		(width 0.1397)
		(layer "B.Cu")
		(net "PWM_EXP_2A")
	)
	(segment
		(start 11.9126 -110.369096)
		(end 11.9126 -93.255846)
		(width 0.1397)
		(layer "B.Cu")
		(net "PWM_EXP_2A")
	)
	(segment
		(start 20.8534 -146.2532)
		(end 15.4559 -140.8557)
		(width 0.1397)
		(layer "B.Cu")
		(net "PWM_EXP_2A")
	)
	(segment
		(start 20.116292 -62.99835)
		(end 20.118578 -63.000636)
		(width 0.1397)
		(layer "B.Cu")
		(net "PWM_EXP_2A")
	)
	(segment
		(start 22.02307 -150.87473)
		(end 22.57425 -150.32355)
		(width 0.1397)
		(layer "B.Cu")
		(net "PWM_EXP_2A")
	)
	(segment
		(start 11.9126 -93.255846)
		(end 12.172696 -92.99575)
		(width 0.1397)
		(layer "B.Cu")
		(net "PWM_EXP_2A")
	)
	(segment
		(start 17.17675 -64.89065)
		(end 17.17675 -63.493396)
		(width 0.1397)
		(layer "B.Cu")
		(net "PWM_EXP_2A")
	)
	(segment
		(start 22.02307 -153.746962)
		(end 22.02307 -150.87473)
		(width 0.1397)
		(layer "B.Cu")
		(net "PWM_EXP_2A")
	)
	(segment
		(start 15.4559 -124.51715)
		(end 13.1953 -122.25655)
		(width 0.1397)
		(layer "B.Cu")
		(net "PWM_EXP_2A")
	)
	(segment
		(start 35.3822 -60.9092)
		(end 35.7886 -60.5028)
		(width 0.1397)
		(layer "B.Cu")
		(net "PWM_EXP_2A")
	)
	(segment
		(start 40.795956 -152.8572)
		(end 40.26789 -153.385266)
		(width 0.508)
		(layer "F.Cu")
		(net "P3V3")
	)
	(segment
		(start 19.714718 -175.152304)
		(end 19.17065 -175.152304)
		(width 0.508)
		(layer "F.Cu")
		(net "P3V3")
	)
	(segment
		(start 16.1544 -61.6585)
		(end 16.1925 -61.6585)
		(width 0.508)
		(layer "F.Cu")
		(net "P3V3")
	)
	(segment
		(start 33.2232 -249.3264)
		(end 33.2232 -250.3932)
		(width 0.254)
		(layer "F.Cu")
		(net "P3V3")
	)
	(segment
		(start 20.4851 -174.612046)
		(end 20.4851 -174.3456)
		(width 0.508)
		(layer "F.Cu")
		(net "P3V3")
	)
	(segment
		(start 45.83811 -161.282634)
		(end 43.566588 -161.282634)
		(width 0.508)
		(layer "F.Cu")
		(net "P3V3")
	)
	(segment
		(start 14.7955 -175.40224)
		(end 14.7955 -177.056542)
		(width 0.4064)
		(layer "F.Cu")
		(net "P3V3")
	)
	(segment
		(start 4.7117 -417.6522)
		(end 3.3782 -417.6522)
		(width 0.508)
		(layer "F.Cu")
		(net "P3V3")
	)
	(segment
		(start 9.2456 -172.212)
		(end 12.319 -172.212)
		(width 0.508)
		(layer "F.Cu")
		(net "P3V3")
	)
	(segment
		(start 24.765 -145.291048)
		(end 24.765 -147.7518)
		(width 0.508)
		(layer "F.Cu")
		(net "P3V3")
	)
	(segment
		(start 28.779724 -171.629324)
		(end 27.6098 -170.4594)
		(width 0.508)
		(layer "F.Cu")
		(net "P3V3")
	)
	(segment
		(start 36.480242 -168.178734)
		(end 34.99231 -168.178734)
		(width 0.508)
		(layer "F.Cu")
		(net "P3V3")
	)
	(segment
		(start 19.8374 -236.4486)
		(end 19.583654 -236.702346)
		(width 1.016)
		(layer "F.Cu")
		(net "P3V3")
	)
	(segment
		(start 36.969192 -170.1292)
		(end 36.969192 -168.713658)
		(width 0.508)
		(layer "F.Cu")
		(net "P3V3")
	)
	(segment
		(start 7.3406 -69.1642)
		(end 6.7183 -69.7865)
		(width 0.508)
		(layer "F.Cu")
		(net "P3V3")
	)
	(segment
		(start 39.116 -254.8255)
		(end 40.513 -253.4285)
		(width 0.508)
		(layer "F.Cu")
		(net "P3V3")
	)
	(segment
		(start 46.284134 -155.83789)
		(end 46.284134 -154.969972)
		(width 0.508)
		(layer "F.Cu")
		(net "P3V3")
	)
	(segment
		(start 24.765 -147.7518)
		(end 23.63851 -148.87829)
		(width 0.508)
		(layer "F.Cu")
		(net "P3V3")
	)
	(segment
		(start 32.103822 -143.253714)
		(end 26.802334 -143.253714)
		(width 0.508)
		(layer "F.Cu")
		(net "P3V3")
	)
	(segment
		(start 26.543 -234.696)
		(end 25.8572 -234.0102)
		(width 1.016)
		(layer "F.Cu")
		(net "P3V3")
	)
	(segment
		(start 20.4216 -235.868464)
		(end 19.841464 -236.4486)
		(width 1.016)
		(layer "F.Cu")
		(net "P3V3")
	)
	(segment
		(start 14.5796 -171.9199)
		(end 14.5796 -172.816266)
		(width 0.508)
		(layer "F.Cu")
		(net "P3V3")
	)
	(segment
		(start 19.940524 -175.37811)
		(end 19.940524 -175.156622)
		(width 0.508)
		(layer "F.Cu")
		(net "P3V3")
	)
	(segment
		(start 16.383 -296.0878)
		(end 22.1742 -296.0878)
		(width 1.016)
		(layer "F.Cu")
		(net "P3V3")
	)
	(segment
		(start 16.5608 -52.7939)
		(end 15.6464 -52.7939)
		(width 0.508)
		(layer "F.Cu")
		(net "P3V3")
	)
	(segment
		(start 15.9512 -60.071)
		(end 16.2306 -60.071)
		(width 0.508)
		(layer "F.Cu")
		(net "P3V3")
	)
	(segment
		(start 21.3233 -219.8878)
		(end 21.3233 -220.752416)
		(width 0.508)
		(layer "F.Cu")
		(net "P3V3")
	)
	(segment
		(start 26.802334 -143.253714)
		(end 24.765 -145.291048)
		(width 0.508)
		(layer "F.Cu")
		(net "P3V3")
	)
	(segment
		(start 36.5252 -254.8255)
		(end 37.5412 -254.8255)
		(width 0.508)
		(layer "F.Cu")
		(net "P3V3")
	)
	(segment
		(start 19.882612 -173.9392)
		(end 19.831812 -173.8884)
		(width 0.508)
		(layer "F.Cu")
		(net "P3V3")
	)
	(segment
		(start 46.531276 -164.847524)
		(end 41.2496 -170.1292)
		(width 0.508)
		(layer "F.Cu")
		(net "P3V3")
	)
	(segment
		(start 21.3233 -216.637616)
		(end 21.322284 -216.6366)
		(width 0.508)
		(layer "F.Cu")
		(net "P3V3")
	)
	(segment
		(start 20.0787 -173.9392)
		(end 19.882612 -173.9392)
		(width 0.508)
		(layer "F.Cu")
		(net "P3V3")
	)
	(segment
		(start 7.4422 -174.0154)
		(end 9.2456 -172.212)
		(width 0.508)
		(layer "F.Cu")
		(net "P3V3")
	)
	(segment
		(start 15.9385 -60.0837)
		(end 15.9512 -60.071)
		(width 0.508)
		(layer "F.Cu")
		(net "P3V3")
	)
	(segment
		(start 16.68145 -69.25945)
		(end 16.002 -68.58)
		(width 0.508)
		(layer "F.Cu")
		(net "P3V3")
	)
	(segment
		(start 15.9766 -71.12)
		(end 16.68145 -70.41515)
		(width 0.508)
		(layer "F.Cu")
		(net "P3V3")
	)
	(segment
		(start 32.385 -237.821724)
		(end 33.351724 -236.855)
		(width 0.508)
		(layer "F.Cu")
		(net "P3V3")
	)
	(segment
		(start 24.6761 -169.5958)
		(end 24.1808 -169.1005)
		(width 0.508)
		(layer "F.Cu")
		(net "P3V3")
	)
	(segment
		(start 9.939274 -176.242726)
		(end 10.77976 -175.40224)
		(width 0.4064)
		(layer "F.Cu")
		(net "P3V3")
	)
	(segment
		(start 19.304 -172.6438)
		(end 22.352 -169.5958)
		(width 0.508)
		(layer "F.Cu")
		(net "P3V3")
	)
	(segment
		(start 17.9324 -62.7634)
		(end 16.51 -61.341)
		(width 0.508)
		(layer "F.Cu")
		(net "P3V3")
	)
	(segment
		(start 32.131 -247.396)
		(end 32.131 -248.296684)
		(width 0.508)
		(layer "F.Cu")
		(net "P3V3")
	)
	(segment
		(start 39.1922 -150.3172)
		(end 37.2364 -150.3172)
		(width 0.508)
		(layer "F.Cu")
		(net "P3V3")
	)
	(segment
		(start 23.4442 -221.654116)
		(end 24.4983 -220.600016)
		(width 0.3556)
		(layer "F.Cu")
		(net "P3V3")
	)
	(segment
		(start 42.672 -248.285)
		(end 41.148508 -246.761508)
		(width 0.508)
		(layer "F.Cu")
		(net "P3V3")
	)
	(segment
		(start 38.608 -254.8001)
		(end 38.6334 -254.8255)
		(width 0.508)
		(layer "F.Cu")
		(net "P3V3")
	)
	(segment
		(start 7.3787 -81.6102)
		(end 6.5024 -81.6102)
		(width 0.508)
		(layer "F.Cu")
		(net "P3V3")
	)
	(segment
		(start 17.0942 -178.3588)
		(end 15.935706 -177.200306)
		(width 0.508)
		(layer "F.Cu")
		(net "P3V3")
	)
	(segment
		(start 45.81271 -163.149534)
		(end 46.131734 -163.149534)
		(width 0.508)
		(layer "F.Cu")
		(net "P3V3")
	)
	(segment
		(start 39.878 -240.2205)
		(end 41.3385 -240.2205)
		(width 0.508)
		(layer "F.Cu")
		(net "P3V3")
	)
	(segment
		(start 37.5412 -254.8255)
		(end 37.5666 -254.8001)
		(width 0.508)
		(layer "F.Cu")
		(net "P3V3")
	)
	(segment
		(start 36.969192 -168.713658)
		(end 36.933886 -168.678352)
		(width 0.508)
		(layer "F.Cu")
		(net "P3V3")
	)
	(segment
		(start 46.6598 -160.8582)
		(end 46.6598 -156.213556)
		(width 0.508)
		(layer "F.Cu")
		(net "P3V3")
	)
	(segment
		(start 17.2085 -68.0085)
		(end 17.272 -68.072)
		(width 0.508)
		(layer "F.Cu")
		(net "P3V3")
	)
	(segment
		(start 37.846 -240.2205)
		(end 38.862 -240.2205)
		(width 0.508)
		(layer "F.Cu")
		(net "P3V3")
	)
	(segment
		(start 21.322284 -214.4014)
		(end 21.322284 -215.519)
		(width 0.508)
		(layer "F.Cu")
		(net "P3V3")
	)
	(segment
		(start 19.151346 -175.133)
		(end 18.269966 -175.133)
		(width 0.508)
		(layer "F.Cu")
		(net "P3V3")
	)
	(segment
		(start 34.6964 -145.846292)
		(end 32.103822 -143.253714)
		(width 0.508)
		(layer "F.Cu")
		(net "P3V3")
	)
	(segment
		(start 14.605 -214.503)
		(end 14.7066 -214.4014)
		(width 0.508)
		(layer "F.Cu")
		(net "P3V3")
	)
	(segment
		(start 17.0942 -179.0954)
		(end 17.0942 -178.3588)
		(width 0.508)
		(layer "F.Cu")
		(net "P3V3")
	)
	(segment
		(start 11.40714 -58.8772)
		(end 14.2875 -58.8772)
		(width 0.508)
		(layer "F.Cu")
		(net "P3V3")
	)
	(segment
		(start 46.284134 -154.969972)
		(end 44.171362 -152.8572)
		(width 0.508)
		(layer "F.Cu")
		(net "P3V3")
	)
	(segment
		(start 30.904434 -237.821724)
		(end 32.385 -237.821724)
		(width 0.508)
		(layer "F.Cu")
		(net "P3V3")
	)
	(segment
		(start 25.8572 -234.0102)
		(end 22.2758 -234.0102)
		(width 1.016)
		(layer "F.Cu")
		(net "P3V3")
	)
	(segment
		(start 32.78251 -172.439076)
		(end 31.36011 -172.439076)
		(width 0.508)
		(layer "F.Cu")
		(net "P3V3")
	)
	(segment
		(start 22.2758 -234.0102)
		(end 20.4216 -235.8644)
		(width 1.016)
		(layer "F.Cu")
		(net "P3V3")
	)
	(segment
		(start 23.4442 -221.654116)
		(end 22.225 -221.654116)
		(width 0.508)
		(layer "F.Cu")
		(net "P3V3")
	)
	(segment
		(start 37.2364 -150.3172)
		(end 34.6964 -147.7772)
		(width 0.508)
		(layer "F.Cu")
		(net "P3V3")
	)
	(segment
		(start 16.2306 -60.071)
		(end 16.51 -59.7916)
		(width 0.508)
		(layer "F.Cu")
		(net "P3V3")
	)
	(segment
		(start 46.131734 -163.149534)
		(end 46.531276 -163.549076)
		(width 0.508)
		(layer "F.Cu")
		(net "P3V3")
	)
	(segment
		(start 32.78251 -172.439076)
		(end 34.659316 -172.439076)
		(width 0.508)
		(layer "F.Cu")
		(net "P3V3")
	)
	(segment
		(start 42.672 -241.554)
		(end 42.672 -248.285)
		(width 0.508)
		(layer "F.Cu")
		(net "P3V3")
	)
	(segment
		(start 44.171362 -152.8572)
		(end 40.795956 -152.8572)
		(width 0.508)
		(layer "F.Cu")
		(net "P3V3")
	)
	(segment
		(start 4.191 -429.9712)
		(end 5.1181 -429.9712)
		(width 0.508)
		(layer "F.Cu")
		(net "P3V3")
	)
	(segment
		(start 35.8902 -236.855)
		(end 36.83 -237.7948)
		(width 0.508)
		(layer "F.Cu")
		(net "P3V3")
	)
	(segment
		(start 8.3058 -65.2653)
		(end 7.1247 -65.2653)
		(width 0.508)
		(layer "F.Cu")
		(net "P3V3")
	)
	(segment
		(start 10.85088 -59.43346)
		(end 11.40714 -58.8772)
		(width 0.508)
		(layer "F.Cu")
		(net "P3V3")
	)
	(segment
		(start 22.1742 -296.0878)
		(end 22.606 -296.5196)
		(width 1.016)
		(layer "F.Cu")
		(net "P3V3")
	)
	(segment
		(start 9.9314 -280.924)
		(end 7.0485 -280.924)
		(width 0.508)
		(layer "F.Cu")
		(net "P3V3")
	)
	(segment
		(start 21.3233 -219.8878)
		(end 21.3233 -218.821)
		(width 0.508)
		(layer "F.Cu")
		(net "P3V3")
	)
	(segment
		(start 34.659316 -172.439076)
		(end 36.969192 -170.1292)
		(width 0.508)
		(layer "F.Cu")
		(net "P3V3")
	)
	(segment
		(start 14.5796 -172.816266)
		(end 14.40434 -172.991526)
		(width 0.508)
		(layer "F.Cu")
		(net "P3V3")
	)
	(segment
		(start 19.304 -173.482)
		(end 19.304 -172.6438)
		(width 0.508)
		(layer "F.Cu")
		(net "P3V3")
	)
	(segment
		(start 16.67129 -174.778924)
		(end 17.91589 -174.778924)
		(width 0.508)
		(layer "F.Cu")
		(net "P3V3")
	)
	(segment
		(start 18.269966 -175.133)
		(end 17.91589 -174.778924)
		(width 0.508)
		(layer "F.Cu")
		(net "P3V3")
	)
	(segment
		(start 34.85896 -249.3264)
		(end 34.88436 -249.3518)
		(width 0.3048)
		(layer "F.Cu")
		(net "P3V3")
	)
	(segment
		(start 39.878 -240.2205)
		(end 38.862 -240.2205)
		(width 0.508)
		(layer "F.Cu")
		(net "P3V3")
	)
	(segment
		(start 26.543 -236.9058)
		(end 26.543 -234.696)
		(width 1.016)
		(layer "F.Cu")
		(net "P3V3")
	)
	(segment
		(start 41.529 -253.4285)
		(end 40.513 -253.4285)
		(width 0.508)
		(layer "F.Cu")
		(net "P3V3")
	)
	(segment
		(start 15.494 -60.0837)
		(end 14.585696 -59.175396)
		(width 0.508)
		(layer "F.Cu")
		(net "P3V3")
	)
	(segment
		(start 19.940524 -175.156622)
		(end 20.4851 -174.612046)
		(width 0.508)
		(layer "F.Cu")
		(net "P3V3")
	)
	(segment
		(start 23.6855 -169.5958)
		(end 24.1808 -169.1005)
		(width 0.508)
		(layer "F.Cu")
		(net "P3V3")
	)
	(segment
		(start 27.2542 -250.444)
		(end 27.2542 -251.6632)
		(width 0.508)
		(layer "F.Cu")
		(net "P3V3")
	)
	(segment
		(start 36.933886 -168.678352)
		(end 36.933886 -168.632378)
		(width 0.508)
		(layer "F.Cu")
		(net "P3V3")
	)
	(segment
		(start 33.2232 -249.3264)
		(end 32.5628 -248.666)
		(width 0.508)
		(layer "F.Cu")
		(net "P3V3")
	)
	(segment
		(start 3.3782 -429.1584)
		(end 4.191 -429.9712)
		(width 0.508)
		(layer "F.Cu")
		(net "P3V3")
	)
	(segment
		(start 37.5666 -254.8001)
		(end 38.608 -254.8001)
		(width 0.508)
		(layer "F.Cu")
		(net "P3V3")
	)
	(segment
		(start 23.63851 -148.87829)
		(end 23.63851 -150.881334)
		(width 0.508)
		(layer "F.Cu")
		(net "P3V3")
	)
	(segment
		(start 19.841464 -236.4486)
		(end 19.8374 -236.4486)
		(width 1.016)
		(layer "F.Cu")
		(net "P3V3")
	)
	(segment
		(start 43.566588 -161.282634)
		(end 43.52798 -161.244026)
		(width 0.508)
		(layer "F.Cu")
		(net "P3V3")
	)
	(segment
		(start 18.3388 -179.1208)
		(end 17.0688 -179.1208)
		(width 0.508)
		(layer "F.Cu")
		(net "P3V3")
	)
	(segment
		(start 16.002 -68.0085)
		(end 17.2085 -68.0085)
		(width 0.508)
		(layer "F.Cu")
		(net "P3V3")
	)
	(segment
		(start 9.9822 -280.8732)
		(end 9.9314 -280.924)
		(width 0.508)
		(layer "F.Cu")
		(net "P3V3")
	)
	(segment
		(start 16.68145 -70.41515)
		(end 16.68145 -69.25945)
		(width 0.508)
		(layer "F.Cu")
		(net "P3V3")
	)
	(segment
		(start 32.5628 -248.666)
		(end 31.761684 -248.666)
		(width 0.508)
		(layer "F.Cu")
		(net "P3V3")
	)
	(segment
		(start 33.2232 -249.3264)
		(end 34.85896 -249.3264)
		(width 0.3048)
		(layer "F.Cu")
		(net "P3V3")
	)
	(segment
		(start 21.3233 -217.7288)
		(end 21.3233 -216.637616)
		(width 0.508)
		(layer "F.Cu")
		(net "P3V3")
	)
	(segment
		(start 21.3233 -220.752416)
		(end 22.225 -221.654116)
		(width 0.508)
		(layer "F.Cu")
		(net "P3V3")
	)
	(segment
		(start 46.235366 -161.282634)
		(end 46.6598 -160.8582)
		(width 0.508)
		(layer "F.Cu")
		(net "P3V3")
	)
	(segment
		(start 37.846 -240.2205)
		(end 36.83 -240.2205)
		(width 0.508)
		(layer "F.Cu")
		(net "P3V3")
	)
	(segment
		(start 15.9004 -62.4205)
		(end 15.9004 -61.9125)
		(width 0.508)
		(layer "F.Cu")
		(net "P3V3")
	)
	(segment
		(start 19.940524 -175.37811)
		(end 19.714718 -175.152304)
		(width 0.508)
		(layer "F.Cu")
		(net "P3V3")
	)
	(segment
		(start 26.2382 -169.5958)
		(end 24.6761 -169.5958)
		(width 0.508)
		(layer "F.Cu")
		(net "P3V3")
	)
	(segment
		(start 16.0274 -174.135034)
		(end 16.0274 -172.7708)
		(width 0.508)
		(layer "F.Cu")
		(net "P3V3")
	)
	(segment
		(start 10.922 -177.8)
		(end 9.939274 -176.817274)
		(width 0.4064)
		(layer "F.Cu")
		(net "P3V3")
	)
	(segment
		(start 17.9324 -63.627)
		(end 17.9324 -62.7634)
		(width 0.508)
		(layer "F.Cu")
		(net "P3V3")
	)
	(segment
		(start 14.052042 -177.8)
		(end 10.922 -177.8)
		(width 0.4064)
		(layer "F.Cu")
		(net "P3V3")
	)
	(segment
		(start 31.761684 -248.666)
		(end 31.67634 -248.751344)
		(width 0.508)
		(layer "F.Cu")
		(net "P3V3")
	)
	(segment
		(start 46.531276 -163.549076)
		(end 46.531276 -164.847524)
		(width 0.508)
		(layer "F.Cu")
		(net "P3V3")
	)
	(segment
		(start 27.2542 -251.6632)
		(end 28.448 -251.6632)
		(width 0.508)
		(layer "F.Cu")
		(net "P3V3")
	)
	(segment
		(start 20.4216 -235.8644)
		(end 20.4216 -235.868464)
		(width 1.016)
		(layer "F.Cu")
		(net "P3V3")
	)
	(segment
		(start 40.26789 -151.39289)
		(end 39.1922 -150.3172)
		(width 0.508)
		(layer "F.Cu")
		(net "P3V3")
	)
	(segment
		(start 46.6598 -156.213556)
		(end 46.284134 -155.83789)
		(width 0.508)
		(layer "F.Cu")
		(net "P3V3")
	)
	(segment
		(start 15.9004 -61.9125)
		(end 16.1544 -61.6585)
		(width 0.508)
		(layer "F.Cu")
		(net "P3V3")
	)
	(segment
		(start 28.448 -251.6632)
		(end 28.94584 -251.16536)
		(width 0.3556)
		(layer "F.Cu")
		(net "P3V3")
	)
	(segment
		(start 24.4983 -220.600016)
		(end 25.60955 -220.600016)
		(width 0.3556)
		(layer "F.Cu")
		(net "P3V3")
	)
	(segment
		(start 15.5956 -172.339)
		(end 15.5956 -171.9199)
		(width 0.508)
		(layer "F.Cu")
		(net "P3V3")
	)
	(segment
		(start 41.148508 -246.761508)
		(end 32.765492 -246.761508)
		(width 0.508)
		(layer "F.Cu")
		(net "P3V3")
	)
	(segment
		(start 16.98625 -173.000924)
		(end 16.98625 -174.463964)
		(width 0.3048)
		(layer "F.Cu")
		(net "P3V3")
	)
	(segment
		(start 6.1214 -174.0154)
		(end 7.3406 -174.0154)
		(width 0.508)
		(layer "F.Cu")
		(net "P3V3")
	)
	(segment
		(start 14.2875 -58.8772)
		(end 14.585696 -59.175396)
		(width 0.508)
		(layer "F.Cu")
		(net "P3V3")
	)
	(segment
		(start 16.0274 -172.7708)
		(end 15.5956 -172.339)
		(width 0.508)
		(layer "F.Cu")
		(net "P3V3")
	)
	(segment
		(start 16.1925 -61.6585)
		(end 16.51 -61.341)
		(width 0.508)
		(layer "F.Cu")
		(net "P3V3")
	)
	(segment
		(start 45.83811 -163.124134)
		(end 45.81271 -163.149534)
		(width 0.508)
		(layer "F.Cu")
		(net "P3V3")
	)
	(segment
		(start 15.494 -60.0837)
		(end 15.9385 -60.0837)
		(width 0.508)
		(layer "F.Cu")
		(net "P3V3")
	)
	(segment
		(start 33.2232 -250.3932)
		(end 32.9946 -250.6218)
		(width 0.254)
		(layer "F.Cu")
		(net "P3V3")
	)
	(segment
		(start 28.540456 -248.751344)
		(end 27.2542 -250.0376)
		(width 0.508)
		(layer "F.Cu")
		(net "P3V3")
	)
	(segment
		(start 19.583654 -236.702346)
		(end 10.414 -236.702346)
		(width 1.016)
		(layer "F.Cu")
		(net "P3V3")
	)
	(segment
		(start 42.672 -252.73)
		(end 41.9735 -253.4285)
		(width 0.508)
		(layer "F.Cu")
		(net "P3V3")
	)
	(segment
		(start 12.319 -172.212)
		(end 13.462 -171.069)
		(width 0.508)
		(layer "F.Cu")
		(net "P3V3")
	)
	(segment
		(start 6.5024 -81.6102)
		(end 6.477 -81.5848)
		(width 0.508)
		(layer "F.Cu")
		(net "P3V3")
	)
	(segment
		(start 21.322284 -215.519)
		(end 21.322284 -216.6366)
		(width 0.508)
		(layer "F.Cu")
		(net "P3V3")
	)
	(segment
		(start 27.1018 -170.4594)
		(end 26.2382 -169.5958)
		(width 0.508)
		(layer "F.Cu")
		(net "P3V3")
	)
	(segment
		(start 14.6685 -55.118)
		(end 13.8176 -55.118)
		(width 0.508)
		(layer "F.Cu")
		(net "P3V3")
	)
	(segment
		(start 19.831812 -173.8884)
		(end 19.7104 -173.8884)
		(width 0.508)
		(layer "F.Cu")
		(net "P3V3")
	)
	(segment
		(start 15.935706 -177.200306)
		(end 14.651736 -177.200306)
		(width 0.508)
		(layer "F.Cu")
		(net "P3V3")
	)
	(segment
		(start 14.5796 -171.9199)
		(end 15.5956 -171.9199)
		(width 0.508)
		(layer "F.Cu")
		(net "P3V3")
	)
	(segment
		(start 22.352 -169.5958)
		(end 23.6855 -169.5958)
		(width 0.508)
		(layer "F.Cu")
		(net "P3V3")
	)
	(segment
		(start 32.765492 -246.761508)
		(end 32.131 -247.396)
		(width 0.508)
		(layer "F.Cu")
		(net "P3V3")
	)
	(segment
		(start 42.672 -248.285)
		(end 42.672 -252.73)
		(width 0.508)
		(layer "F.Cu")
		(net "P3V3")
	)
	(segment
		(start 36.83 -237.7948)
		(end 36.83 -240.2205)
		(width 0.508)
		(layer "F.Cu")
		(net "P3V3")
	)
	(segment
		(start 31.36011 -172.439076)
		(end 30.984444 -172.06341)
		(width 0.508)
		(layer "F.Cu")
		(net "P3V3")
	)
	(segment
		(start 27.6098 -170.4594)
		(end 27.1018 -170.4594)
		(width 0.508)
		(layer "F.Cu")
		(net "P3V3")
	)
	(segment
		(start 17.0688 -179.1208)
		(end 17.0942 -179.0954)
		(width 0.508)
		(layer "F.Cu")
		(net "P3V3")
	)
	(segment
		(start 15.3289 -71.12)
		(end 15.9766 -71.12)
		(width 0.508)
		(layer "F.Cu")
		(net "P3V3")
	)
	(segment
		(start 10.77976 -175.40224)
		(end 10.8585 -175.40224)
		(width 0.4064)
		(layer "F.Cu")
		(net "P3V3")
	)
	(segment
		(start 16.98625 -174.463964)
		(end 16.67129 -174.778924)
		(width 0.3048)
		(layer "F.Cu")
		(net "P3V3")
	)
	(segment
		(start 33.351724 -236.855)
		(end 35.8902 -236.855)
		(width 0.508)
		(layer "F.Cu")
		(net "P3V3")
	)
	(segment
		(start 41.9735 -253.4285)
		(end 41.529 -253.4285)
		(width 0.508)
		(layer "F.Cu")
		(net "P3V3")
	)
	(segment
		(start 16.67129 -174.778924)
		(end 16.0274 -174.135034)
		(width 0.508)
		(layer "F.Cu")
		(net "P3V3")
	)
	(segment
		(start 9.939274 -176.817274)
		(end 9.939274 -176.242726)
		(width 0.4064)
		(layer "F.Cu")
		(net "P3V3")
	)
	(segment
		(start 41.2496 -170.1292)
		(end 36.969192 -170.1292)
		(width 0.508)
		(layer "F.Cu")
		(net "P3V3")
	)
	(segment
		(start 11.8491 -225.9076)
		(end 12.5984 -225.9076)
		(width 0.508)
		(layer "F.Cu")
		(net "P3V3")
	)
	(segment
		(start 28.779724 -172.06341)
		(end 28.779724 -171.629324)
		(width 0.508)
		(layer "F.Cu")
		(net "P3V3")
	)
	(segment
		(start 30.984444 -172.06341)
		(end 28.779724 -172.06341)
		(width 0.508)
		(layer "F.Cu")
		(net "P3V3")
	)
	(segment
		(start 28.94584 -251.16536)
		(end 28.94584 -250.2408)
		(width 0.3556)
		(layer "F.Cu")
		(net "P3V3")
	)
	(segment
		(start 38.6334 -254.8255)
		(end 39.116 -254.8255)
		(width 0.508)
		(layer "F.Cu")
		(net "P3V3")
	)
	(segment
		(start 34.6964 -147.7772)
		(end 34.6964 -145.846292)
		(width 0.508)
		(layer "F.Cu")
		(net "P3V3")
	)
	(segment
		(start 14.651736 -177.200306)
		(end 14.052042 -177.8)
		(width 0.4064)
		(layer "F.Cu")
		(net "P3V3")
	)
	(segment
		(start 20.4851 -174.3456)
		(end 20.0787 -173.9392)
		(width 0.508)
		(layer "F.Cu")
		(net "P3V3")
	)
	(segment
		(start 31.67634 -248.751344)
		(end 28.540456 -248.751344)
		(width 0.508)
		(layer "F.Cu")
		(net "P3V3")
	)
	(segment
		(start 32.131 -248.296684)
		(end 31.761684 -248.666)
		(width 0.508)
		(layer "F.Cu")
		(net "P3V3")
	)
	(segment
		(start 21.3233 -218.821)
		(end 21.3233 -217.7288)
		(width 0.508)
		(layer "F.Cu")
		(net "P3V3")
	)
	(segment
		(start 41.3385 -240.2205)
		(end 42.672 -241.554)
		(width 0.508)
		(layer "F.Cu")
		(net "P3V3")
	)
	(segment
		(start 45.83811 -161.282634)
		(end 45.83811 -163.124134)
		(width 0.508)
		(layer "F.Cu")
		(net "P3V3")
	)
	(segment
		(start 40.26789 -153.385266)
		(end 40.26789 -151.39289)
		(width 0.508)
		(layer "F.Cu")
		(net "P3V3")
	)
	(segment
		(start 8.3185 -69.1642)
		(end 7.3406 -69.1642)
		(width 0.508)
		(layer "F.Cu")
		(net "P3V3")
	)
	(segment
		(start 19.7104 -173.8884)
		(end 19.304 -173.482)
		(width 0.508)
		(layer "F.Cu")
		(net "P3V3")
	)
	(segment
		(start 14.7955 -177.056542)
		(end 14.651736 -177.200306)
		(width 0.4064)
		(layer "F.Cu")
		(net "P3V3")
	)
	(segment
		(start 14.7066 -214.4014)
		(end 21.322284 -214.4014)
		(width 0.508)
		(layer "F.Cu")
		(net "P3V3")
	)
	(segment
		(start 27.2542 -250.0376)
		(end 27.2542 -250.444)
		(width 0.508)
		(layer "F.Cu")
		(net "P3V3")
	)
	(segment
		(start 45.83811 -161.282634)
		(end 46.235366 -161.282634)
		(width 0.508)
		(layer "F.Cu")
		(net "P3V3")
	)
	(segment
		(start 7.3406 -174.0154)
		(end 7.4422 -174.0154)
		(width 0.508)
		(layer "F.Cu")
		(net "P3V3")
	)
	(segment
		(start 16.002 -68.58)
		(end 16.002 -68.0085)
		(width 0.508)
		(layer "F.Cu")
		(net "P3V3")
	)
	(segment
		(start 11.0236 -226.7331)
		(end 11.8491 -225.9076)
		(width 0.508)
		(layer "F.Cu")
		(net "P3V3")
	)
	(segment
		(start 19.17065 -175.152304)
		(end 19.151346 -175.133)
		(width 0.508)
		(layer "F.Cu")
		(net "P3V3")
	)
	(segment
		(start 36.933886 -168.632378)
		(end 36.480242 -168.178734)
		(width 0.508)
		(layer "F.Cu")
		(net "P3V3")
	)
	(via
		(at 13.462 -171.069)
		(size 0.5588)
		(drill 0.3048)
		(layers "F.Cu" "B.Cu")
		(net "P3V3")
	)
	(via
		(at 14.605 -214.503)
		(size 0.5588)
		(drill 0.3048)
		(layers "F.Cu" "B.Cu")
		(net "P3V3")
	)
	(via
		(at 12.5984 -225.9076)
		(size 0.5588)
		(drill 0.3048)
		(layers "F.Cu" "B.Cu")
		(net "P3V3")
	)
	(via
		(at 14.40434 -172.991526)
		(size 0.7112)
		(drill 0.4064)
		(layers "F.Cu" "B.Cu")
		(net "P3V3")
	)
	(via
		(at 14.585696 -59.175396)
		(size 0.5588)
		(drill 0.3048)
		(layers "F.Cu" "B.Cu")
		(net "P3V3")
	)
	(via
		(at 10.85088 -59.43346)
		(size 0.5588)
		(drill 0.3048)
		(layers "F.Cu" "B.Cu")
		(net "P3V3")
	)
	(via
		(at 3.3782 -429.1584)
		(size 0.5588)
		(drill 0.3048)
		(layers "F.Cu" "B.Cu")
		(net "P3V3")
	)
	(via
		(at 9.9822 -280.8732)
		(size 0.7112)
		(drill 0.4064)
		(layers "F.Cu" "B.Cu")
		(net "P3V3")
	)
	(via
		(at 13.208 -220.345)
		(size 0.7112)
		(drill 0.3556)
		(layers "F.Cu" "B.Cu")
		(net "P3V3")
	)
	(via
		(at 14.651736 -177.200306)
		(size 0.5588)
		(drill 0.3048)
		(layers "F.Cu" "B.Cu")
		(net "P3V3")
	)
	(via
		(at 16.51 -61.341)
		(size 0.5588)
		(drill 0.3048)
		(layers "F.Cu" "B.Cu")
		(net "P3V3")
	)
	(via
		(at 7.1247 -65.2653)
		(size 0.7112)
		(drill 0.4064)
		(layers "F.Cu" "B.Cu")
		(net "P3V3")
	)
	(via
		(at 16.383 -296.0878)
		(size 0.7112)
		(drill 0.4064)
		(layers "F.Cu" "B.Cu")
		(net "P3V3")
	)
	(via
		(at 3.3782 -417.6522)
		(size 0.5588)
		(drill 0.3048)
		(layers "F.Cu" "B.Cu")
		(net "P3V3")
	)
	(via
		(at 17.272 -68.072)
		(size 0.5588)
		(drill 0.3048)
		(layers "F.Cu" "B.Cu")
		(net "P3V3")
	)
	(via
		(at 6.477 -81.5848)
		(size 0.5588)
		(drill 0.3048)
		(layers "F.Cu" "B.Cu")
		(net "P3V3")
	)
	(via
		(at 16.51 -59.7916)
		(size 0.5588)
		(drill 0.3048)
		(layers "F.Cu" "B.Cu")
		(net "P3V3")
	)
	(via
		(at 22.606 -296.5196)
		(size 0.7112)
		(drill 0.4064)
		(layers "F.Cu" "B.Cu")
		(net "P3V3")
	)
	(via
		(at 16.5608 -52.7939)
		(size 0.5588)
		(drill 0.3048)
		(layers "F.Cu" "B.Cu")
		(net "P3V3")
	)
	(via
		(at 10.414 -236.702346)
		(size 0.7112)
		(drill 0.4064)
		(layers "F.Cu" "B.Cu")
		(net "P3V3")
	)
	(via
		(at 13.8176 -55.118)
		(size 0.5588)
		(drill 0.3048)
		(layers "F.Cu" "B.Cu")
		(net "P3V3")
	)
	(via
		(at 14.4272 -211.074)
		(size 0.7112)
		(drill 0.3556)
		(layers "F.Cu" "B.Cu")
		(net "P3V3")
	)
	(via
		(at 6.7183 -69.7865)
		(size 0.5588)
		(drill 0.3048)
		(layers "F.Cu" "B.Cu")
		(net "P3V3")
	)
	(via
		(at 17.9324 -63.627)
		(size 0.5588)
		(drill 0.3048)
		(layers "F.Cu" "B.Cu")
		(net "P3V3")
	)
	(via
		(at 26.797 -359.41)
		(size 0.7112)
		(drill 0.4064)
		(layers "F.Cu" "B.Cu")
		(net "P3V3")
	)
	(via
		(at 14.4272 -175.514)
		(size 0.7112)
		(drill 0.3556)
		(layers "F.Cu" "B.Cu")
		(net "P3V3")
	)
	(segment
		(start 6.9342 -69.5706)
		(end 6.7183 -69.7865)
		(width 0.508)
		(layer "B.Cu")
		(net "P3V3")
	)
	(segment
		(start 2.8702 -417.1442)
		(end 3.3782 -417.6522)
		(width 0.508)
		(layer "B.Cu")
		(net "P3V3")
	)
	(segment
		(start 16.1417 -52.7939)
		(end 13.8176 -55.118)
		(width 0.508)
		(layer "B.Cu")
		(net "P3V3")
	)
	(segment
		(start 6.477 -81.5848)
		(end 4.678934 -83.382866)
		(width 0.508)
		(layer "B.Cu")
		(net "P3V3")
	)
	(segment
		(start 10.58545 -236.530896)
		(end 10.414 -236.702346)
		(width 1.016)
		(layer "B.Cu")
		(net "P3V3")
	)
	(segment
		(start 17.8054 -67.5386)
		(end 17.272 -68.072)
		(width 0.508)
		(layer "B.Cu")
		(net "P3V3")
	)
	(segment
		(start 17.8054 -63.754)
		(end 17.8054 -67.5386)
		(width 0.508)
		(layer "B.Cu")
		(net "P3V3")
	)
	(segment
		(start 7.1374 -134.1374)
		(end 10.16 -137.16)
		(width 0.508)
		(layer "B.Cu")
		(net "P3V3")
	)
	(segment
		(start 12.5984 -229.475792)
		(end 10.58545 -231.488742)
		(width 1.016)
		(layer "B.Cu")
		(net "P3V3")
	)
	(segment
		(start 14.40434 -175.49114)
		(end 14.40434 -172.991526)
		(width 1.016)
		(layer "B.Cu")
		(net "P3V3")
	)
	(segment
		(start 14.4272 -175.514)
		(end 14.40434 -175.49114)
		(width 1.016)
		(layer "B.Cu")
		(net "P3V3")
	)
	(segment
		(start 24.8666 -317.351664)
		(end 24.8666 -298.7802)
		(width 1.016)
		(layer "B.Cu")
		(net "P3V3")
	)
	(segment
		(start 6.698996 -69.805804)
		(end 6.698742 -69.805804)
		(width 0.508)
		(layer "B.Cu")
		(net "P3V3")
	)
	(segment
		(start 17.9324 -63.627)
		(end 17.8054 -63.754)
		(width 0.508)
		(layer "B.Cu")
		(net "P3V3")
	)
	(segment
		(start 9.9822 -280.8732)
		(end 10.5156 -281.4066)
		(width 1.016)
		(layer "B.Cu")
		(net "P3V3")
	)
	(segment
		(start 14.585696 -55.886096)
		(end 13.8176 -55.118)
		(width 0.508)
		(layer "B.Cu")
		(net "P3V3")
	)
	(segment
		(start 26.8732 -319.358264)
		(end 24.8666 -317.351664)
		(width 1.016)
		(layer "B.Cu")
		(net "P3V3")
	)
	(segment
		(start 24.8666 -298.7802)
		(end 22.606 -296.5196)
		(width 1.016)
		(layer "B.Cu")
		(net "P3V3")
	)
	(segment
		(start 10.58545 -280.26995)
		(end 10.58545 -236.873796)
		(width 1.016)
		(layer "B.Cu")
		(net "P3V3")
	)
	(segment
		(start 16.5608 -52.7939)
		(end 16.1417 -52.7939)
		(width 0.508)
		(layer "B.Cu")
		(net "P3V3")
	)
	(segment
		(start 14.605 -214.503)
		(end 13.208 -215.9)
		(width 1.016)
		(layer "B.Cu")
		(net "P3V3")
	)
	(segment
		(start 13.462 -172.049186)
		(end 14.40434 -172.991526)
		(width 0.508)
		(layer "B.Cu")
		(net "P3V3")
	)
	(segment
		(start 7.1374 -121.3612)
		(end 7.1374 -134.1374)
		(width 0.508)
		(layer "B.Cu")
		(net "P3V3")
	)
	(segment
		(start 10.58545 -231.488742)
		(end 10.58545 -236.530896)
		(width 1.016)
		(layer "B.Cu")
		(net "P3V3")
	)
	(segment
		(start 6.698742 -69.805804)
		(end 6.0706 -70.433946)
		(width 0.508)
		(layer "B.Cu")
		(net "P3V3")
	)
	(segment
		(start 16.2306 -296.2402)
		(end 16.2306 -336.8294)
		(width 0.508)
		(layer "B.Cu")
		(net "P3V3")
	)
	(segment
		(start 6.0706 -81.1784)
		(end 6.477 -81.5848)
		(width 0.508)
		(layer "B.Cu")
		(net "P3V3")
	)
	(segment
		(start 7.1247 -65.2653)
		(end 6.9342 -65.4558)
		(width 0.508)
		(layer "B.Cu")
		(net "P3V3")
	)
	(segment
		(start 12.5984 -224.4598)
		(end 12.5984 -225.9076)
		(width 1.016)
		(layer "B.Cu")
		(net "P3V3")
	)
	(segment
		(start 4.678934 -113.777014)
		(end 4.204716 -114.251232)
		(width 0.508)
		(layer "B.Cu")
		(net "P3V3")
	)
	(segment
		(start 26.8732 -359.3338)
		(end 26.8732 -319.358264)
		(width 1.016)
		(layer "B.Cu")
		(net "P3V3")
	)
	(segment
		(start 10.5156 -281.4066)
		(end 10.5156 -285.4706)
		(width 1.016)
		(layer "B.Cu")
		(net "P3V3")
	)
	(segment
		(start 4.204716 -118.428516)
		(end 7.1374 -121.3612)
		(width 0.508)
		(layer "B.Cu")
		(net "P3V3")
	)
	(segment
		(start 3.3782 -417.6522)
		(end 3.3782 -429.1584)
		(width 0.508)
		(layer "B.Cu")
		(net "P3V3")
	)
	(segment
		(start 6.9342 -65.4558)
		(end 6.9342 -69.5706)
		(width 0.508)
		(layer "B.Cu")
		(net "P3V3")
	)
	(segment
		(start 4.678934 -83.382866)
		(end 4.678934 -113.777014)
		(width 0.508)
		(layer "B.Cu")
		(net "P3V3")
	)
	(segment
		(start 2.8702 -378.8156)
		(end 2.8702 -417.1442)
		(width 0.508)
		(layer "B.Cu")
		(net "P3V3")
	)
	(segment
		(start 10.58545 -236.873796)
		(end 10.414 -236.702346)
		(width 1.016)
		(layer "B.Cu")
		(net "P3V3")
	)
	(segment
		(start 10.16 -147.066)
		(end 13.462 -150.368)
		(width 0.508)
		(layer "B.Cu")
		(net "P3V3")
	)
	(segment
		(start 10.5156 -285.4706)
		(end 15.621 -290.576)
		(width 1.016)
		(layer "B.Cu")
		(net "P3V3")
	)
	(segment
		(start 10.16 -137.16)
		(end 10.16 -147.066)
		(width 0.508)
		(layer "B.Cu")
		(net "P3V3")
	)
	(segment
		(start 14.4272 -214.3252)
		(end 14.605 -214.503)
		(width 1.016)
		(layer "B.Cu")
		(net "P3V3")
	)
	(segment
		(start 10.85088 -59.43346)
		(end 7.1247 -63.15964)
		(width 0.508)
		(layer "B.Cu")
		(net "P3V3")
	)
	(segment
		(start 4.204716 -114.251232)
		(end 4.204716 -118.428516)
		(width 0.508)
		(layer "B.Cu")
		(net "P3V3")
	)
	(segment
		(start 15.621 -290.576)
		(end 15.621 -295.3258)
		(width 1.016)
		(layer "B.Cu")
		(net "P3V3")
	)
	(segment
		(start 13.462 -171.069)
		(end 13.462 -172.049186)
		(width 0.508)
		(layer "B.Cu")
		(net "P3V3")
	)
	(segment
		(start 2.342134 -378.287534)
		(end 2.8702 -378.8156)
		(width 0.508)
		(layer "B.Cu")
		(net "P3V3")
	)
	(segment
		(start 16.2306 -336.8294)
		(end 2.342134 -350.717866)
		(width 0.508)
		(layer "B.Cu")
		(net "P3V3")
	)
	(segment
		(start 7.1247 -63.15964)
		(end 7.1247 -65.2653)
		(width 0.508)
		(layer "B.Cu")
		(net "P3V3")
	)
	(segment
		(start 12.5984 -225.9076)
		(end 12.5984 -229.475792)
		(width 1.016)
		(layer "B.Cu")
		(net "P3V3")
	)
	(segment
		(start 14.4272 -177.424842)
		(end 14.651736 -177.200306)
		(width 1.016)
		(layer "B.Cu")
		(net "P3V3")
	)
	(segment
		(start 13.462 -150.368)
		(end 13.462 -171.069)
		(width 0.508)
		(layer "B.Cu")
		(net "P3V3")
	)
	(segment
		(start 14.585696 -59.175396)
		(end 14.585696 -55.886096)
		(width 0.508)
		(layer "B.Cu")
		(net "P3V3")
	)
	(segment
		(start 15.621 -295.3258)
		(end 16.383 -296.0878)
		(width 1.016)
		(layer "B.Cu")
		(net "P3V3")
	)
	(segment
		(start 14.4272 -211.074)
		(end 14.4272 -214.3252)
		(width 1.016)
		(layer "B.Cu")
		(net "P3V3")
	)
	(segment
		(start 6.0706 -70.433946)
		(end 6.0706 -81.1784)
		(width 0.508)
		(layer "B.Cu")
		(net "P3V3")
	)
	(segment
		(start 13.208 -215.9)
		(end 13.208 -220.345)
		(width 1.016)
		(layer "B.Cu")
		(net "P3V3")
	)
	(segment
		(start 16.51 -61.341)
		(end 16.51 -59.7916)
		(width 0.508)
		(layer "B.Cu")
		(net "P3V3")
	)
	(segment
		(start 2.342134 -350.717866)
		(end 2.342134 -378.287534)
		(width 0.508)
		(layer "B.Cu")
		(net "P3V3")
	)
	(segment
		(start 26.797 -359.41)
		(end 26.8732 -359.3338)
		(width 1.016)
		(layer "B.Cu")
		(net "P3V3")
	)
	(segment
		(start 6.7183 -69.7865)
		(end 6.698996 -69.805804)
		(width 0.508)
		(layer "B.Cu")
		(net "P3V3")
	)
	(segment
		(start 13.208 -223.8502)
		(end 12.5984 -224.4598)
		(width 1.016)
		(layer "B.Cu")
		(net "P3V3")
	)
	(segment
		(start 13.208 -220.345)
		(end 13.208 -223.8502)
		(width 1.016)
		(layer "B.Cu")
		(net "P3V3")
	)
	(segment
		(start 14.651736 -175.738536)
		(end 14.651736 -177.200306)
		(width 1.016)
		(layer "B.Cu")
		(net "P3V3")
	)
	(segment
		(start 14.4272 -211.074)
		(end 14.4272 -177.424842)
		(width 1.016)
		(layer "B.Cu")
		(net "P3V3")
	)
	(segment
		(start 16.383 -296.0878)
		(end 16.2306 -296.2402)
		(width 0.508)
		(layer "B.Cu")
		(net "P3V3")
	)
	(segment
		(start 14.4272 -175.514)
		(end 14.651736 -175.738536)
		(width 1.016)
		(layer "B.Cu")
		(net "P3V3")
	)
	(segment
		(start 9.9822 -280.8732)
		(end 10.58545 -280.26995)
		(width 1.016)
		(layer "B.Cu")
		(net "P3V3")
	)
	(segment
		(start 30.348682 -174.500032)
		(end 30.372304 -174.500032)
		(width 0.1397)
		(layer "F.Cu")
		(net "PWM_EXP_1B")
	)
	(segment
		(start 31.686246 -174.500032)
		(end 31.954724 -174.76851)
		(width 0.1397)
		(layer "F.Cu")
		(net "PWM_EXP_1B")
	)
	(segment
		(start 28.779724 -174.60341)
		(end 30.245304 -174.60341)
		(width 0.1397)
		(layer "F.Cu")
		(net "PWM_EXP_1B")
	)
	(segment
		(start 30.372304 -174.500032)
		(end 31.686246 -174.500032)
		(width 0.1397)
		(layer "F.Cu")
		(net "PWM_EXP_1B")
	)
	(segment
		(start 30.245304 -174.60341)
		(end 30.348682 -174.500032)
		(width 0.1397)
		(layer "F.Cu")
		(net "PWM_EXP_1B")
	)
	(via
		(at 30.372304 -174.500032)
		(size 0.7112)
		(drill 0.4064)
		(layers "F.Cu" "B.Cu")
		(net "PWM_EXP_1B")
	)
	(segment
		(start 12.3063 -122.62485)
		(end 12.3063 -112.389158)
		(width 0.1397)
		(layer "B.Cu")
		(net "PWM_EXP_1B")
	)
	(segment
		(start 11.4808 -92.430092)
		(end 11.4808 -72.091296)
		(width 0.1397)
		(layer "B.Cu")
		(net "PWM_EXP_1B")
	)
	(segment
		(start 11.023346 -109.460792)
		(end 11.0236 -109.460538)
		(width 0.1397)
		(layer "B.Cu")
		(net "PWM_EXP_1B")
	)
	(segment
		(start 11.023092 -111.10595)
		(end 11.023092 -110.73765)
		(width 0.1397)
		(layer "B.Cu")
		(net "PWM_EXP_1B")
	)
	(segment
		(start 17.13865 -54.984142)
		(end 20.202906 -51.919886)
		(width 0.1397)
		(layer "B.Cu")
		(net "PWM_EXP_1B")
	)
	(segment
		(start 11.023346 -110.737396)
		(end 11.023346 -109.460792)
		(width 0.1397)
		(layer "B.Cu")
		(net "PWM_EXP_1B")
	)
	(segment
		(start 11.4808 -72.091296)
		(end 12.274296 -71.2978)
		(width 0.1397)
		(layer "B.Cu")
		(net "PWM_EXP_1B")
	)
	(segment
		(start 17.13865 -61.638688)
		(end 17.13865 -54.984142)
		(width 0.1397)
		(layer "B.Cu")
		(net "PWM_EXP_1B")
	)
	(segment
		(start 11.0236 -92.887292)
		(end 11.4808 -92.430092)
		(width 0.1397)
		(layer "B.Cu")
		(net "PWM_EXP_1B")
	)
	(segment
		(start 12.274296 -71.2978)
		(end 12.274296 -67.481704)
		(width 0.1397)
		(layer "B.Cu")
		(net "PWM_EXP_1B")
	)
	(segment
		(start 12.274296 -67.481704)
		(end 14.4526 -65.3034)
		(width 0.1397)
		(layer "B.Cu")
		(net "PWM_EXP_1B")
	)
	(segment
		(start 16.8656 -144.8816)
		(end 14.5669 -142.5829)
		(width 0.1397)
		(layer "B.Cu")
		(net "PWM_EXP_1B")
	)
	(segment
		(start 32.48025 -166.78275)
		(end 32.48025 -165.461442)
		(width 0.1397)
		(layer "B.Cu")
		(net "PWM_EXP_1B")
	)
	(segment
		(start 14.5669 -124.88545)
		(end 12.3063 -122.62485)
		(width 0.1397)
		(layer "B.Cu")
		(net "PWM_EXP_1B")
	)
	(segment
		(start 14.4526 -65.3034)
		(end 14.4526 -64.324738)
		(width 0.1397)
		(layer "B.Cu")
		(net "PWM_EXP_1B")
	)
	(segment
		(start 30.372304 -174.500032)
		(end 29.67355 -173.801278)
		(width 0.1397)
		(layer "B.Cu")
		(net "PWM_EXP_1B")
	)
	(segment
		(start 11.023092 -110.73765)
		(end 11.023346 -110.737396)
		(width 0.1397)
		(layer "B.Cu")
		(net "PWM_EXP_1B")
	)
	(segment
		(start 20.8788 -153.859992)
		(end 20.8788 -150.3934)
		(width 0.1397)
		(layer "B.Cu")
		(net "PWM_EXP_1B")
	)
	(segment
		(start 29.67355 -169.58945)
		(end 32.48025 -166.78275)
		(width 0.1397)
		(layer "B.Cu")
		(net "PWM_EXP_1B")
	)
	(segment
		(start 14.5669 -142.5829)
		(end 14.5669 -124.88545)
		(width 0.1397)
		(layer "B.Cu")
		(net "PWM_EXP_1B")
	)
	(segment
		(start 32.48025 -165.461442)
		(end 20.8788 -153.859992)
		(width 0.1397)
		(layer "B.Cu")
		(net "PWM_EXP_1B")
	)
	(segment
		(start 16.8656 -146.3802)
		(end 16.8656 -144.8816)
		(width 0.1397)
		(layer "B.Cu")
		(net "PWM_EXP_1B")
	)
	(segment
		(start 20.8788 -150.3934)
		(end 16.8656 -146.3802)
		(width 0.1397)
		(layer "B.Cu")
		(net "PWM_EXP_1B")
	)
	(segment
		(start 29.67355 -173.801278)
		(end 29.67355 -169.58945)
		(width 0.1397)
		(layer "B.Cu")
		(net "PWM_EXP_1B")
	)
	(segment
		(start 20.202906 -51.919886)
		(end 20.500086 -51.919886)
		(width 0.1397)
		(layer "B.Cu")
		(net "PWM_EXP_1B")
	)
	(segment
		(start 11.0236 -109.460538)
		(end 11.0236 -92.887292)
		(width 0.1397)
		(layer "B.Cu")
		(net "PWM_EXP_1B")
	)
	(segment
		(start 14.4526 -64.324738)
		(end 17.13865 -61.638688)
		(width 0.1397)
		(layer "B.Cu")
		(net "PWM_EXP_1B")
	)
	(segment
		(start 12.3063 -112.389158)
		(end 11.023092 -111.10595)
		(width 0.1397)
		(layer "B.Cu")
		(net "PWM_EXP_1B")
	)
	(segment
		(start 28.779724 -173.33341)
		(end 30.58541 -173.33341)
		(width 0.1397)
		(layer "F.Cu")
		(net "PWM_EXP_1A")
	)
	(segment
		(start 31.912814 -173.609)
		(end 31.954724 -173.65091)
		(width 0.1397)
		(layer "F.Cu")
		(net "PWM_EXP_1A")
	)
	(segment
		(start 30.58541 -173.33341)
		(end 30.861 -173.609)
		(width 0.1397)
		(layer "F.Cu")
		(net "PWM_EXP_1A")
	)
	(segment
		(start 30.861 -173.609)
		(end 31.912814 -173.609)
		(width 0.1397)
		(layer "F.Cu")
		(net "PWM_EXP_1A")
	)
	(via
		(at 30.861 -173.609)
		(size 0.7112)
		(drill 0.4064)
		(layers "F.Cu" "B.Cu")
		(net "PWM_EXP_1A")
	)
	(segment
		(start 21.3614 -150.241)
		(end 21.3614 -153.713942)
		(width 0.1397)
		(layer "B.Cu")
		(net "PWM_EXP_1A")
	)
	(segment
		(start 12.7508 -112.204754)
		(end 12.7508 -122.4407)
		(width 0.1397)
		(layer "B.Cu")
		(net "PWM_EXP_1A")
	)
	(segment
		(start 11.4681 -109.644688)
		(end 11.467846 -109.644942)
		(width 0.1397)
		(layer "B.Cu")
		(net "PWM_EXP_1A")
	)
	(segment
		(start 21.3614 -153.713942)
		(end 32.92475 -165.277292)
		(width 0.1397)
		(layer "B.Cu")
		(net "PWM_EXP_1A")
	)
	(segment
		(start 16.731996 -64.706754)
		(end 12.718796 -68.719954)
		(width 0.1397)
		(layer "B.Cu")
		(net "PWM_EXP_1A")
	)
	(segment
		(start 20.3962 -148.068792)
		(end 20.3962 -149.2758)
		(width 0.1397)
		(layer "B.Cu")
		(net "PWM_EXP_1A")
	)
	(segment
		(start 11.72845 -92.811346)
		(end 11.728196 -92.811346)
		(width 0.1397)
		(layer "B.Cu")
		(net "PWM_EXP_1A")
	)
	(segment
		(start 18.901664 -60.905136)
		(end 16.731996 -63.074804)
		(width 0.1397)
		(layer "B.Cu")
		(net "PWM_EXP_1A")
	)
	(segment
		(start 12.718796 -71.7296)
		(end 11.9253 -72.523096)
		(width 0.1397)
		(layer "B.Cu")
		(net "PWM_EXP_1A")
	)
	(segment
		(start 18.28165 -145.617946)
		(end 18.28165 -145.954242)
		(width 0.1397)
		(layer "B.Cu")
		(net "PWM_EXP_1A")
	)
	(segment
		(start 11.467846 -110.9218)
		(end 12.7508 -112.204754)
		(width 0.1397)
		(layer "B.Cu")
		(net "PWM_EXP_1A")
	)
	(segment
		(start 32.92475 -166.97325)
		(end 30.861 -169.037)
		(width 0.1397)
		(layer "B.Cu")
		(net "PWM_EXP_1A")
	)
	(segment
		(start 18.28165 -145.954242)
		(end 20.3962 -148.068792)
		(width 0.1397)
		(layer "B.Cu")
		(net "PWM_EXP_1A")
	)
	(segment
		(start 11.9253 -72.523096)
		(end 11.9253 -92.614496)
		(width 0.1397)
		(layer "B.Cu")
		(net "PWM_EXP_1A")
	)
	(segment
		(start 11.728196 -92.811346)
		(end 11.4681 -93.071442)
		(width 0.1397)
		(layer "B.Cu")
		(net "PWM_EXP_1A")
	)
	(segment
		(start 15.0114 -142.347696)
		(end 18.28165 -145.617946)
		(width 0.1397)
		(layer "B.Cu")
		(net "PWM_EXP_1A")
	)
	(segment
		(start 32.92475 -165.277292)
		(end 32.92475 -166.97325)
		(width 0.1397)
		(layer "B.Cu")
		(net "PWM_EXP_1A")
	)
	(segment
		(start 11.9253 -92.614496)
		(end 11.72845 -92.811346)
		(width 0.1397)
		(layer "B.Cu")
		(net "PWM_EXP_1A")
	)
	(segment
		(start 21.674836 -60.905136)
		(end 18.901664 -60.905136)
		(width 0.1397)
		(layer "B.Cu")
		(net "PWM_EXP_1A")
	)
	(segment
		(start 15.0114 -124.7013)
		(end 15.0114 -142.347696)
		(width 0.1397)
		(layer "B.Cu")
		(net "PWM_EXP_1A")
	)
	(segment
		(start 23.040086 -59.539886)
		(end 21.674836 -60.905136)
		(width 0.1397)
		(layer "B.Cu")
		(net "PWM_EXP_1A")
	)
	(segment
		(start 12.7508 -122.4407)
		(end 15.0114 -124.7013)
		(width 0.1397)
		(layer "B.Cu")
		(net "PWM_EXP_1A")
	)
	(segment
		(start 11.467846 -109.644942)
		(end 11.467846 -110.9218)
		(width 0.1397)
		(layer "B.Cu")
		(net "PWM_EXP_1A")
	)
	(segment
		(start 30.861 -169.037)
		(end 30.861 -173.609)
		(width 0.1397)
		(layer "B.Cu")
		(net "PWM_EXP_1A")
	)
	(segment
		(start 16.731996 -63.074804)
		(end 16.731996 -64.706754)
		(width 0.1397)
		(layer "B.Cu")
		(net "PWM_EXP_1A")
	)
	(segment
		(start 11.4681 -93.071442)
		(end 11.4681 -109.644688)
		(width 0.1397)
		(layer "B.Cu")
		(net "PWM_EXP_1A")
	)
	(segment
		(start 12.718796 -68.719954)
		(end 12.718796 -71.7296)
		(width 0.1397)
		(layer "B.Cu")
		(net "PWM_EXP_1A")
	)
	(segment
		(start 20.3962 -149.2758)
		(end 21.3614 -150.241)
		(width 0.1397)
		(layer "B.Cu")
		(net "PWM_EXP_1A")
	)
	(segment
		(start 30.493716 -240.1824)
		(end 30.493716 -239.121442)
		(width 0.1397)
		(layer "F.Cu")
		(net "FCB_EEPROM_A2")
	)
	(segment
		(start 30.493716 -242.14328)
		(end 30.493716 -240.1824)
		(width 0.1397)
		(layer "F.Cu")
		(net "FCB_EEPROM_A2")
	)
	(segment
		(start 30.24632 -243.647722)
		(end 31.122366 -242.771676)
		(width 0.1397)
		(layer "F.Cu")
		(net "FCB_EEPROM_A2")
	)
	(segment
		(start 30.493716 -239.121442)
		(end 30.904434 -238.710724)
		(width 0.1397)
		(layer "F.Cu")
		(net "FCB_EEPROM_A2")
	)
	(segment
		(start 30.24632 -244.602)
		(end 30.24632 -243.647722)
		(width 0.1397)
		(layer "F.Cu")
		(net "FCB_EEPROM_A2")
	)
	(segment
		(start 31.122366 -242.771676)
		(end 31.122112 -242.771676)
		(width 0.1397)
		(layer "F.Cu")
		(net "FCB_EEPROM_A2")
	)
	(segment
		(start 31.122112 -242.771676)
		(end 30.493716 -242.14328)
		(width 0.1397)
		(layer "F.Cu")
		(net "FCB_EEPROM_A2")
	)
	(via
		(at 30.493716 -240.1824)
		(size 0.7112)
		(drill 0.3556)
		(layers "F.Cu" "B.Cu")
		(net "FCB_EEPROM_A2")
	)
	(segment
		(start 29.223716 -241.02187)
		(end 29.223716 -242.202716)
		(width 0.1397)
		(layer "F.Cu")
		(net "FCB_EEPROM_A1")
	)
	(segment
		(start 28.697936 -240.49609)
		(end 28.6512 -240.449354)
		(width 0.1397)
		(layer "F.Cu")
		(net "FCB_EEPROM_A1")
	)
	(segment
		(start 29.223716 -242.202716)
		(end 29.792676 -242.771676)
		(width 0.1397)
		(layer "F.Cu")
		(net "FCB_EEPROM_A1")
	)
	(segment
		(start 28.697936 -240.49609)
		(end 29.223716 -241.02187)
		(width 0.1397)
		(layer "F.Cu")
		(net "FCB_EEPROM_A1")
	)
	(segment
		(start 29.852366 -242.771676)
		(end 29.59608 -243.027962)
		(width 0.1397)
		(layer "F.Cu")
		(net "FCB_EEPROM_A1")
	)
	(segment
		(start 28.6512 -239.8395)
		(end 29.7942 -238.6965)
		(width 0.1397)
		(layer "F.Cu")
		(net "FCB_EEPROM_A1")
	)
	(segment
		(start 29.59608 -243.027962)
		(end 29.59608 -244.602)
		(width 0.1397)
		(layer "F.Cu")
		(net "FCB_EEPROM_A1")
	)
	(segment
		(start 29.792676 -242.771676)
		(end 29.852366 -242.771676)
		(width 0.1397)
		(layer "F.Cu")
		(net "FCB_EEPROM_A1")
	)
	(segment
		(start 28.6512 -240.449354)
		(end 28.6512 -239.8395)
		(width 0.1397)
		(layer "F.Cu")
		(net "FCB_EEPROM_A1")
	)
	(via
		(at 28.697936 -240.49609)
		(size 0.7112)
		(drill 0.3556)
		(layers "F.Cu" "B.Cu")
		(net "FCB_EEPROM_A1")
	)
	(segment
		(start 28.067 -238.6965)
		(end 28.067 -239.395)
		(width 0.1397)
		(layer "F.Cu")
		(net "FCB_EEPROM_A0")
	)
	(segment
		(start 26.9367 -241.6429)
		(end 27.4828 -242.189)
		(width 0.1397)
		(layer "F.Cu")
		(net "FCB_EEPROM_A0")
	)
	(segment
		(start 26.9367 -240.5253)
		(end 26.9367 -241.6429)
		(width 0.1397)
		(layer "F.Cu")
		(net "FCB_EEPROM_A0")
	)
	(segment
		(start 27.4828 -242.189)
		(end 28.065476 -242.771676)
		(width 0.1397)
		(layer "F.Cu")
		(net "FCB_EEPROM_A0")
	)
	(segment
		(start 28.94584 -243.13515)
		(end 28.94584 -244.602)
		(width 0.1397)
		(layer "F.Cu")
		(net "FCB_EEPROM_A0")
	)
	(segment
		(start 28.065476 -242.771676)
		(end 28.582366 -242.771676)
		(width 0.1397)
		(layer "F.Cu")
		(net "FCB_EEPROM_A0")
	)
	(segment
		(start 28.067 -239.395)
		(end 26.9367 -240.5253)
		(width 0.1397)
		(layer "F.Cu")
		(net "FCB_EEPROM_A0")
	)
	(segment
		(start 28.582366 -242.771676)
		(end 28.94584 -243.13515)
		(width 0.1397)
		(layer "F.Cu")
		(net "FCB_EEPROM_A0")
	)
	(via
		(at 27.4828 -242.189)
		(size 0.7112)
		(drill 0.3556)
		(layers "F.Cu" "B.Cu")
		(net "FCB_EEPROM_A0")
	)
	(segment
		(start 26.742898 -368.158014)
		(end 27.2796 -368.158014)
		(width 0.254)
		(layer "F.Cu")
		(net "ADM1276_SS")
	)
	(segment
		(start 25.4 -366.815116)
		(end 26.742898 -368.158014)
		(width 0.254)
		(layer "F.Cu")
		(net "ADM1276_SS")
	)
	(segment
		(start 25.4 -365.7981)
		(end 25.4 -366.522)
		(width 0.254)
		(layer "F.Cu")
		(net "ADM1276_SS")
	)
	(segment
		(start 25.4 -366.522)
		(end 25.4 -366.815116)
		(width 0.254)
		(layer "F.Cu")
		(net "ADM1276_SS")
	)
	(segment
		(start 24.0665 -364.4646)
		(end 25.4 -365.7981)
		(width 0.254)
		(layer "F.Cu")
		(net "ADM1276_SS")
	)
	(via
		(at 25.4 -366.522)
		(size 0.7112)
		(drill 0.3556)
		(layers "F.Cu" "B.Cu")
		(net "ADM1276_SS")
	)
	(segment
		(start 27.61234 -155.607766)
		(end 27.61234 -154.86634)
		(width 0.1397)
		(layer "F.Cu")
		(net "NCT7904_VREF")
	)
	(segment
		(start 26.67 -153.924)
		(end 26.67 -153.2128)
		(width 0.1397)
		(layer "F.Cu")
		(net "NCT7904_VREF")
	)
	(segment
		(start 26.67 -153.2128)
		(end 26.67 -152.1333)
		(width 0.1397)
		(layer "F.Cu")
		(net "NCT7904_VREF")
	)
	(segment
		(start 27.61234 -154.86634)
		(end 26.67 -153.924)
		(width 0.1397)
		(layer "F.Cu")
		(net "NCT7904_VREF")
	)
	(segment
		(start 26.67 -152.1333)
		(end 26.289 -151.7523)
		(width 0.1397)
		(layer "F.Cu")
		(net "NCT7904_VREF")
	)
	(segment
		(start 40.3098 -156.4386)
		(end 38.96614 -157.78226)
		(width 0.1397)
		(layer "F.Cu")
		(net "NCT7904_PROCHOT")
	)
	(segment
		(start 38.96614 -157.78226)
		(end 37.81933 -157.78226)
		(width 0.1397)
		(layer "F.Cu")
		(net "NCT7904_PROCHOT")
	)
	(segment
		(start 37.81933 -157.78226)
		(end 36.002214 -159.599376)
		(width 0.1397)
		(layer "F.Cu")
		(net "NCT7904_PROCHOT")
	)
	(segment
		(start 40.8178 -156.4386)
		(end 40.3098 -156.4386)
		(width 0.1397)
		(layer "F.Cu")
		(net "NCT7904_PROCHOT")
	)
	(segment
		(start 36.002214 -159.599376)
		(end 34.60369 -159.599376)
		(width 0.1397)
		(layer "F.Cu")
		(net "NCT7904_PROCHOT")
	)
	(segment
		(start 38.361366 -159.40151)
		(end 38.118288 -159.40151)
		(width 0.1397)
		(layer "F.Cu")
		(net "NCT7904_THERMTRIP")
	)
	(segment
		(start 36.420552 -161.099246)
		(end 34.60369 -161.099246)
		(width 0.1397)
		(layer "F.Cu")
		(net "NCT7904_THERMTRIP")
	)
	(segment
		(start 38.118288 -159.40151)
		(end 36.420552 -161.099246)
		(width 0.1397)
		(layer "F.Cu")
		(net "NCT7904_THERMTRIP")
	)
	(segment
		(start 36.20135 -156.88564)
		(end 35.487864 -157.599126)
		(width 0.1397)
		(layer "F.Cu")
		(net "NCT7904_VSEN14")
	)
	(segment
		(start 35.487864 -157.599126)
		(end 34.60369 -157.599126)
		(width 0.1397)
		(layer "F.Cu")
		(net "NCT7904_VSEN14")
	)
	(segment
		(start 36.659566 -152.08631)
		(end 36.20135 -152.544526)
		(width 0.1397)
		(layer "F.Cu")
		(net "NCT7904_VSEN14")
	)
	(segment
		(start 36.20135 -152.544526)
		(end 36.20135 -156.88564)
		(width 0.1397)
		(layer "F.Cu")
		(net "NCT7904_VSEN14")
	)
	(segment
		(start 37.70249 -165.958266)
		(end 37.70249 -167.134032)
		(width 0.1397)
		(layer "F.Cu")
		(net "I2C_C_SCL")
	)
	(segment
		(start 34.163 -360.68)
		(end 33.9852 -360.8578)
		(width 0.1397)
		(layer "F.Cu")
		(net "I2C_C_SCL")
	)
	(segment
		(start 30.3022 -254.3429)
		(end 35.280092 -259.320792)
		(width 0.1397)
		(layer "F.Cu")
		(net "I2C_C_SCL")
	)
	(segment
		(start 37.70249 -167.134032)
		(end 37.84473 -167.276272)
		(width 0.1397)
		(layer "F.Cu")
		(net "I2C_C_SCL")
	)
	(segment
		(start 35.3314 -254.8001)
		(end 35.3314 -255.5748)
		(width 0.1397)
		(layer "F.Cu")
		(net "I2C_C_SCL")
	)
	(segment
		(start 33.9852 -360.8578)
		(end 32.3977 -360.8578)
		(width 0.1397)
		(layer "F.Cu")
		(net "I2C_C_SCL")
	)
	(segment
		(start 36.105592 -259.320792)
		(end 36.5506 -259.7658)
		(width 0.1397)
		(layer "F.Cu")
		(net "I2C_C_SCL")
	)
	(segment
		(start 13.7922 -67.3862)
		(end 14.605 -68.199)
		(width 0.1397)
		(layer "F.Cu")
		(net "I2C_C_SCL")
	)
	(segment
		(start 35.280092 -259.320792)
		(end 36.105592 -259.320792)
		(width 0.1397)
		(layer "F.Cu")
		(net "I2C_C_SCL")
	)
	(segment
		(start 32.3977 -360.8578)
		(end 32.385 -360.8705)
		(width 0.1397)
		(layer "F.Cu")
		(net "I2C_C_SCL")
	)
	(segment
		(start 37.83965 -259.029454)
		(end 37.103304 -259.7658)
		(width 0.1397)
		(layer "F.Cu")
		(net "I2C_C_SCL")
	)
	(segment
		(start 37.103304 -259.7658)
		(end 36.5506 -259.7658)
		(width 0.1397)
		(layer "F.Cu")
		(net "I2C_C_SCL")
	)
	(segment
		(start 35.3314 -255.5748)
		(end 37.83965 -258.08305)
		(width 0.1397)
		(layer "F.Cu")
		(net "I2C_C_SCL")
	)
	(segment
		(start 13.7922 -66.8909)
		(end 13.7922 -67.3862)
		(width 0.1397)
		(layer "F.Cu")
		(net "I2C_C_SCL")
	)
	(segment
		(start 37.83965 -258.08305)
		(end 37.83965 -259.029454)
		(width 0.1397)
		(layer "F.Cu")
		(net "I2C_C_SCL")
	)
	(via
		(at 36.5506 -259.7658)
		(size 0.7112)
		(drill 0.4064)
		(layers "F.Cu" "B.Cu")
		(net "I2C_C_SCL")
	)
	(via
		(at 14.605 -68.199)
		(size 0.5588)
		(drill 0.3048)
		(layers "F.Cu" "B.Cu")
		(net "I2C_C_SCL")
	)
	(via
		(at 34.163 -360.68)
		(size 0.5588)
		(drill 0.3048)
		(layers "F.Cu" "B.Cu")
		(net "I2C_C_SCL")
	)
	(via
		(at 37.84473 -167.276272)
		(size 0.7112)
		(drill 0.4064)
		(layers "F.Cu" "B.Cu")
		(net "I2C_C_SCL")
	)
	(via
		(at 19.346164 -140.072364)
		(size 0.7112)
		(drill 0.3556)
		(layers "F.Cu" "B.Cu")
		(net "I2C_C_SCL")
	)
	(segment
		(start 12.8778 -110.3376)
		(end 14.1605 -111.6203)
		(width 0.1397)
		(layer "B.Cu")
		(net "I2C_C_SCL")
	)
	(segment
		(start 38.9128 -186.8932)
		(end 38.8366 -186.9694)
		(width 0.1397)
		(layer "B.Cu")
		(net "I2C_C_SCL")
	)
	(segment
		(start 40.0304 -185.7502)
		(end 38.9128 -186.8678)
		(width 0.1397)
		(layer "B.Cu")
		(net "I2C_C_SCL")
	)
	(segment
		(start 33.921954 -360.438954)
		(end 33.921954 -278.777446)
		(width 0.1397)
		(layer "B.Cu")
		(net "I2C_C_SCL")
	)
	(segment
		(start 36.7538 -258.2672)
		(end 36.5506 -258.4704)
		(width 0.1397)
		(layer "B.Cu")
		(net "I2C_C_SCL")
	)
	(segment
		(start 37.84473 -167.276272)
		(end 37.84473 -169.603928)
		(width 0.1397)
		(layer "B.Cu")
		(net "I2C_C_SCL")
	)
	(segment
		(start 33.62325 -153.96845)
		(end 32.4612 -152.8064)
		(width 0.1397)
		(layer "B.Cu")
		(net "I2C_C_SCL")
	)
	(segment
		(start 39.99865 -173.23435)
		(end 39.9796 -173.2534)
		(width 0.1397)
		(layer "B.Cu")
		(net "I2C_C_SCL")
	)
	(segment
		(start 42.3164 -252.7046)
		(end 42.291 -252.7046)
		(width 0.1397)
		(layer "B.Cu")
		(net "I2C_C_SCL")
	)
	(segment
		(start 35.985958 -260.3754)
		(end 36.5506 -259.810758)
		(width 0.1397)
		(layer "B.Cu")
		(net "I2C_C_SCL")
	)
	(segment
		(start 39.99865 -171.757848)
		(end 39.99865 -173.23435)
		(width 0.1397)
		(layer "B.Cu")
		(net "I2C_C_SCL")
	)
	(segment
		(start 42.1386 -213.9442)
		(end 43.6372 -215.4428)
		(width 0.1397)
		(layer "B.Cu")
		(net "I2C_C_SCL")
	)
	(segment
		(start 35.979354 -273.779234)
		(end 35.979862 -273.778726)
		(width 0.1397)
		(layer "B.Cu")
		(net "I2C_C_SCL")
	)
	(segment
		(start 35.979354 -276.720046)
		(end 35.979354 -273.779234)
		(width 0.1397)
		(layer "B.Cu")
		(net "I2C_C_SCL")
	)
	(segment
		(start 14.6431 -68.2371)
		(end 14.6431 -73.1647)
		(width 0.1397)
		(layer "B.Cu")
		(net "I2C_C_SCL")
	)
	(segment
		(start 14.1605 -121.8565)
		(end 16.4211 -124.1171)
		(width 0.1397)
		(layer "B.Cu")
		(net "I2C_C_SCL")
	)
	(segment
		(start 38.8366 -186.9694)
		(end 38.8366 -210.6422)
		(width 0.1397)
		(layer "B.Cu")
		(net "I2C_C_SCL")
	)
	(segment
		(start 39.9796 -173.2534)
		(end 39.9796 -176.1236)
		(width 0.1397)
		(layer "B.Cu")
		(net "I2C_C_SCL")
	)
	(segment
		(start 38.4302 -166.690802)
		(end 38.4302 -159.978598)
		(width 0.1397)
		(layer "B.Cu")
		(net "I2C_C_SCL")
	)
	(segment
		(start 30.0736 -150.4442)
		(end 30.0736 -150.4188)
		(width 0.1397)
		(layer "B.Cu")
		(net "I2C_C_SCL")
	)
	(segment
		(start 35.98545 -260.484366)
		(end 35.98545 -260.484112)
		(width 0.1397)
		(layer "B.Cu")
		(net "I2C_C_SCL")
	)
	(segment
		(start 38.9128 -186.8678)
		(end 38.9128 -186.8932)
		(width 0.1397)
		(layer "B.Cu")
		(net "I2C_C_SCL")
	)
	(segment
		(start 40.3098 -212.1154)
		(end 40.3352 -212.1154)
		(width 0.1397)
		(layer "B.Cu")
		(net "I2C_C_SCL")
	)
	(segment
		(start 32.4612 -152.8064)
		(end 32.4358 -152.8064)
		(width 0.1397)
		(layer "B.Cu")
		(net "I2C_C_SCL")
	)
	(segment
		(start 33.921954 -278.777446)
		(end 35.979354 -276.720046)
		(width 0.1397)
		(layer "B.Cu")
		(net "I2C_C_SCL")
	)
	(segment
		(start 35.985958 -260.483604)
		(end 35.985958 -260.3754)
		(width 0.1397)
		(layer "B.Cu")
		(net "I2C_C_SCL")
	)
	(segment
		(start 22.6822 -143.4084)
		(end 19.346164 -140.072364)
		(width 0.1397)
		(layer "B.Cu")
		(net "I2C_C_SCL")
	)
	(segment
		(start 43.6372 -215.4428)
		(end 43.6372 -251.3838)
		(width 0.1397)
		(layer "B.Cu")
		(net "I2C_C_SCL")
	)
	(segment
		(start 36.816538 -153.96845)
		(end 33.62325 -153.96845)
		(width 0.1397)
		(layer "B.Cu")
		(net "I2C_C_SCL")
	)
	(segment
		(start 37.84473 -169.603928)
		(end 39.99865 -171.757848)
		(width 0.1397)
		(layer "B.Cu")
		(net "I2C_C_SCL")
	)
	(segment
		(start 12.8778 -93.65615)
		(end 12.8778 -110.3376)
		(width 0.1397)
		(layer "B.Cu")
		(net "I2C_C_SCL")
	)
	(segment
		(start 39.9796 -176.1236)
		(end 40.022018 -176.166018)
		(width 0.1397)
		(layer "B.Cu")
		(net "I2C_C_SCL")
	)
	(segment
		(start 16.4211 -124.1171)
		(end 16.4211 -137.1473)
		(width 0.1397)
		(layer "B.Cu")
		(net "I2C_C_SCL")
	)
	(segment
		(start 38.4302 -159.978598)
		(end 39.795196 -158.613602)
		(width 0.1397)
		(layer "B.Cu")
		(net "I2C_C_SCL")
	)
	(segment
		(start 42.291 -252.7046)
		(end 36.7538 -258.2418)
		(width 0.1397)
		(layer "B.Cu")
		(net "I2C_C_SCL")
	)
	(segment
		(start 43.6372 -251.3838)
		(end 42.3164 -252.7046)
		(width 0.1397)
		(layer "B.Cu")
		(net "I2C_C_SCL")
	)
	(segment
		(start 39.795196 -156.947108)
		(end 36.816538 -153.96845)
		(width 0.1397)
		(layer "B.Cu")
		(net "I2C_C_SCL")
	)
	(segment
		(start 42.1386 -213.9188)
		(end 42.1386 -213.9442)
		(width 0.1397)
		(layer "B.Cu")
		(net "I2C_C_SCL")
	)
	(segment
		(start 35.979862 -273.778726)
		(end 35.979862 -260.489954)
		(width 0.1397)
		(layer "B.Cu")
		(net "I2C_C_SCL")
	)
	(segment
		(start 35.979862 -260.489954)
		(end 35.98545 -260.484366)
		(width 0.1397)
		(layer "B.Cu")
		(net "I2C_C_SCL")
	)
	(segment
		(start 13.335 -74.4728)
		(end 13.335 -93.19895)
		(width 0.1397)
		(layer "B.Cu")
		(net "I2C_C_SCL")
	)
	(segment
		(start 14.6431 -73.1647)
		(end 13.335 -74.4728)
		(width 0.1397)
		(layer "B.Cu")
		(net "I2C_C_SCL")
	)
	(segment
		(start 14.1605 -111.6203)
		(end 14.1605 -121.8565)
		(width 0.1397)
		(layer "B.Cu")
		(net "I2C_C_SCL")
	)
	(segment
		(start 34.163 -360.68)
		(end 33.921954 -360.438954)
		(width 0.1397)
		(layer "B.Cu")
		(net "I2C_C_SCL")
	)
	(segment
		(start 37.84473 -167.276272)
		(end 38.4302 -166.690802)
		(width 0.1397)
		(layer "B.Cu")
		(net "I2C_C_SCL")
	)
	(segment
		(start 40.3352 -212.1154)
		(end 42.1386 -213.9188)
		(width 0.1397)
		(layer "B.Cu")
		(net "I2C_C_SCL")
	)
	(segment
		(start 23.0632 -143.4084)
		(end 22.6822 -143.4084)
		(width 0.1397)
		(layer "B.Cu")
		(net "I2C_C_SCL")
	)
	(segment
		(start 36.5506 -258.4704)
		(end 36.5506 -259.7658)
		(width 0.1397)
		(layer "B.Cu")
		(net "I2C_C_SCL")
	)
	(segment
		(start 38.8366 -210.6422)
		(end 40.3098 -212.1154)
		(width 0.1397)
		(layer "B.Cu")
		(net "I2C_C_SCL")
	)
	(segment
		(start 40.0304 -185.2422)
		(end 40.0304 -185.7502)
		(width 0.1397)
		(layer "B.Cu")
		(net "I2C_C_SCL")
	)
	(segment
		(start 30.0736 -150.4188)
		(end 23.0632 -143.4084)
		(width 0.1397)
		(layer "B.Cu")
		(net "I2C_C_SCL")
	)
	(segment
		(start 32.4358 -152.8064)
		(end 30.0736 -150.4442)
		(width 0.1397)
		(layer "B.Cu")
		(net "I2C_C_SCL")
	)
	(segment
		(start 36.7538 -258.2418)
		(end 36.7538 -258.2672)
		(width 0.1397)
		(layer "B.Cu")
		(net "I2C_C_SCL")
	)
	(segment
		(start 16.4211 -137.1473)
		(end 19.346164 -140.072364)
		(width 0.1397)
		(layer "B.Cu")
		(net "I2C_C_SCL")
	)
	(segment
		(start 13.335 -93.19895)
		(end 12.8778 -93.65615)
		(width 0.1397)
		(layer "B.Cu")
		(net "I2C_C_SCL")
	)
	(segment
		(start 39.795196 -158.613602)
		(end 39.795196 -156.947108)
		(width 0.1397)
		(layer "B.Cu")
		(net "I2C_C_SCL")
	)
	(segment
		(start 36.5506 -259.810758)
		(end 36.5506 -259.7658)
		(width 0.1397)
		(layer "B.Cu")
		(net "I2C_C_SCL")
	)
	(segment
		(start 40.022018 -185.233818)
		(end 40.0304 -185.2422)
		(width 0.1397)
		(layer "B.Cu")
		(net "I2C_C_SCL")
	)
	(segment
		(start 35.98545 -260.484112)
		(end 35.985958 -260.483604)
		(width 0.1397)
		(layer "B.Cu")
		(net "I2C_C_SCL")
	)
	(segment
		(start 40.022018 -176.166018)
		(end 40.022018 -185.233818)
		(width 0.1397)
		(layer "B.Cu")
		(net "I2C_C_SCL")
	)
	(segment
		(start 14.605 -68.199)
		(end 14.6431 -68.2371)
		(width 0.1397)
		(layer "B.Cu")
		(net "I2C_C_SCL")
	)
	(segment
		(start 35.358324 -157.100016)
		(end 34.60369 -157.100016)
		(width 0.1397)
		(layer "F.Cu")
		(net "NCT7904_VSEN13")
	)
	(segment
		(start 35.75685 -153.672794)
		(end 35.75685 -156.70149)
		(width 0.1397)
		(layer "F.Cu")
		(net "NCT7904_VSEN13")
	)
	(segment
		(start 35.75685 -156.70149)
		(end 35.358324 -157.100016)
		(width 0.1397)
		(layer "F.Cu")
		(net "NCT7904_VSEN13")
	)
	(segment
		(start 35.541966 -153.45791)
		(end 35.75685 -153.672794)
		(width 0.1397)
		(layer "F.Cu")
		(net "NCT7904_VSEN13")
	)
	(segment
		(start 33.11144 -154.407616)
		(end 33.11144 -155.607766)
		(width 0.1397)
		(layer "F.Cu")
		(net "NCT7904_VSEN12")
	)
	(segment
		(start 35.59429 -151.924766)
		(end 33.11144 -154.407616)
		(width 0.1397)
		(layer "F.Cu")
		(net "NCT7904_VSEN12")
	)
	(segment
		(start 35.59429 -150.680166)
		(end 35.59429 -151.924766)
		(width 0.1397)
		(layer "F.Cu")
		(net "NCT7904_VSEN12")
	)
	(segment
		(start 36.322 -258.8006)
		(end 37.2872 -258.8006)
		(width 0.1397)
		(layer "F.Cu")
		(net "I2C_C_SDA")
	)
	(segment
		(start 34.29 -254.8255)
		(end 34.29 -255.397)
		(width 0.1397)
		(layer "F.Cu")
		(net "I2C_C_SDA")
	)
	(segment
		(start 37.869368 -168.082214)
		(end 37.0332 -167.246046)
		(width 0.1397)
		(layer "F.Cu")
		(net "I2C_C_SDA")
	)
	(segment
		(start 37.0332 -166.355776)
		(end 36.63569 -165.958266)
		(width 0.1397)
		(layer "F.Cu")
		(net "I2C_C_SDA")
	)
	(segment
		(start 33.655 -360.3244)
		(end 32.0548 -360.3244)
		(width 0.1397)
		(layer "F.Cu")
		(net "I2C_C_SDA")
	)
	(segment
		(start 15.24 -69.9516)
		(end 15.24 -67.3227)
		(width 0.1397)
		(layer "F.Cu")
		(net "I2C_C_SDA")
	)
	(segment
		(start 35.762692 -258.800092)
		(end 36.321492 -258.800092)
		(width 0.1397)
		(layer "F.Cu")
		(net "I2C_C_SDA")
	)
	(segment
		(start 34.29 -255.397)
		(end 37.2872 -258.3942)
		(width 0.1397)
		(layer "F.Cu")
		(net "I2C_C_SDA")
	)
	(segment
		(start 34.442654 -359.7148)
		(end 34.2646 -359.7148)
		(width 0.1397)
		(layer "F.Cu")
		(net "I2C_C_SDA")
	)
	(segment
		(start 37.2872 -258.3942)
		(end 37.2872 -258.8006)
		(width 0.1397)
		(layer "F.Cu")
		(net "I2C_C_SDA")
	)
	(segment
		(start 31.5087 -360.8705)
		(end 31.242 -360.8705)
		(width 0.1397)
		(layer "F.Cu")
		(net "I2C_C_SDA")
	)
	(segment
		(start 31.3182 -254.3429)
		(end 31.3182 -254.3556)
		(width 0.1397)
		(layer "F.Cu")
		(net "I2C_C_SDA")
	)
	(segment
		(start 34.2646 -359.7148)
		(end 33.655 -360.3244)
		(width 0.1397)
		(layer "F.Cu")
		(net "I2C_C_SDA")
	)
	(segment
		(start 15.24 -67.3227)
		(end 14.8082 -66.8909)
		(width 0.1397)
		(layer "F.Cu")
		(net "I2C_C_SDA")
	)
	(segment
		(start 38.463728 -168.082214)
		(end 37.869368 -168.082214)
		(width 0.1397)
		(layer "F.Cu")
		(net "I2C_C_SDA")
	)
	(segment
		(start 31.3182 -254.3556)
		(end 35.762692 -258.800092)
		(width 0.1397)
		(layer "F.Cu")
		(net "I2C_C_SDA")
	)
	(segment
		(start 32.0548 -360.3244)
		(end 31.5087 -360.8705)
		(width 0.1397)
		(layer "F.Cu")
		(net "I2C_C_SDA")
	)
	(segment
		(start 37.0332 -167.246046)
		(end 37.0332 -166.355776)
		(width 0.1397)
		(layer "F.Cu")
		(net "I2C_C_SDA")
	)
	(segment
		(start 15.3162 -70.0278)
		(end 15.24 -69.9516)
		(width 0.1397)
		(layer "F.Cu")
		(net "I2C_C_SDA")
	)
	(segment
		(start 36.321492 -258.800092)
		(end 36.322 -258.8006)
		(width 0.1397)
		(layer "F.Cu")
		(net "I2C_C_SDA")
	)
	(via
		(at 38.463728 -168.082214)
		(size 0.7112)
		(drill 0.4064)
		(layers "F.Cu" "B.Cu")
		(net "I2C_C_SDA")
	)
	(via
		(at 15.3162 -70.0278)
		(size 0.5588)
		(drill 0.3048)
		(layers "F.Cu" "B.Cu")
		(net "I2C_C_SDA")
	)
	(via
		(at 34.442654 -359.7148)
		(size 0.5588)
		(drill 0.3048)
		(layers "F.Cu" "B.Cu")
		(net "I2C_C_SDA")
	)
	(via
		(at 15.012416 -112.037876)
		(size 0.7112)
		(drill 0.3556)
		(layers "F.Cu" "B.Cu")
		(net "I2C_C_SDA")
	)
	(via
		(at 37.2872 -258.8006)
		(size 0.7112)
		(drill 0.4064)
		(layers "F.Cu" "B.Cu")
		(net "I2C_C_SDA")
	)
	(segment
		(start 40.51935 -171.541948)
		(end 38.463728 -169.486326)
		(width 0.1397)
		(layer "B.Cu")
		(net "I2C_C_SDA")
	)
	(segment
		(start 40.5003 -175.8823)
		(end 40.5003 -173.4693)
		(width 0.1397)
		(layer "B.Cu")
		(net "I2C_C_SDA")
	)
	(segment
		(start 39.37 -187.1726)
		(end 40.5638 -185.9788)
		(width 0.1397)
		(layer "B.Cu")
		(net "I2C_C_SDA")
	)
	(segment
		(start 40.5638 -185.9788)
		(end 40.5638 -175.9458)
		(width 0.1397)
		(layer "B.Cu")
		(net "I2C_C_SDA")
	)
	(segment
		(start 13.8557 -93.41485)
		(end 13.3985 -93.87205)
		(width 0.1397)
		(layer "B.Cu")
		(net "I2C_C_SDA")
	)
	(segment
		(start 13.3985 -93.87205)
		(end 13.3985 -110.1217)
		(width 0.1397)
		(layer "B.Cu")
		(net "I2C_C_SDA")
	)
	(segment
		(start 14.6812 -121.6406)
		(end 16.9672 -123.9266)
		(width 0.1397)
		(layer "B.Cu")
		(net "I2C_C_SDA")
	)
	(segment
		(start 40.315896 -155.993592)
		(end 40.315896 -158.829502)
		(width 0.1397)
		(layer "B.Cu")
		(net "I2C_C_SDA")
	)
	(segment
		(start 36.582604 -152.2603)
		(end 40.315896 -155.993592)
		(width 0.1397)
		(layer "B.Cu")
		(net "I2C_C_SDA")
	)
	(segment
		(start 40.5638 -175.9458)
		(end 40.5003 -175.8823)
		(width 0.1397)
		(layer "B.Cu")
		(net "I2C_C_SDA")
	)
	(segment
		(start 16.9672 -123.9266)
		(end 16.9672 -136.5758)
		(width 0.1397)
		(layer "B.Cu")
		(net "I2C_C_SDA")
	)
	(segment
		(start 40.5003 -173.4693)
		(end 40.51935 -173.45025)
		(width 0.1397)
		(layer "B.Cu")
		(net "I2C_C_SDA")
	)
	(segment
		(start 37.10305 -259.994908)
		(end 37.10305 -259.9944)
		(width 0.1397)
		(layer "B.Cu")
		(net "I2C_C_SDA")
	)
	(segment
		(start 37.2872 -258.8006)
		(end 37.2872 -258.4704)
		(width 0.1397)
		(layer "B.Cu")
		(net "I2C_C_SDA")
	)
	(segment
		(start 36.50615 -260.700012)
		(end 36.506658 -260.699504)
		(width 0.1397)
		(layer "B.Cu")
		(net "I2C_C_SDA")
	)
	(segment
		(start 15.3162 -70.0278)
		(end 15.3162 -73.2282)
		(width 0.1397)
		(layer "B.Cu")
		(net "I2C_C_SDA")
	)
	(segment
		(start 13.3985 -110.1217)
		(end 15.012416 -111.735616)
		(width 0.1397)
		(layer "B.Cu")
		(net "I2C_C_SDA")
	)
	(segment
		(start 36.500054 -277.113746)
		(end 36.500054 -273.995134)
		(width 0.1397)
		(layer "B.Cu")
		(net "I2C_C_SDA")
	)
	(segment
		(start 32.6517 -152.2603)
		(end 36.582604 -152.2603)
		(width 0.1397)
		(layer "B.Cu")
		(net "I2C_C_SDA")
	)
	(segment
		(start 44.1706 -251.587)
		(end 44.1706 -215.2142)
		(width 0.1397)
		(layer "B.Cu")
		(net "I2C_C_SDA")
	)
	(segment
		(start 40.315896 -158.829502)
		(end 38.9509 -160.194498)
		(width 0.1397)
		(layer "B.Cu")
		(net "I2C_C_SDA")
	)
	(segment
		(start 38.9509 -160.194498)
		(end 38.9509 -167.595042)
		(width 0.1397)
		(layer "B.Cu")
		(net "I2C_C_SDA")
	)
	(segment
		(start 37.2618 -259.83565)
		(end 37.2618 -258.826)
		(width 0.1397)
		(layer "B.Cu")
		(net "I2C_C_SDA")
	)
	(segment
		(start 34.442654 -359.7148)
		(end 34.442654 -279.171146)
		(width 0.1397)
		(layer "B.Cu")
		(net "I2C_C_SDA")
	)
	(segment
		(start 38.463728 -169.486326)
		(end 38.463728 -168.082214)
		(width 0.1397)
		(layer "B.Cu")
		(net "I2C_C_SDA")
	)
	(segment
		(start 13.8557 -74.6887)
		(end 13.8557 -93.41485)
		(width 0.1397)
		(layer "B.Cu")
		(net "I2C_C_SDA")
	)
	(segment
		(start 36.506658 -260.5913)
		(end 37.10305 -259.994908)
		(width 0.1397)
		(layer "B.Cu")
		(net "I2C_C_SDA")
	)
	(segment
		(start 15.012416 -112.037876)
		(end 14.6812 -112.369092)
		(width 0.1397)
		(layer "B.Cu")
		(net "I2C_C_SDA")
	)
	(segment
		(start 36.500562 -273.994626)
		(end 36.500562 -260.705854)
		(width 0.1397)
		(layer "B.Cu")
		(net "I2C_C_SDA")
	)
	(segment
		(start 14.6812 -112.369092)
		(end 14.6812 -121.6406)
		(width 0.1397)
		(layer "B.Cu")
		(net "I2C_C_SDA")
	)
	(segment
		(start 37.2618 -258.826)
		(end 37.2872 -258.8006)
		(width 0.1397)
		(layer "B.Cu")
		(net "I2C_C_SDA")
	)
	(segment
		(start 36.50615 -260.700266)
		(end 36.50615 -260.700012)
		(width 0.1397)
		(layer "B.Cu")
		(net "I2C_C_SDA")
	)
	(segment
		(start 37.2872 -258.4704)
		(end 44.1706 -251.587)
		(width 0.1397)
		(layer "B.Cu")
		(net "I2C_C_SDA")
	)
	(segment
		(start 40.51935 -173.45025)
		(end 40.51935 -171.541948)
		(width 0.1397)
		(layer "B.Cu")
		(net "I2C_C_SDA")
	)
	(segment
		(start 15.012416 -111.735616)
		(end 15.012416 -112.037876)
		(width 0.1397)
		(layer "B.Cu")
		(net "I2C_C_SDA")
	)
	(segment
		(start 39.37 -210.4136)
		(end 39.37 -187.1726)
		(width 0.1397)
		(layer "B.Cu")
		(net "I2C_C_SDA")
	)
	(segment
		(start 34.442654 -279.171146)
		(end 36.500054 -277.113746)
		(width 0.1397)
		(layer "B.Cu")
		(net "I2C_C_SDA")
	)
	(segment
		(start 36.506658 -260.699504)
		(end 36.506658 -260.5913)
		(width 0.1397)
		(layer "B.Cu")
		(net "I2C_C_SDA")
	)
	(segment
		(start 44.1706 -215.2142)
		(end 39.37 -210.4136)
		(width 0.1397)
		(layer "B.Cu")
		(net "I2C_C_SDA")
	)
	(segment
		(start 36.500562 -260.705854)
		(end 36.50615 -260.700266)
		(width 0.1397)
		(layer "B.Cu")
		(net "I2C_C_SDA")
	)
	(segment
		(start 36.500054 -273.995134)
		(end 36.500562 -273.994626)
		(width 0.1397)
		(layer "B.Cu")
		(net "I2C_C_SDA")
	)
	(segment
		(start 15.3162 -73.2282)
		(end 13.8557 -74.6887)
		(width 0.1397)
		(layer "B.Cu")
		(net "I2C_C_SDA")
	)
	(segment
		(start 16.9672 -136.5758)
		(end 32.6517 -152.2603)
		(width 0.1397)
		(layer "B.Cu")
		(net "I2C_C_SDA")
	)
	(segment
		(start 37.10305 -259.9944)
		(end 37.2618 -259.83565)
		(width 0.1397)
		(layer "B.Cu")
		(net "I2C_C_SDA")
	)
	(segment
		(start 38.9509 -167.595042)
		(end 38.463728 -168.082214)
		(width 0.1397)
		(layer "B.Cu")
		(net "I2C_C_SDA")
	)
	(segment
		(start 32.61233 -155.607766)
		(end 32.61233 -153.789126)
		(width 0.1397)
		(layer "F.Cu")
		(net "NCT7904_VSEN11")
	)
	(segment
		(start 32.61233 -153.789126)
		(end 33.51149 -152.889966)
		(width 0.1397)
		(layer "F.Cu")
		(net "NCT7904_VSEN11")
	)
	(segment
		(start 32.90824 -152.648666)
		(end 32.11195 -153.444956)
		(width 0.1397)
		(layer "F.Cu")
		(net "NCT7904_VSEN10")
	)
	(segment
		(start 32.90824 -152.64003)
		(end 32.90824 -152.648666)
		(width 0.1397)
		(layer "F.Cu")
		(net "NCT7904_VSEN10")
	)
	(segment
		(start 33.71469 -151.83358)
		(end 32.90824 -152.64003)
		(width 0.1397)
		(layer "F.Cu")
		(net "NCT7904_VSEN10")
	)
	(segment
		(start 33.71469 -150.730966)
		(end 33.71469 -151.83358)
		(width 0.1397)
		(layer "F.Cu")
		(net "NCT7904_VSEN10")
	)
	(segment
		(start 32.11195 -153.444956)
		(end 32.11195 -155.607766)
		(width 0.1397)
		(layer "F.Cu")
		(net "NCT7904_VSEN10")
	)
	(segment
		(start 32.46374 -152.45588)
		(end 32.46374 -152.464516)
		(width 0.1397)
		(layer "F.Cu")
		(net "NCT7904_VSEN9")
	)
	(segment
		(start 31.61157 -153.316686)
		(end 31.61157 -155.607766)
		(width 0.1397)
		(layer "F.Cu")
		(net "NCT7904_VSEN9")
	)
	(segment
		(start 32.46374 -152.464516)
		(end 31.61157 -153.316686)
		(width 0.1397)
		(layer "F.Cu")
		(net "NCT7904_VSEN9")
	)
	(segment
		(start 43.2308 -158.4071)
		(end 43.2308 -157.504892)
		(width 0.1397)
		(layer "F.Cu")
		(net "NCT7904_VSEN9")
	)
	(segment
		(start 32.766 -151.638)
		(end 32.766 -152.15362)
		(width 0.1397)
		(layer "F.Cu")
		(net "NCT7904_VSEN9")
	)
	(segment
		(start 43.2308 -157.504892)
		(end 43.268646 -157.467046)
		(width 0.1397)
		(layer "F.Cu")
		(net "NCT7904_VSEN9")
	)
	(segment
		(start 32.766 -152.15362)
		(end 32.46374 -152.45588)
		(width 0.1397)
		(layer "F.Cu")
		(net "NCT7904_VSEN9")
	)
	(via
		(at 32.766 -151.638)
		(size 0.5588)
		(drill 0.3048)
		(layers "F.Cu" "B.Cu")
		(net "NCT7904_VSEN9")
	)
	(via
		(at 34.671 -151.638)
		(size 0.7112)
		(drill 0.3556)
		(layers "F.Cu" "B.Cu")
		(net "NCT7904_VSEN9")
	)
	(via
		(at 43.268646 -157.467046)
		(size 0.7112)
		(drill 0.4064)
		(layers "F.Cu" "B.Cu")
		(net "NCT7904_VSEN9")
	)
	(segment
		(start 37.6555 -152.5651)
		(end 36.7284 -151.638)
		(width 0.1397)
		(layer "B.Cu")
		(net "NCT7904_VSEN9")
	)
	(segment
		(start 43.268646 -157.467046)
		(end 43.268646 -156.578046)
		(width 0.1397)
		(layer "B.Cu")
		(net "NCT7904_VSEN9")
	)
	(segment
		(start 34.671 -151.638)
		(end 32.766 -151.638)
		(width 0.1397)
		(layer "B.Cu")
		(net "NCT7904_VSEN9")
	)
	(segment
		(start 36.7284 -151.638)
		(end 34.671 -151.638)
		(width 0.1397)
		(layer "B.Cu")
		(net "NCT7904_VSEN9")
	)
	(segment
		(start 43.268646 -156.578046)
		(end 39.2557 -152.5651)
		(width 0.1397)
		(layer "B.Cu")
		(net "NCT7904_VSEN9")
	)
	(segment
		(start 39.2557 -152.5651)
		(end 37.6555 -152.5651)
		(width 0.1397)
		(layer "B.Cu")
		(net "NCT7904_VSEN9")
	)
	(segment
		(start 32.738568 -149.518116)
		(end 31.7246 -149.518116)
		(width 0.1397)
		(layer "F.Cu")
		(net "NCT7904_VSEN7")
	)
	(segment
		(start 30.6832 -150.8506)
		(end 31.7246 -149.8092)
		(width 0.1397)
		(layer "F.Cu")
		(net "NCT7904_VSEN7")
	)
	(segment
		(start 30.61208 -155.607766)
		(end 30.61208 -152.14092)
		(width 0.1397)
		(layer "F.Cu")
		(net "NCT7904_VSEN7")
	)
	(segment
		(start 30.6832 -152.0698)
		(end 30.6832 -150.8506)
		(width 0.1397)
		(layer "F.Cu")
		(net "NCT7904_VSEN7")
	)
	(segment
		(start 30.61208 -152.14092)
		(end 30.6832 -152.0698)
		(width 0.1397)
		(layer "F.Cu")
		(net "NCT7904_VSEN7")
	)
	(segment
		(start 31.7246 -149.8092)
		(end 31.7246 -149.518116)
		(width 0.1397)
		(layer "F.Cu")
		(net "NCT7904_VSEN7")
	)
	(segment
		(start 32.7406 -149.516084)
		(end 32.738568 -149.518116)
		(width 0.1397)
		(layer "F.Cu")
		(net "NCT7904_VSEN7")
	)
	(via
		(at 30.6832 -152.0698)
		(size 0.7112)
		(drill 0.3556)
		(layers "F.Cu" "B.Cu")
		(net "NCT7904_VSEN7")
	)
	(segment
		(start 34.60369 -160.600136)
		(end 36.258754 -160.600136)
		(width 0.1397)
		(layer "F.Cu")
		(net "NCT7904_PECI")
	)
	(segment
		(start 39.26586 -158.67126)
		(end 39.8018 -159.2072)
		(width 0.1397)
		(layer "F.Cu")
		(net "NCT7904_PECI")
	)
	(segment
		(start 38.18763 -158.67126)
		(end 39.26586 -158.67126)
		(width 0.1397)
		(layer "F.Cu")
		(net "NCT7904_PECI")
	)
	(segment
		(start 36.258754 -160.600136)
		(end 38.18763 -158.67126)
		(width 0.1397)
		(layer "F.Cu")
		(net "NCT7904_PECI")
	)
	(segment
		(start 28.3464 -355.5238)
		(end 28.194 -355.6762)
		(width 0.1397)
		(layer "F.Cu")
		(net "TEMP_ALM#")
	)
	(segment
		(start 30.8356 -357.6828)
		(end 29.2989 -357.6828)
		(width 0.1397)
		(layer "F.Cu")
		(net "TEMP_ALM#")
	)
	(segment
		(start 39.243 -174.5615)
		(end 38.4937 -174.5615)
		(width 0.1397)
		(layer "F.Cu")
		(net "TEMP_ALM#")
	)
	(segment
		(start 28.194 -356.7176)
		(end 28.3464 -356.87)
		(width 0.1397)
		(layer "F.Cu")
		(net "TEMP_ALM#")
	)
	(segment
		(start 29.2989 -357.4542)
		(end 29.2989 -357.6828)
		(width 0.1397)
		(layer "F.Cu")
		(net "TEMP_ALM#")
	)
	(segment
		(start 28.194 -355.6762)
		(end 28.194 -356.7176)
		(width 0.1397)
		(layer "F.Cu")
		(net "TEMP_ALM#")
	)
	(segment
		(start 38.7858 -157.1498)
		(end 39.567866 -156.367734)
		(width 0.1397)
		(layer "F.Cu")
		(net "TEMP_ALM#")
	)
	(segment
		(start 32.6898 -357.632)
		(end 32.290766 -357.232966)
		(width 0.1397)
		(layer "F.Cu")
		(net "TEMP_ALM#")
	)
	(segment
		(start 38.7858 -157.175962)
		(end 38.7858 -157.1498)
		(width 0.1397)
		(layer "F.Cu")
		(net "TEMP_ALM#")
	)
	(segment
		(start 32.290766 -357.232966)
		(end 31.285434 -357.232966)
		(width 0.1397)
		(layer "F.Cu")
		(net "TEMP_ALM#")
	)
	(segment
		(start 28.7147 -356.87)
		(end 29.2989 -357.4542)
		(width 0.1397)
		(layer "F.Cu")
		(net "TEMP_ALM#")
	)
	(segment
		(start 38.36035 -174.69485)
		(end 38.348412 -174.69485)
		(width 0.1397)
		(layer "F.Cu")
		(net "TEMP_ALM#")
	)
	(segment
		(start 32.85109 -168.168066)
		(end 32.85109 -169.198544)
		(width 0.1397)
		(layer "F.Cu")
		(net "TEMP_ALM#")
	)
	(segment
		(start 39.567866 -156.367734)
		(end 39.567866 -156.22651)
		(width 0.1397)
		(layer "F.Cu")
		(net "TEMP_ALM#")
	)
	(segment
		(start 33.651952 -169.999406)
		(end 35.252152 -169.999406)
		(width 0.1397)
		(layer "F.Cu")
		(net "TEMP_ALM#")
	)
	(segment
		(start 38.4937 -174.5615)
		(end 38.36035 -174.69485)
		(width 0.1397)
		(layer "F.Cu")
		(net "TEMP_ALM#")
	)
	(segment
		(start 28.9052 -355.5238)
		(end 28.3464 -355.5238)
		(width 0.1397)
		(layer "F.Cu")
		(net "TEMP_ALM#")
	)
	(segment
		(start 32.85109 -169.198544)
		(end 33.651952 -169.999406)
		(width 0.1397)
		(layer "F.Cu")
		(net "TEMP_ALM#")
	)
	(segment
		(start 23.02002 -152.91308)
		(end 23.48611 -153.37917)
		(width 0.1397)
		(layer "F.Cu")
		(net "TEMP_ALM#")
	)
	(segment
		(start 35.252152 -169.999406)
		(end 36.232592 -169.018966)
		(width 0.1397)
		(layer "F.Cu")
		(net "TEMP_ALM#")
	)
	(segment
		(start 31.285434 -357.232966)
		(end 30.8356 -357.6828)
		(width 0.1397)
		(layer "F.Cu")
		(net "TEMP_ALM#")
	)
	(segment
		(start 23.48611 -153.37917)
		(end 23.48611 -154.157934)
		(width 0.1397)
		(layer "F.Cu")
		(net "TEMP_ALM#")
	)
	(segment
		(start 28.3464 -356.87)
		(end 28.7147 -356.87)
		(width 0.1397)
		(layer "F.Cu")
		(net "TEMP_ALM#")
	)
	(via
		(at 38.7858 -157.175962)
		(size 0.7112)
		(drill 0.4064)
		(layers "F.Cu" "B.Cu")
		(net "TEMP_ALM#")
	)
	(via
		(at 36.232592 -169.018966)
		(size 0.5588)
		(drill 0.3048)
		(layers "F.Cu" "B.Cu")
		(net "TEMP_ALM#")
	)
	(via
		(at 38.348412 -174.69485)
		(size 0.5588)
		(drill 0.3048)
		(layers "F.Cu" "B.Cu")
		(net "TEMP_ALM#")
	)
	(via
		(at 23.02002 -152.91308)
		(size 0.7112)
		(drill 0.4064)
		(layers "F.Cu" "B.Cu")
		(net "TEMP_ALM#")
	)
	(via
		(at 37.084 -162.9156)
		(size 0.7112)
		(drill 0.3556)
		(layers "F.Cu" "B.Cu")
		(net "TEMP_ALM#")
	)
	(via
		(at 32.6898 -357.632)
		(size 0.5588)
		(drill 0.3048)
		(layers "F.Cu" "B.Cu")
		(net "TEMP_ALM#")
	)
	(segment
		(start 37.815266 -177.515266)
		(end 37.80155 -177.50155)
		(width 0.1397)
		(layer "B.Cu")
		(net "TEMP_ALM#")
	)
	(segment
		(start 42.5577 -250.907042)
		(end 42.5577 -215.89365)
		(width 0.1397)
		(layer "B.Cu")
		(net "TEMP_ALM#")
	)
	(segment
		(start 35.751262 -157.175962)
		(end 38.7858 -157.175962)
		(width 0.1397)
		(layer "B.Cu")
		(net "TEMP_ALM#")
	)
	(segment
		(start 38.7858 -157.861)
		(end 37.084 -159.5628)
		(width 0.1397)
		(layer "B.Cu")
		(net "TEMP_ALM#")
	)
	(segment
		(start 29.71165 -151.13635)
		(end 35.751262 -157.175962)
		(width 0.1397)
		(layer "B.Cu")
		(net "TEMP_ALM#")
	)
	(segment
		(start 32.6898 -278.3332)
		(end 34.899854 -276.123146)
		(width 0.1397)
		(layer "B.Cu")
		(net "TEMP_ALM#")
	)
	(segment
		(start 35.3695 -257.0607)
		(end 40.9194 -251.5108)
		(width 0.1397)
		(layer "B.Cu")
		(net "TEMP_ALM#")
	)
	(segment
		(start 34.8996 -273.33194)
		(end 34.899854 -273.331686)
		(width 0.1397)
		(layer "B.Cu")
		(net "TEMP_ALM#")
	)
	(segment
		(start 38.354 -174.689262)
		(end 38.354 -171.140374)
		(width 0.1397)
		(layer "B.Cu")
		(net "TEMP_ALM#")
	)
	(segment
		(start 38.34765 -174.695612)
		(end 38.348412 -174.69485)
		(width 0.1397)
		(layer "B.Cu")
		(net "TEMP_ALM#")
	)
	(segment
		(start 37.815266 -186.441334)
		(end 37.815266 -177.515266)
		(width 0.1397)
		(layer "B.Cu")
		(net "TEMP_ALM#")
	)
	(segment
		(start 34.899854 -274.226782)
		(end 34.8996 -274.226528)
		(width 0.1397)
		(layer "B.Cu")
		(net "TEMP_ALM#")
	)
	(segment
		(start 37.084 -159.5628)
		(end 37.084 -162.9156)
		(width 0.1397)
		(layer "B.Cu")
		(net "TEMP_ALM#")
	)
	(segment
		(start 37.7571 -186.4995)
		(end 37.815266 -186.441334)
		(width 0.1397)
		(layer "B.Cu")
		(net "TEMP_ALM#")
	)
	(segment
		(start 34.899854 -259.752846)
		(end 35.3695 -259.2832)
		(width 0.1397)
		(layer "B.Cu")
		(net "TEMP_ALM#")
	)
	(segment
		(start 34.899854 -273.331686)
		(end 34.899854 -259.752846)
		(width 0.1397)
		(layer "B.Cu")
		(net "TEMP_ALM#")
	)
	(segment
		(start 32.6898 -357.632)
		(end 32.6898 -278.3332)
		(width 0.1397)
		(layer "B.Cu")
		(net "TEMP_ALM#")
	)
	(segment
		(start 38.7858 -157.175962)
		(end 38.7858 -157.861)
		(width 0.1397)
		(layer "B.Cu")
		(net "TEMP_ALM#")
	)
	(segment
		(start 38.34765 -174.70755)
		(end 38.34765 -174.695612)
		(width 0.1397)
		(layer "B.Cu")
		(net "TEMP_ALM#")
	)
	(segment
		(start 38.354 -171.140374)
		(end 36.232592 -169.018966)
		(width 0.1397)
		(layer "B.Cu")
		(net "TEMP_ALM#")
	)
	(segment
		(start 38.348412 -174.69485)
		(end 38.354 -174.689262)
		(width 0.1397)
		(layer "B.Cu")
		(net "TEMP_ALM#")
	)
	(segment
		(start 34.899854 -276.123146)
		(end 34.899854 -274.226782)
		(width 0.1397)
		(layer "B.Cu")
		(net "TEMP_ALM#")
	)
	(segment
		(start 35.3695 -259.2832)
		(end 35.3695 -257.0607)
		(width 0.1397)
		(layer "B.Cu")
		(net "TEMP_ALM#")
	)
	(segment
		(start 36.232592 -169.018966)
		(end 37.084 -168.167558)
		(width 0.1397)
		(layer "B.Cu")
		(net "TEMP_ALM#")
	)
	(segment
		(start 24.79675 -151.13635)
		(end 29.71165 -151.13635)
		(width 0.1397)
		(layer "B.Cu")
		(net "TEMP_ALM#")
	)
	(segment
		(start 23.02002 -152.91308)
		(end 24.79675 -151.13635)
		(width 0.1397)
		(layer "B.Cu")
		(net "TEMP_ALM#")
	)
	(segment
		(start 41.953942 -251.5108)
		(end 42.5577 -250.907042)
		(width 0.1397)
		(layer "B.Cu")
		(net "TEMP_ALM#")
	)
	(segment
		(start 37.084 -168.167558)
		(end 37.084 -162.9156)
		(width 0.1397)
		(layer "B.Cu")
		(net "TEMP_ALM#")
	)
	(segment
		(start 34.8996 -274.226528)
		(end 34.8996 -273.33194)
		(width 0.1397)
		(layer "B.Cu")
		(net "TEMP_ALM#")
	)
	(segment
		(start 42.5577 -215.89365)
		(end 37.7571 -211.09305)
		(width 0.1397)
		(layer "B.Cu")
		(net "TEMP_ALM#")
	)
	(segment
		(start 37.80155 -175.25365)
		(end 38.34765 -174.70755)
		(width 0.1397)
		(layer "B.Cu")
		(net "TEMP_ALM#")
	)
	(segment
		(start 37.80155 -177.50155)
		(end 37.80155 -175.25365)
		(width 0.1397)
		(layer "B.Cu")
		(net "TEMP_ALM#")
	)
	(segment
		(start 37.7571 -211.09305)
		(end 37.7571 -186.4995)
		(width 0.1397)
		(layer "B.Cu")
		(net "TEMP_ALM#")
	)
	(segment
		(start 40.9194 -251.5108)
		(end 41.953942 -251.5108)
		(width 0.1397)
		(layer "B.Cu")
		(net "TEMP_ALM#")
	)
	(segment
		(start 23.031196 -168.394126)
		(end 23.2918 -168.133522)
		(width 0.1397)
		(layer "F.Cu")
		(net "FANIN_7")
	)
	(segment
		(start 19.6088 -178.4223)
		(end 20.8153 -178.4223)
		(width 0.1397)
		(layer "F.Cu")
		(net "FANIN_7")
	)
	(segment
		(start 19.05 -176.0474)
		(end 19.05 -177.8635)
		(width 0.1397)
		(layer "F.Cu")
		(net "FANIN_7")
	)
	(segment
		(start 19.195034 -175.902366)
		(end 19.05 -176.0474)
		(width 0.1397)
		(layer "F.Cu")
		(net "FANIN_7")
	)
	(segment
		(start 19.195034 -175.893984)
		(end 19.195034 -175.902366)
		(width 0.1397)
		(layer "F.Cu")
		(net "FANIN_7")
	)
	(segment
		(start 23.031196 -168.495218)
		(end 23.031196 -168.394126)
		(width 0.1397)
		(layer "F.Cu")
		(net "FANIN_7")
	)
	(segment
		(start 19.05 -177.8635)
		(end 19.6088 -178.4223)
		(width 0.1397)
		(layer "F.Cu")
		(net "FANIN_7")
	)
	(segment
		(start 23.2918 -167.157654)
		(end 26.12009 -164.329364)
		(width 0.1397)
		(layer "F.Cu")
		(net "FANIN_7")
	)
	(segment
		(start 23.2918 -168.133522)
		(end 23.2918 -167.157654)
		(width 0.1397)
		(layer "F.Cu")
		(net "FANIN_7")
	)
	(segment
		(start 20.8153 -178.4223)
		(end 20.828 -178.4096)
		(width 0.1397)
		(layer "F.Cu")
		(net "FANIN_7")
	)
	(segment
		(start 26.12009 -164.329364)
		(end 26.12009 -162.599116)
		(width 0.1397)
		(layer "F.Cu")
		(net "FANIN_7")
	)
	(via
		(at 23.031196 -168.495218)
		(size 0.7112)
		(drill 0.4064)
		(layers "F.Cu" "B.Cu")
		(net "FANIN_7")
	)
	(via
		(at 21.336 -171.196)
		(size 0.7112)
		(drill 0.3556)
		(layers "F.Cu" "B.Cu")
		(net "FANIN_7")
	)
	(via
		(at 19.195034 -175.893984)
		(size 0.5588)
		(drill 0.3048)
		(layers "F.Cu" "B.Cu")
		(net "FANIN_7")
	)
	(segment
		(start 23.031196 -169.094404)
		(end 23.031196 -168.495218)
		(width 0.1397)
		(layer "B.Cu")
		(net "FANIN_7")
	)
	(segment
		(start 21.336 -170.7896)
		(end 23.031196 -169.094404)
		(width 0.1397)
		(layer "B.Cu")
		(net "FANIN_7")
	)
	(segment
		(start 20.8153 -171.7167)
		(end 20.8153 -172.211492)
		(width 0.1397)
		(layer "B.Cu")
		(net "FANIN_7")
	)
	(segment
		(start 18.85315 -175.5521)
		(end 19.195034 -175.893984)
		(width 0.1397)
		(layer "B.Cu")
		(net "FANIN_7")
	)
	(segment
		(start 21.336 -171.196)
		(end 20.8153 -171.7167)
		(width 0.1397)
		(layer "B.Cu")
		(net "FANIN_7")
	)
	(segment
		(start 20.8153 -172.211492)
		(end 18.85315 -174.173642)
		(width 0.1397)
		(layer "B.Cu")
		(net "FANIN_7")
	)
	(segment
		(start 21.336 -171.196)
		(end 21.336 -170.7896)
		(width 0.1397)
		(layer "B.Cu")
		(net "FANIN_7")
	)
	(segment
		(start 18.85315 -174.173642)
		(end 18.85315 -175.5521)
		(width 0.1397)
		(layer "B.Cu")
		(net "FANIN_7")
	)
	(segment
		(start 23.3045 -165.25875)
		(end 23.3045 -165.259004)
		(width 0.1397)
		(layer "F.Cu")
		(net "FANIN_6")
	)
	(segment
		(start 15.6972 -260.35)
		(end 15.6972 -259.5499)
		(width 0.1397)
		(layer "F.Cu")
		(net "FANIN_6")
	)
	(segment
		(start 21.404072 -167.159432)
		(end 21.404072 -169.054272)
		(width 0.1397)
		(layer "F.Cu")
		(net "FANIN_6")
	)
	(segment
		(start 21.464016 -169.114216)
		(end 21.464016 -169.253662)
		(width 0.1397)
		(layer "F.Cu")
		(net "FANIN_6")
	)
	(segment
		(start 21.404072 -169.054272)
		(end 21.464016 -169.114216)
		(width 0.1397)
		(layer "F.Cu")
		(net "FANIN_6")
	)
	(segment
		(start 24.974804 -161.099246)
		(end 24.2697 -161.80435)
		(width 0.1397)
		(layer "F.Cu")
		(net "FANIN_6")
	)
	(segment
		(start 24.009604 -164.5539)
		(end 24.00935 -164.5539)
		(width 0.1397)
		(layer "F.Cu")
		(net "FANIN_6")
	)
	(segment
		(start 23.3045 -165.259004)
		(end 21.404072 -167.159432)
		(width 0.1397)
		(layer "F.Cu")
		(net "FANIN_6")
	)
	(segment
		(start 26.12009 -161.099246)
		(end 24.974804 -161.099246)
		(width 0.1397)
		(layer "F.Cu")
		(net "FANIN_6")
	)
	(segment
		(start 24.00935 -164.5539)
		(end 23.3045 -165.25875)
		(width 0.1397)
		(layer "F.Cu")
		(net "FANIN_6")
	)
	(segment
		(start 15.6972 -259.5499)
		(end 16.0147 -259.2324)
		(width 0.1397)
		(layer "F.Cu")
		(net "FANIN_6")
	)
	(segment
		(start 24.2697 -164.293804)
		(end 24.009604 -164.5539)
		(width 0.1397)
		(layer "F.Cu")
		(net "FANIN_6")
	)
	(segment
		(start 24.2697 -161.80435)
		(end 24.2697 -164.293804)
		(width 0.1397)
		(layer "F.Cu")
		(net "FANIN_6")
	)
	(segment
		(start 13.716 -260.35)
		(end 13.589 -260.477)
		(width 0.1397)
		(layer "F.Cu")
		(net "FANIN_6")
	)
	(segment
		(start 15.6972 -260.35)
		(end 13.716 -260.35)
		(width 0.1397)
		(layer "F.Cu")
		(net "FANIN_6")
	)
	(via
		(at 21.464016 -169.253662)
		(size 0.7112)
		(drill 0.4064)
		(layers "F.Cu" "B.Cu")
		(net "FANIN_6")
	)
	(via
		(at 13.589 -260.477)
		(size 0.5588)
		(drill 0.3048)
		(layers "F.Cu" "B.Cu")
		(net "FANIN_6")
	)
	(via
		(at 17.018 -230.4542)
		(size 0.7112)
		(drill 0.3556)
		(layers "F.Cu" "B.Cu")
		(net "FANIN_6")
	)
	(segment
		(start 17.018 -230.4542)
		(end 17.018 -257.340608)
		(width 0.1397)
		(layer "B.Cu")
		(net "FANIN_6")
	)
	(segment
		(start 17.96415 -175.965612)
		(end 19.58975 -177.591212)
		(width 0.1397)
		(layer "B.Cu")
		(net "FANIN_6")
	)
	(segment
		(start 18.01495 -209.98815)
		(end 18.01495 -229.45725)
		(width 0.1397)
		(layer "B.Cu")
		(net "FANIN_6")
	)
	(segment
		(start 19.1135 -172.655992)
		(end 17.96415 -173.805342)
		(width 0.1397)
		(layer "B.Cu")
		(net "FANIN_6")
	)
	(segment
		(start 19.99615 -169.544746)
		(end 19.99615 -170.37685)
		(width 0.1397)
		(layer "B.Cu")
		(net "FANIN_6")
	)
	(segment
		(start 19.99615 -170.37685)
		(end 19.1135 -171.2595)
		(width 0.1397)
		(layer "B.Cu")
		(net "FANIN_6")
	)
	(segment
		(start 17.46885 -193.70675)
		(end 17.46885 -209.44205)
		(width 0.1397)
		(layer "B.Cu")
		(net "FANIN_6")
	)
	(segment
		(start 18.01495 -229.45725)
		(end 17.018 -230.4542)
		(width 0.1397)
		(layer "B.Cu")
		(net "FANIN_6")
	)
	(segment
		(start 17.96415 -173.805342)
		(end 17.96415 -175.965612)
		(width 0.1397)
		(layer "B.Cu")
		(net "FANIN_6")
	)
	(segment
		(start 21.431504 -169.22115)
		(end 20.319746 -169.22115)
		(width 0.1397)
		(layer "B.Cu")
		(net "FANIN_6")
	)
	(segment
		(start 13.881608 -260.477)
		(end 13.589 -260.477)
		(width 0.1397)
		(layer "B.Cu")
		(net "FANIN_6")
	)
	(segment
		(start 19.1135 -171.2595)
		(end 19.1135 -172.655992)
		(width 0.1397)
		(layer "B.Cu")
		(net "FANIN_6")
	)
	(segment
		(start 21.464016 -169.253662)
		(end 21.431504 -169.22115)
		(width 0.1397)
		(layer "B.Cu")
		(net "FANIN_6")
	)
	(segment
		(start 17.018 -257.340608)
		(end 13.881608 -260.477)
		(width 0.1397)
		(layer "B.Cu")
		(net "FANIN_6")
	)
	(segment
		(start 19.58975 -191.58585)
		(end 17.46885 -193.70675)
		(width 0.1397)
		(layer "B.Cu")
		(net "FANIN_6")
	)
	(segment
		(start 17.46885 -209.44205)
		(end 18.01495 -209.98815)
		(width 0.1397)
		(layer "B.Cu")
		(net "FANIN_6")
	)
	(segment
		(start 20.319746 -169.22115)
		(end 19.99615 -169.544746)
		(width 0.1397)
		(layer "B.Cu")
		(net "FANIN_6")
	)
	(segment
		(start 19.58975 -177.591212)
		(end 19.58975 -191.58585)
		(width 0.1397)
		(layer "B.Cu")
		(net "FANIN_6")
	)
	(segment
		(start 25.1587 -164.662104)
		(end 22.597618 -167.223186)
		(width 0.1397)
		(layer "F.Cu")
		(net "FANIN_8")
	)
	(segment
		(start 22.597618 -167.223186)
		(end 22.597618 -167.576246)
		(width 0.1397)
		(layer "F.Cu")
		(net "FANIN_8")
	)
	(segment
		(start 19.558 -184.7469)
		(end 18.7071 -184.7469)
		(width 0.1397)
		(layer "F.Cu")
		(net "FANIN_8")
	)
	(segment
		(start 25.29586 -162.100006)
		(end 25.1587 -162.237166)
		(width 0.1397)
		(layer "F.Cu")
		(net "FANIN_8")
	)
	(segment
		(start 18.7071 -184.7469)
		(end 18.542 -184.912)
		(width 0.1397)
		(layer "F.Cu")
		(net "FANIN_8")
	)
	(segment
		(start 25.1587 -162.237166)
		(end 25.1587 -164.662104)
		(width 0.1397)
		(layer "F.Cu")
		(net "FANIN_8")
	)
	(segment
		(start 26.12009 -162.100006)
		(end 25.29586 -162.100006)
		(width 0.1397)
		(layer "F.Cu")
		(net "FANIN_8")
	)
	(segment
		(start 20.6883 -184.7469)
		(end 20.701 -184.7596)
		(width 0.1397)
		(layer "F.Cu")
		(net "FANIN_8")
	)
	(segment
		(start 19.558 -184.7469)
		(end 20.6883 -184.7469)
		(width 0.1397)
		(layer "F.Cu")
		(net "FANIN_8")
	)
	(via
		(at 21.3106 -167.576246)
		(size 0.7112)
		(drill 0.3556)
		(layers "F.Cu" "B.Cu")
		(net "FANIN_8")
	)
	(via
		(at 18.542 -184.912)
		(size 0.5588)
		(drill 0.3048)
		(layers "F.Cu" "B.Cu")
		(net "FANIN_8")
	)
	(via
		(at 22.597618 -167.576246)
		(size 0.7112)
		(drill 0.4064)
		(layers "F.Cu" "B.Cu")
		(net "FANIN_8")
	)
	(segment
		(start 18.542 -184.912)
		(end 18.542 -184.7596)
		(width 0.1397)
		(layer "B.Cu")
		(net "FANIN_8")
	)
	(segment
		(start 18.542 -184.7596)
		(end 16.99895 -183.21655)
		(width 0.1397)
		(layer "B.Cu")
		(net "FANIN_8")
	)
	(segment
		(start 16.99895 -183.21655)
		(end 16.99895 -173.5074)
		(width 0.1397)
		(layer "B.Cu")
		(net "FANIN_8")
	)
	(segment
		(start 16.99895 -173.5074)
		(end 18.0975 -172.40885)
		(width 0.1397)
		(layer "B.Cu")
		(net "FANIN_8")
	)
	(segment
		(start 18.0975 -172.40885)
		(end 18.0975 -169.969688)
		(width 0.1397)
		(layer "B.Cu")
		(net "FANIN_8")
	)
	(segment
		(start 20.490942 -167.576246)
		(end 21.3106 -167.576246)
		(width 0.1397)
		(layer "B.Cu")
		(net "FANIN_8")
	)
	(segment
		(start 18.0975 -169.969688)
		(end 20.490942 -167.576246)
		(width 0.1397)
		(layer "B.Cu")
		(net "FANIN_8")
	)
	(segment
		(start 22.597618 -167.576246)
		(end 21.3106 -167.576246)
		(width 0.1397)
		(layer "B.Cu")
		(net "FANIN_8")
	)
	(segment
		(start 24.7142 -164.477954)
		(end 21.956522 -167.235632)
		(width 0.1397)
		(layer "F.Cu")
		(net "FANIN_5")
	)
	(segment
		(start 25.16759 -161.599626)
		(end 24.7142 -162.053016)
		(width 0.1397)
		(layer "F.Cu")
		(net "FANIN_5")
	)
	(segment
		(start 16.6878 -253.9492)
		(end 16.3068 -253.5682)
		(width 0.1397)
		(layer "F.Cu")
		(net "FANIN_5")
	)
	(segment
		(start 21.956522 -167.235632)
		(end 21.956522 -168.364662)
		(width 0.1397)
		(layer "F.Cu")
		(net "FANIN_5")
	)
	(segment
		(start 26.12009 -161.599626)
		(end 25.16759 -161.599626)
		(width 0.1397)
		(layer "F.Cu")
		(net "FANIN_5")
	)
	(segment
		(start 24.7142 -162.053016)
		(end 24.7142 -164.477954)
		(width 0.1397)
		(layer "F.Cu")
		(net "FANIN_5")
	)
	(segment
		(start 17.4371 -253.9492)
		(end 16.6878 -253.9492)
		(width 0.1397)
		(layer "F.Cu")
		(net "FANIN_5")
	)
	(segment
		(start 15.8496 -253.111)
		(end 16.3068 -253.5682)
		(width 0.1397)
		(layer "F.Cu")
		(net "FANIN_5")
	)
	(segment
		(start 13.716 -253.111)
		(end 15.8496 -253.111)
		(width 0.1397)
		(layer "F.Cu")
		(net "FANIN_5")
	)
	(via
		(at 21.956522 -168.364662)
		(size 0.7112)
		(drill 0.4064)
		(layers "F.Cu" "B.Cu")
		(net "FANIN_5")
	)
	(via
		(at 13.716 -253.111)
		(size 0.5588)
		(drill 0.3048)
		(layers "F.Cu" "B.Cu")
		(net "FANIN_5")
	)
	(via
		(at 13.7668 -235.3818)
		(size 0.7112)
		(drill 0.3556)
		(layers "F.Cu" "B.Cu")
		(net "FANIN_5")
	)
	(segment
		(start 13.716 -253.111)
		(end 13.462 -252.857)
		(width 0.1397)
		(layer "B.Cu")
		(net "FANIN_5")
	)
	(segment
		(start 17.02435 -193.50355)
		(end 17.02435 -209.88655)
		(width 0.1397)
		(layer "B.Cu")
		(net "FANIN_5")
	)
	(segment
		(start 18.669 -171.0436)
		(end 18.669 -172.466)
		(width 0.1397)
		(layer "B.Cu")
		(net "FANIN_5")
	)
	(segment
		(start 21.956522 -168.364662)
		(end 21.919184 -168.402)
		(width 0.1397)
		(layer "B.Cu")
		(net "FANIN_5")
	)
	(segment
		(start 20.510246 -168.402)
		(end 19.5453 -169.366946)
		(width 0.1397)
		(layer "B.Cu")
		(net "FANIN_5")
	)
	(segment
		(start 17.51965 -173.61535)
		(end 17.51965 -176.149762)
		(width 0.1397)
		(layer "B.Cu")
		(net "FANIN_5")
	)
	(segment
		(start 16.2052 -230.2764)
		(end 16.2052 -232.9434)
		(width 0.1397)
		(layer "B.Cu")
		(net "FANIN_5")
	)
	(segment
		(start 17.02435 -209.88655)
		(end 17.57045 -210.43265)
		(width 0.1397)
		(layer "B.Cu")
		(net "FANIN_5")
	)
	(segment
		(start 13.462 -235.6866)
		(end 13.7668 -235.3818)
		(width 0.1397)
		(layer "B.Cu")
		(net "FANIN_5")
	)
	(segment
		(start 21.919184 -168.402)
		(end 20.510246 -168.402)
		(width 0.1397)
		(layer "B.Cu")
		(net "FANIN_5")
	)
	(segment
		(start 17.57045 -228.91115)
		(end 16.2052 -230.2764)
		(width 0.1397)
		(layer "B.Cu")
		(net "FANIN_5")
	)
	(segment
		(start 16.2052 -232.9434)
		(end 13.7668 -235.3818)
		(width 0.1397)
		(layer "B.Cu")
		(net "FANIN_5")
	)
	(segment
		(start 18.669 -172.466)
		(end 17.51965 -173.61535)
		(width 0.1397)
		(layer "B.Cu")
		(net "FANIN_5")
	)
	(segment
		(start 13.462 -252.857)
		(end 13.462 -235.6866)
		(width 0.1397)
		(layer "B.Cu")
		(net "FANIN_5")
	)
	(segment
		(start 19.5453 -169.366946)
		(end 19.5453 -170.1673)
		(width 0.1397)
		(layer "B.Cu")
		(net "FANIN_5")
	)
	(segment
		(start 19.14525 -191.38265)
		(end 17.02435 -193.50355)
		(width 0.1397)
		(layer "B.Cu")
		(net "FANIN_5")
	)
	(segment
		(start 19.5453 -170.1673)
		(end 18.669 -171.0436)
		(width 0.1397)
		(layer "B.Cu")
		(net "FANIN_5")
	)
	(segment
		(start 17.57045 -210.43265)
		(end 17.57045 -228.91115)
		(width 0.1397)
		(layer "B.Cu")
		(net "FANIN_5")
	)
	(segment
		(start 19.14525 -177.775362)
		(end 19.14525 -191.38265)
		(width 0.1397)
		(layer "B.Cu")
		(net "FANIN_5")
	)
	(segment
		(start 17.51965 -176.149762)
		(end 19.14525 -177.775362)
		(width 0.1397)
		(layer "B.Cu")
		(net "FANIN_5")
	)
	(segment
		(start 33.30829 -162.446716)
		(end 33.30829 -161.90849)
		(width 0.1397)
		(layer "F.Cu")
		(net "FANIN_4")
	)
	(segment
		(start 27.93111 -160.4772)
		(end 27.553666 -160.099756)
		(width 0.1397)
		(layer "F.Cu")
		(net "FANIN_4")
	)
	(segment
		(start 19.802094 -291.602414)
		(end 19.258026 -291.058346)
		(width 0.1397)
		(layer "F.Cu")
		(net "FANIN_4")
	)
	(segment
		(start 20.675092 -289.040062)
		(end 19.560032 -289.040062)
		(width 0.1397)
		(layer "F.Cu")
		(net "FANIN_4")
	)
	(segment
		(start 27.553666 -160.099756)
		(end 26.12009 -160.099756)
		(width 0.1397)
		(layer "F.Cu")
		(net "FANIN_4")
	)
	(segment
		(start 19.258026 -291.058346)
		(end 19.258026 -289.33902)
		(width 0.1397)
		(layer "F.Cu")
		(net "FANIN_4")
	)
	(segment
		(start 19.886168 -291.602414)
		(end 19.802094 -291.602414)
		(width 0.1397)
		(layer "F.Cu")
		(net "FANIN_4")
	)
	(segment
		(start 19.560032 -289.040062)
		(end 19.558508 -289.038538)
		(width 0.1397)
		(layer "F.Cu")
		(net "FANIN_4")
	)
	(segment
		(start 33.30829 -161.90849)
		(end 31.877 -160.4772)
		(width 0.1397)
		(layer "F.Cu")
		(net "FANIN_4")
	)
	(segment
		(start 31.877 -160.4772)
		(end 27.93111 -160.4772)
		(width 0.1397)
		(layer "F.Cu")
		(net "FANIN_4")
	)
	(segment
		(start 19.258026 -289.33902)
		(end 19.558508 -289.038538)
		(width 0.1397)
		(layer "F.Cu")
		(net "FANIN_4")
	)
	(via
		(at 33.55594 -172.301662)
		(size 0.7112)
		(drill 0.3556)
		(layers "F.Cu" "B.Cu")
		(net "FANIN_4")
	)
	(via
		(at 19.886168 -291.602414)
		(size 0.7112)
		(drill 0.4064)
		(layers "F.Cu" "B.Cu")
		(net "FANIN_4")
	)
	(via
		(at 33.30829 -162.446716)
		(size 0.5588)
		(drill 0.3048)
		(layers "F.Cu" "B.Cu")
		(net "FANIN_4")
	)
	(segment
		(start 38.89375 -250.05665)
		(end 38.89375 -244.82425)
		(width 0.1397)
		(layer "B.Cu")
		(net "FANIN_4")
	)
	(segment
		(start 34.37255 -173.118272)
		(end 33.55594 -172.301662)
		(width 0.1397)
		(layer "B.Cu")
		(net "FANIN_4")
	)
	(segment
		(start 38.43655 -214.96655)
		(end 34.37255 -210.90255)
		(width 0.1397)
		(layer "B.Cu")
		(net "FANIN_4")
	)
	(segment
		(start 32.893 -258.2164)
		(end 32.893 -256.0574)
		(width 0.1397)
		(layer "B.Cu")
		(net "FANIN_4")
	)
	(segment
		(start 21.463 -290.025582)
		(end 21.463 -286.004)
		(width 0.1397)
		(layer "B.Cu")
		(net "FANIN_4")
	)
	(segment
		(start 33.30829 -162.446716)
		(end 34.25825 -163.396676)
		(width 0.1397)
		(layer "B.Cu")
		(net "FANIN_4")
	)
	(segment
		(start 33.247076 -171.981876)
		(end 33.55594 -172.29074)
		(width 0.1397)
		(layer "B.Cu")
		(net "FANIN_4")
	)
	(segment
		(start 34.25825 -163.396676)
		(end 34.25825 -167.54475)
		(width 0.1397)
		(layer "B.Cu")
		(net "FANIN_4")
	)
	(segment
		(start 33.247076 -168.555924)
		(end 33.247076 -171.981876)
		(width 0.1397)
		(layer "B.Cu")
		(net "FANIN_4")
	)
	(segment
		(start 34.37255 -210.90255)
		(end 34.37255 -173.118272)
		(width 0.1397)
		(layer "B.Cu")
		(net "FANIN_4")
	)
	(segment
		(start 38.43655 -239.243108)
		(end 38.43655 -214.96655)
		(width 0.1397)
		(layer "B.Cu")
		(net "FANIN_4")
	)
	(segment
		(start 32.6771 -272.41119)
		(end 32.677354 -272.410936)
		(width 0.1397)
		(layer "B.Cu")
		(net "FANIN_4")
	)
	(segment
		(start 19.886168 -291.602414)
		(end 21.463 -290.025582)
		(width 0.1397)
		(layer "B.Cu")
		(net "FANIN_4")
	)
	(segment
		(start 32.6771 -274.7899)
		(end 32.6771 -272.41119)
		(width 0.1397)
		(layer "B.Cu")
		(net "FANIN_4")
	)
	(segment
		(start 32.677354 -272.410936)
		(end 32.677354 -258.432046)
		(width 0.1397)
		(layer "B.Cu")
		(net "FANIN_4")
	)
	(segment
		(start 39.751 -243.967)
		(end 39.751 -240.557558)
		(width 0.1397)
		(layer "B.Cu")
		(net "FANIN_4")
	)
	(segment
		(start 32.893 -256.0574)
		(end 38.89375 -250.05665)
		(width 0.1397)
		(layer "B.Cu")
		(net "FANIN_4")
	)
	(segment
		(start 34.25825 -167.54475)
		(end 33.247076 -168.555924)
		(width 0.1397)
		(layer "B.Cu")
		(net "FANIN_4")
	)
	(segment
		(start 38.89375 -244.82425)
		(end 39.751 -243.967)
		(width 0.1397)
		(layer "B.Cu")
		(net "FANIN_4")
	)
	(segment
		(start 39.751 -240.557558)
		(end 38.43655 -239.243108)
		(width 0.1397)
		(layer "B.Cu")
		(net "FANIN_4")
	)
	(segment
		(start 21.463 -286.004)
		(end 32.6771 -274.7899)
		(width 0.1397)
		(layer "B.Cu")
		(net "FANIN_4")
	)
	(segment
		(start 32.677354 -258.432046)
		(end 32.893 -258.2164)
		(width 0.1397)
		(layer "B.Cu")
		(net "FANIN_4")
	)
	(segment
		(start 33.55594 -172.29074)
		(end 33.55594 -172.301662)
		(width 0.1397)
		(layer "B.Cu")
		(net "FANIN_4")
	)
	(segment
		(start 26.12009 -160.600136)
		(end 24.845264 -160.600136)
		(width 0.1397)
		(layer "F.Cu")
		(net "FANIN_3")
	)
	(segment
		(start 17.094708 -288.746692)
		(end 16.648938 -289.192462)
		(width 0.1397)
		(layer "F.Cu")
		(net "FANIN_3")
	)
	(segment
		(start 24.845264 -160.600136)
		(end 23.8252 -161.6202)
		(width 0.1397)
		(layer "F.Cu")
		(net "FANIN_3")
	)
	(segment
		(start 16.053308 -289.191446)
		(end 16.053308 -288.073338)
		(width 0.1397)
		(layer "F.Cu")
		(net "FANIN_3")
	)
	(segment
		(start 16.648938 -289.192462)
		(end 16.052292 -289.192462)
		(width 0.1397)
		(layer "F.Cu")
		(net "FANIN_3")
	)
	(segment
		(start 20.5994 -167.3352)
		(end 20.5994 -169.7228)
		(width 0.1397)
		(layer "F.Cu")
		(net "FANIN_3")
	)
	(segment
		(start 16.052292 -289.192462)
		(end 16.053308 -289.191446)
		(width 0.1397)
		(layer "F.Cu")
		(net "FANIN_3")
	)
	(segment
		(start 23.8252 -161.6202)
		(end 23.8252 -164.1094)
		(width 0.1397)
		(layer "F.Cu")
		(net "FANIN_3")
	)
	(segment
		(start 17.094708 -287.90646)
		(end 17.094708 -288.746692)
		(width 0.1397)
		(layer "F.Cu")
		(net "FANIN_3")
	)
	(segment
		(start 23.8252 -164.1094)
		(end 20.5994 -167.3352)
		(width 0.1397)
		(layer "F.Cu")
		(net "FANIN_3")
	)
	(segment
		(start 20.5994 -169.7228)
		(end 20.5486 -169.7736)
		(width 0.1397)
		(layer "F.Cu")
		(net "FANIN_3")
	)
	(via
		(at 20.066 -171.577)
		(size 0.7112)
		(drill 0.3556)
		(layers "F.Cu" "B.Cu")
		(net "FANIN_3")
	)
	(via
		(at 17.094708 -287.90646)
		(size 0.7112)
		(drill 0.4064)
		(layers "F.Cu" "B.Cu")
		(net "FANIN_3")
	)
	(via
		(at 20.5486 -169.7736)
		(size 0.7112)
		(drill 0.4064)
		(layers "F.Cu" "B.Cu")
		(net "FANIN_3")
	)
	(segment
		(start 17.91335 -209.22615)
		(end 17.91335 -194.11315)
		(width 0.1397)
		(layer "B.Cu")
		(net "FANIN_3")
	)
	(segment
		(start 20.413726 -191.612774)
		(end 20.413726 -177.052732)
		(width 0.1397)
		(layer "B.Cu")
		(net "FANIN_3")
	)
	(segment
		(start 20.066 -172.332142)
		(end 20.066 -171.577)
		(width 0.1397)
		(layer "B.Cu")
		(net "FANIN_3")
	)
	(segment
		(start 20.134834 -176.77384)
		(end 19.401282 -176.77384)
		(width 0.1397)
		(layer "B.Cu")
		(net "FANIN_3")
	)
	(segment
		(start 19.401282 -176.77384)
		(end 18.40865 -175.781208)
		(width 0.1397)
		(layer "B.Cu")
		(net "FANIN_3")
	)
	(segment
		(start 18.40865 -175.781208)
		(end 18.40865 -173.989492)
		(width 0.1397)
		(layer "B.Cu")
		(net "FANIN_3")
	)
	(segment
		(start 18.45945 -286.541718)
		(end 18.45945 -209.77225)
		(width 0.1397)
		(layer "B.Cu")
		(net "FANIN_3")
	)
	(segment
		(start 20.5486 -171.0944)
		(end 20.066 -171.577)
		(width 0.1397)
		(layer "B.Cu")
		(net "FANIN_3")
	)
	(segment
		(start 18.40865 -173.989492)
		(end 20.066 -172.332142)
		(width 0.1397)
		(layer "B.Cu")
		(net "FANIN_3")
	)
	(segment
		(start 18.45945 -209.77225)
		(end 17.91335 -209.22615)
		(width 0.1397)
		(layer "B.Cu")
		(net "FANIN_3")
	)
	(segment
		(start 17.91335 -194.11315)
		(end 20.413726 -191.612774)
		(width 0.1397)
		(layer "B.Cu")
		(net "FANIN_3")
	)
	(segment
		(start 17.094708 -287.90646)
		(end 18.45945 -286.541718)
		(width 0.1397)
		(layer "B.Cu")
		(net "FANIN_3")
	)
	(segment
		(start 20.5486 -169.7736)
		(end 20.5486 -171.0944)
		(width 0.1397)
		(layer "B.Cu")
		(net "FANIN_3")
	)
	(segment
		(start 20.413726 -177.052732)
		(end 20.134834 -176.77384)
		(width 0.1397)
		(layer "B.Cu")
		(net "FANIN_3")
	)
	(segment
		(start 35.2806 -166.1668)
		(end 33.8582 -166.1668)
		(width 0.1397)
		(layer "F.Cu")
		(net "FANIN_2")
	)
	(segment
		(start 33.8582 -166.1668)
		(end 32.61233 -164.92093)
		(width 0.1397)
		(layer "F.Cu")
		(net "FANIN_2")
	)
	(segment
		(start 32.61233 -164.92093)
		(end 32.61233 -164.091366)
		(width 0.1397)
		(layer "F.Cu")
		(net "FANIN_2")
	)
	(segment
		(start 13.843 -448.2338)
		(end 13.8303 -448.2338)
		(width 0.1397)
		(layer "F.Cu")
		(net "FANIN_2")
	)
	(segment
		(start 12.4079 -450.2785)
		(end 12.4079 -449.6562)
		(width 0.1397)
		(layer "F.Cu")
		(net "FANIN_2")
	)
	(segment
		(start 35.3568 -166.0906)
		(end 35.2806 -166.1668)
		(width 0.1397)
		(layer "F.Cu")
		(net "FANIN_2")
	)
	(segment
		(start 13.8303 -448.2338)
		(end 12.5349 -449.5292)
		(width 0.1397)
		(layer "F.Cu")
		(net "FANIN_2")
	)
	(segment
		(start 12.4079 -449.6562)
		(end 12.5349 -449.5292)
		(width 0.1397)
		(layer "F.Cu")
		(net "FANIN_2")
	)
	(segment
		(start 11.5062 -451.1802)
		(end 12.4079 -450.2785)
		(width 0.1397)
		(layer "F.Cu")
		(net "FANIN_2")
	)
	(via
		(at 36.0172 -171.7802)
		(size 0.7112)
		(drill 0.3556)
		(layers "F.Cu" "B.Cu")
		(net "FANIN_2")
	)
	(via
		(at 35.3568 -166.0906)
		(size 0.5588)
		(drill 0.3048)
		(layers "F.Cu" "B.Cu")
		(net "FANIN_2")
	)
	(via
		(at 11.5062 -451.1802)
		(size 0.5588)
		(drill 0.3048)
		(layers "F.Cu" "B.Cu")
		(net "FANIN_2")
	)
	(segment
		(start 39.33825 -214.5792)
		(end 39.33698 -214.5792)
		(width 0.1397)
		(layer "B.Cu")
		(net "FANIN_2")
	)
	(segment
		(start 33.566354 -259.041646)
		(end 34.0106 -258.5974)
		(width 0.1397)
		(layer "B.Cu")
		(net "FANIN_2")
	)
	(segment
		(start 9.7282 -449.4022)
		(end 9.271 -449.4022)
		(width 0.1397)
		(layer "B.Cu")
		(net "FANIN_2")
	)
	(segment
		(start 40.4114 -246.4308)
		(end 41.1607 -245.6815)
		(width 0.1397)
		(layer "B.Cu")
		(net "FANIN_2")
	)
	(segment
		(start 9.271 -449.4022)
		(end 6.337554 -446.468754)
		(width 0.1397)
		(layer "B.Cu")
		(net "FANIN_2")
	)
	(segment
		(start 5.421884 -380.556516)
		(end 7.44855 -378.52985)
		(width 0.1397)
		(layer "B.Cu")
		(net "FANIN_2")
	)
	(segment
		(start 10.7188 -348.996)
		(end 21.209 -338.5058)
		(width 0.1397)
		(layer "B.Cu")
		(net "FANIN_2")
	)
	(segment
		(start 34.791142 -170.554142)
		(end 36.0172 -171.7802)
		(width 0.1397)
		(layer "B.Cu")
		(net "FANIN_2")
	)
	(segment
		(start 11.5062 -451.1802)
		(end 9.7282 -449.4022)
		(width 0.1397)
		(layer "B.Cu")
		(net "FANIN_2")
	)
	(segment
		(start 7.44855 -378.52985)
		(end 7.44855 -366.281208)
		(width 0.1397)
		(layer "B.Cu")
		(net "FANIN_2")
	)
	(segment
		(start 36.0172 -173.609)
		(end 36.0172 -171.7802)
		(width 0.1397)
		(layer "B.Cu")
		(net "FANIN_2")
	)
	(segment
		(start 39.33698 -214.5792)
		(end 35.615626 -210.857846)
		(width 0.1397)
		(layer "B.Cu")
		(net "FANIN_2")
	)
	(segment
		(start 40.4114 -249.8852)
		(end 40.4114 -246.4308)
		(width 0.1397)
		(layer "B.Cu")
		(net "FANIN_2")
	)
	(segment
		(start 35.3568 -167.9448)
		(end 34.791142 -168.510458)
		(width 0.1397)
		(layer "B.Cu")
		(net "FANIN_2")
	)
	(segment
		(start 34.0106 -258.5974)
		(end 34.0106 -256.286)
		(width 0.1397)
		(layer "B.Cu")
		(net "FANIN_2")
	)
	(segment
		(start 6.337554 -446.468754)
		(end 6.337554 -416.039046)
		(width 0.1397)
		(layer "B.Cu")
		(net "FANIN_2")
	)
	(segment
		(start 35.615626 -210.857846)
		(end 35.615626 -174.010574)
		(width 0.1397)
		(layer "B.Cu")
		(net "FANIN_2")
	)
	(segment
		(start 10.222484 -363.507274)
		(end 10.222484 -358.839516)
		(width 0.1397)
		(layer "B.Cu")
		(net "FANIN_2")
	)
	(segment
		(start 21.209 -338.5058)
		(end 21.209 -291.973)
		(width 0.1397)
		(layer "B.Cu")
		(net "FANIN_2")
	)
	(segment
		(start 22.479 -290.703)
		(end 22.479 -286.3342)
		(width 0.1397)
		(layer "B.Cu")
		(net "FANIN_2")
	)
	(segment
		(start 10.222484 -358.839516)
		(end 10.7188 -358.3432)
		(width 0.1397)
		(layer "B.Cu")
		(net "FANIN_2")
	)
	(segment
		(start 33.566354 -272.779236)
		(end 33.566354 -259.041646)
		(width 0.1397)
		(layer "B.Cu")
		(net "FANIN_2")
	)
	(segment
		(start 41.1607 -216.40165)
		(end 39.33825 -214.5792)
		(width 0.1397)
		(layer "B.Cu")
		(net "FANIN_2")
	)
	(segment
		(start 10.7188 -358.3432)
		(end 10.7188 -348.996)
		(width 0.1397)
		(layer "B.Cu")
		(net "FANIN_2")
	)
	(segment
		(start 33.5661 -272.77949)
		(end 33.566354 -272.779236)
		(width 0.1397)
		(layer "B.Cu")
		(net "FANIN_2")
	)
	(segment
		(start 41.1607 -245.6815)
		(end 41.1607 -216.40165)
		(width 0.1397)
		(layer "B.Cu")
		(net "FANIN_2")
	)
	(segment
		(start 21.209 -291.973)
		(end 22.479 -290.703)
		(width 0.1397)
		(layer "B.Cu")
		(net "FANIN_2")
	)
	(segment
		(start 34.0106 -256.286)
		(end 40.4114 -249.8852)
		(width 0.1397)
		(layer "B.Cu")
		(net "FANIN_2")
	)
	(segment
		(start 7.44855 -366.281208)
		(end 10.222484 -363.507274)
		(width 0.1397)
		(layer "B.Cu")
		(net "FANIN_2")
	)
	(segment
		(start 34.791142 -168.510458)
		(end 34.791142 -170.554142)
		(width 0.1397)
		(layer "B.Cu")
		(net "FANIN_2")
	)
	(segment
		(start 5.421884 -415.123376)
		(end 5.421884 -380.556516)
		(width 0.1397)
		(layer "B.Cu")
		(net "FANIN_2")
	)
	(segment
		(start 35.3568 -166.0906)
		(end 35.3568 -167.9448)
		(width 0.1397)
		(layer "B.Cu")
		(net "FANIN_2")
	)
	(segment
		(start 35.615626 -174.010574)
		(end 36.0172 -173.609)
		(width 0.1397)
		(layer "B.Cu")
		(net "FANIN_2")
	)
	(segment
		(start 33.5661 -275.2471)
		(end 33.5661 -272.77949)
		(width 0.1397)
		(layer "B.Cu")
		(net "FANIN_2")
	)
	(segment
		(start 6.337554 -416.039046)
		(end 5.421884 -415.123376)
		(width 0.1397)
		(layer "B.Cu")
		(net "FANIN_2")
	)
	(segment
		(start 22.479 -286.3342)
		(end 33.5661 -275.2471)
		(width 0.1397)
		(layer "B.Cu")
		(net "FANIN_2")
	)
	(segment
		(start 33.11144 -164.78504)
		(end 33.11144 -164.091366)
		(width 0.1397)
		(layer "F.Cu")
		(net "FANIN_1")
	)
	(segment
		(start 7.0612 -449.5546)
		(end 6.0071 -449.5546)
		(width 0.1397)
		(layer "F.Cu")
		(net "FANIN_1")
	)
	(segment
		(start 35.2806 -165.1254)
		(end 35.204146 -165.201854)
		(width 0.1397)
		(layer "F.Cu")
		(net "FANIN_1")
	)
	(segment
		(start 7.0612 -449.5546)
		(end 7.0612 -448.7164)
		(width 0.1397)
		(layer "F.Cu")
		(net "FANIN_1")
	)
	(segment
		(start 7.0612 -448.7164)
		(end 6.35 -448.0052)
		(width 0.1397)
		(layer "F.Cu")
		(net "FANIN_1")
	)
	(segment
		(start 35.204146 -165.201854)
		(end 33.528254 -165.201854)
		(width 0.1397)
		(layer "F.Cu")
		(net "FANIN_1")
	)
	(segment
		(start 33.528254 -165.201854)
		(end 33.11144 -164.78504)
		(width 0.1397)
		(layer "F.Cu")
		(net "FANIN_1")
	)
	(segment
		(start 6.0071 -449.5546)
		(end 5.9309 -449.4784)
		(width 0.1397)
		(layer "F.Cu")
		(net "FANIN_1")
	)
	(via
		(at 34.925 -173.355)
		(size 0.7112)
		(drill 0.3556)
		(layers "F.Cu" "B.Cu")
		(net "FANIN_1")
	)
	(via
		(at 6.35 -448.0052)
		(size 0.5588)
		(drill 0.3048)
		(layers "F.Cu" "B.Cu")
		(net "FANIN_1")
	)
	(via
		(at 35.2806 -165.1254)
		(size 0.5588)
		(drill 0.3048)
		(layers "F.Cu" "B.Cu")
		(net "FANIN_1")
	)
	(segment
		(start 39.2176 -215.1126)
		(end 40.7162 -216.6112)
		(width 0.1397)
		(layer "B.Cu")
		(net "FANIN_1")
	)
	(segment
		(start 9.3218 -349.5802)
		(end 9.3218 -358.1654)
		(width 0.1397)
		(layer "B.Cu")
		(net "FANIN_1")
	)
	(segment
		(start 20.5486 -291.7444)
		(end 20.5486 -338.3534)
		(width 0.1397)
		(layer "B.Cu")
		(net "FANIN_1")
	)
	(segment
		(start 33.121854 -272.595086)
		(end 33.1216 -272.59534)
		(width 0.1397)
		(layer "B.Cu")
		(net "FANIN_1")
	)
	(segment
		(start 35.2806 -165.1254)
		(end 34.8742 -165.5318)
		(width 0.1397)
		(layer "B.Cu")
		(net "FANIN_1")
	)
	(segment
		(start 33.71215 -170.11015)
		(end 34.925 -171.323)
		(width 0.1397)
		(layer "B.Cu")
		(net "FANIN_1")
	)
	(segment
		(start 21.971 -290.322)
		(end 20.5486 -291.7444)
		(width 0.1397)
		(layer "B.Cu")
		(net "FANIN_1")
	)
	(segment
		(start 9.777984 -363.2962)
		(end 7.00405 -366.070134)
		(width 0.1397)
		(layer "B.Cu")
		(net "FANIN_1")
	)
	(segment
		(start 34.925 -171.323)
		(end 34.925 -173.355)
		(width 0.1397)
		(layer "B.Cu")
		(net "FANIN_1")
	)
	(segment
		(start 39.1668 -215.0364)
		(end 39.2176 -215.0872)
		(width 0.1397)
		(layer "B.Cu")
		(net "FANIN_1")
	)
	(segment
		(start 39.9034 -245.9482)
		(end 39.9034 -249.7074)
		(width 0.1397)
		(layer "B.Cu")
		(net "FANIN_1")
	)
	(segment
		(start 4.977384 -415.56813)
		(end 5.8928 -416.483546)
		(width 0.1397)
		(layer "B.Cu")
		(net "FANIN_1")
	)
	(segment
		(start 40.7162 -245.1354)
		(end 39.9034 -245.9482)
		(width 0.1397)
		(layer "B.Cu")
		(net "FANIN_1")
	)
	(segment
		(start 33.464246 -256.146554)
		(end 33.464246 -258.3942)
		(width 0.1397)
		(layer "B.Cu")
		(net "FANIN_1")
	)
	(segment
		(start 34.8742 -167.5638)
		(end 33.71215 -168.72585)
		(width 0.1397)
		(layer "B.Cu")
		(net "FANIN_1")
	)
	(segment
		(start 5.8928 -416.483546)
		(end 5.8928 -447.548)
		(width 0.1397)
		(layer "B.Cu")
		(net "FANIN_1")
	)
	(segment
		(start 39.2176 -215.0872)
		(end 39.2176 -215.1126)
		(width 0.1397)
		(layer "B.Cu")
		(net "FANIN_1")
	)
	(segment
		(start 39.9034 -249.7074)
		(end 33.464246 -256.146554)
		(width 0.1397)
		(layer "B.Cu")
		(net "FANIN_1")
	)
	(segment
		(start 21.971 -286.131)
		(end 21.971 -290.322)
		(width 0.1397)
		(layer "B.Cu")
		(net "FANIN_1")
	)
	(segment
		(start 39.1414 -215.0364)
		(end 39.1668 -215.0364)
		(width 0.1397)
		(layer "B.Cu")
		(net "FANIN_1")
	)
	(segment
		(start 7.00405 -378.10821)
		(end 4.977384 -380.134876)
		(width 0.1397)
		(layer "B.Cu")
		(net "FANIN_1")
	)
	(segment
		(start 34.8742 -165.5318)
		(end 34.8742 -167.5638)
		(width 0.1397)
		(layer "B.Cu")
		(net "FANIN_1")
	)
	(segment
		(start 7.00405 -366.070134)
		(end 7.00405 -378.10821)
		(width 0.1397)
		(layer "B.Cu")
		(net "FANIN_1")
	)
	(segment
		(start 40.7162 -216.6112)
		(end 40.7162 -245.1354)
		(width 0.1397)
		(layer "B.Cu")
		(net "FANIN_1")
	)
	(segment
		(start 35.02025 -173.45025)
		(end 35.02025 -210.91525)
		(width 0.1397)
		(layer "B.Cu")
		(net "FANIN_1")
	)
	(segment
		(start 33.1216 -274.9804)
		(end 21.971 -286.131)
		(width 0.1397)
		(layer "B.Cu")
		(net "FANIN_1")
	)
	(segment
		(start 33.464246 -258.3942)
		(end 33.121854 -258.736592)
		(width 0.1397)
		(layer "B.Cu")
		(net "FANIN_1")
	)
	(segment
		(start 34.925 -173.355)
		(end 35.02025 -173.45025)
		(width 0.1397)
		(layer "B.Cu")
		(net "FANIN_1")
	)
	(segment
		(start 35.02025 -210.91525)
		(end 39.1414 -215.0364)
		(width 0.1397)
		(layer "B.Cu")
		(net "FANIN_1")
	)
	(segment
		(start 33.71215 -168.72585)
		(end 33.71215 -170.11015)
		(width 0.1397)
		(layer "B.Cu")
		(net "FANIN_1")
	)
	(segment
		(start 33.121854 -258.736592)
		(end 33.121854 -272.595086)
		(width 0.1397)
		(layer "B.Cu")
		(net "FANIN_1")
	)
	(segment
		(start 5.8928 -447.548)
		(end 6.35 -448.0052)
		(width 0.1397)
		(layer "B.Cu")
		(net "FANIN_1")
	)
	(segment
		(start 33.1216 -272.59534)
		(end 33.1216 -274.9804)
		(width 0.1397)
		(layer "B.Cu")
		(net "FANIN_1")
	)
	(segment
		(start 20.5486 -338.3534)
		(end 9.3218 -349.5802)
		(width 0.1397)
		(layer "B.Cu")
		(net "FANIN_1")
	)
	(segment
		(start 4.977384 -380.134876)
		(end 4.977384 -415.56813)
		(width 0.1397)
		(layer "B.Cu")
		(net "FANIN_1")
	)
	(segment
		(start 9.777984 -358.621584)
		(end 9.777984 -363.2962)
		(width 0.1397)
		(layer "B.Cu")
		(net "FANIN_1")
	)
	(segment
		(start 9.3218 -358.1654)
		(end 9.777984 -358.621584)
		(width 0.1397)
		(layer "B.Cu")
		(net "FANIN_1")
	)
	(zone
		(net "GND")
		(layer "F.Cu")
		(hatch none 0.5)
		(connect_pads
			(clearance 0.5)
		)
		(min_thickness 0.25)
		(fill yes
			(thermal_gap 0.5)
			(thermal_bridge_width 0.5)
			(island_removal_mode 0)
		)
		(polygon
			(pts
				(xy 18.288 -274.701) (xy 16.129 -274.701) (xy 15.113 -275.717) (xy 15.113 -282.448) (xy 15.494 -282.829)
				(xy 17.78 -282.829) (xy 18.669 -281.94) (xy 18.669 -275.082)
			)
		)
	)
	(zone
		(net "P3V3_LX")
		(layer "F.Cu")
		(hatch none 0.5)
		(connect_pads
			(clearance 0.5)
		)
		(min_thickness 0.25)
		(fill yes
			(thermal_gap 0.5)
			(thermal_bridge_width 0.5)
			(island_removal_mode 0)
		)
		(polygon
			(pts
				(xy 18.0594 -239.5728) (xy 15.0876 -239.5728) (xy 14.859 -239.8014) (xy 14.859 -246.253) (xy 15.3797 -246.7737)
				(xy 17.3609 -246.7737) (xy 17.907 -247.3198) (xy 18.288 -247.3198) (xy 18.288 -247.2944) (xy 18.542 -247.2944)
				(xy 18.542 -247.3198) (xy 20.1676 -247.3198) (xy 20.2057 -247.2817) (xy 20.2057 -245.2243) (xy 18.4912 -243.5098)
				(xy 18.4912 -240.0046)
			)
		)
	)
	(zone
		(layer "F.Cu")
		(hatch none 0.5)
		(connect_pads
			(clearance 0)
		)
		(min_thickness 0.25)
		(keepout
			(tracks allowed)
			(vias allowed)
			(pads allowed)
			(copperpour allowed)
			(footprints not_allowed)
		)
		(placement
			(enabled no)
			(sheetname "")
		)
		(fill
			(thermal_gap 0.5)
			(thermal_bridge_width 0.5)
			(island_removal_mode 0)
		)
		(polygon
			(pts
				(arc
					(start 45.500036 -298.99991)
					(mid 41.500044 -294.999918)
					(end 45.500036 -290.999926)
				)
				(arc
					(start 45.500036 -290.999926)
					(mid 49.500028 -294.999918)
					(end 45.500036 -298.99991)
				)
			)
		)
	)
	(zone
		(net "GND")
		(layer "F.Cu")
		(hatch none 0.5)
		(connect_pads
			(clearance 0.5)
		)
		(min_thickness 0.25)
		(fill yes
			(thermal_gap 0.5)
			(thermal_bridge_width 0.5)
			(island_removal_mode 0)
		)
		(polygon
			(pts
				(xy 24.511 -246.507) (xy 23.622 -246.507) (xy 23.495 -246.634) (xy 23.495 -247.523) (xy 23.368 -247.65)
				(xy 21.59 -247.65) (xy 21.59 -246.761) (xy 21.463 -246.634) (xy 20.955 -246.634) (xy 20.828 -246.761)
				(xy 20.828 -249.047) (xy 20.955 -249.174) (xy 21.463 -249.174) (xy 21.717 -248.92) (xy 21.717 -248.412)
				(xy 21.844 -248.285) (xy 23.114 -248.285) (xy 23.368 -248.539) (xy 24.511 -248.539) (xy 24.638 -248.412)
				(xy 24.638 -246.634)
			)
		)
	)
	(zone
		(net "GND")
		(layer "F.Cu")
		(hatch none 0.5)
		(connect_pads
			(clearance 0.5)
		)
		(min_thickness 0.25)
		(fill yes
			(thermal_gap 0.5)
			(thermal_bridge_width 0.5)
			(island_removal_mode 0)
		)
		(polygon
			(pts
				(xy 27.178 -147.701) (xy 25.273 -147.701) (xy 24.003 -148.971) (xy 24.003 -150.114) (xy 24.13 -150.241)
				(xy 24.892 -150.241) (xy 25.908 -151.257) (xy 26.543 -151.257) (xy 28.067 -149.733) (xy 28.067 -148.59)
			)
		)
	)
	(zone
		(layer "F.Cu")
		(hatch none 0.5)
		(connect_pads
			(clearance 0)
		)
		(min_thickness 0.25)
		(keepout
			(tracks allowed)
			(vias allowed)
			(pads allowed)
			(copperpour allowed)
			(footprints not_allowed)
		)
		(placement
			(enabled no)
			(sheetname "")
		)
		(fill
			(thermal_gap 0.5)
			(thermal_bridge_width 0.5)
			(island_removal_mode 0)
		)
		(polygon
			(pts
				(arc
					(start 45.500036 -290.999926)
					(mid 49.500028 -294.999918)
					(end 45.500036 -298.99991)
				)
				(arc
					(start 45.500036 -298.99991)
					(mid 41.500044 -294.999918)
					(end 45.500036 -290.999926)
				)
			)
		)
	)
	(zone
		(layer "F.Cu")
		(hatch none 0.5)
		(connect_pads
			(clearance 0)
		)
		(min_thickness 0.25)
		(keepout
			(tracks allowed)
			(vias allowed)
			(pads allowed)
			(copperpour allowed)
			(footprints allowed)
		)
		(placement
			(enabled no)
			(sheetname "")
		)
		(fill
			(thermal_gap 0.5)
			(thermal_bridge_width 0.5)
			(island_removal_mode 0)
		)
		(polygon
			(pts
				(xy 34.544 -162.814) (xy 34.544 -161.29) (xy 36.83 -161.29) (xy 36.83 -162.814)
			)
		)
	)
	(zone
		(net "GND")
		(layer "F.Cu")
		(hatch none 0.5)
		(connect_pads
			(clearance 0.5)
		)
		(min_thickness 0.25)
		(fill yes
			(thermal_gap 0.5)
			(thermal_bridge_width 0.5)
			(island_removal_mode 0)
		)
		(polygon
			(pts
				(xy 13.462 -143.002) (xy 7.493 -143.002) (xy 7.239 -143.256) (xy 7.239 -143.891) (xy 7.62 -144.272)
				(xy 8.636 -144.272) (xy 9.017 -144.653) (xy 9.017 -145.288) (xy 9.779 -146.05) (xy 15.494 -146.05)
				(xy 15.748 -145.796) (xy 15.748 -145.288)
			)
		)
	)
	(zone
		(layer "F.Cu")
		(hatch none 0.5)
		(connect_pads
			(clearance 0)
		)
		(min_thickness 0.25)
		(keepout
			(tracks allowed)
			(vias allowed)
			(pads allowed)
			(copperpour allowed)
			(footprints not_allowed)
		)
		(placement
			(enabled no)
			(sheetname "")
		)
		(fill
			(thermal_gap 0.5)
			(thermal_bridge_width 0.5)
			(island_removal_mode 0)
		)
		(polygon
			(pts
				(xy 8.999982 -351.199958) (xy 38.699948 -351.199958) (xy 38.699948 -345.849956)
				(arc
					(start 44.04995 -345.849956)
					(mid 49.954289 -343.404299)
					(end 52.399946 -337.49996)
				)
				(arc
					(start 52.399946 -337.49996)
					(mid 49.954289 -331.595621)
					(end 44.04995 -329.149964)
				)
				(xy 38.699948 -329.149964) (xy 38.699948 -323.799962) (xy 8.999982 -323.799962)
			)
		)
	)
	(zone
		(net "P12V")
		(layer "F.Cu")
		(hatch none 0.5)
		(connect_pads
			(clearance 0.5)
		)
		(min_thickness 0.25)
		(fill yes
			(thermal_gap 0.5)
			(thermal_bridge_width 0.5)
			(island_removal_mode 0)
		)
		(polygon
			(pts
				(xy 24.003 -254.635) (xy 18.161 -254.635) (xy 17.907 -254.889) (xy 17.907 -257.683) (xy 18.796 -258.572)
				(xy 18.796 -282.7528) (xy 18.288 -283.2608) (xy 16.1544 -283.2608) (xy 15.8242 -283.591) (xy 15.8242 -284.7848)
				(xy 15.875 -284.8356) (xy 16.6116 -284.8356) (xy 16.891 -285.115) (xy 16.891 -286.6644) (xy 17.0434 -286.8168)
				(xy 18.6436 -286.8168) (xy 18.8468 -286.6136) (xy 18.8468 -285.6738) (xy 18.923 -285.5976) (xy 21.4884 -285.5976)
				(xy 21.6154 -285.7246) (xy 21.6154 -286.131) (xy 21.59 -286.1564) (xy 21.59 -286.766) (xy 22.0091 -287.1851)
				(xy 22.9743 -287.1851) (xy 24.9936 -289.2044) (xy 37.084 -289.2044) (xy 39.878 -289.2044) (xy 40.259 -288.8234)
				(xy 40.259 -284.1498) (xy 39.37 -283.2608) (xy 25.8318 -283.2608) (xy 25.4 -282.829) (xy 25.4 -256.032)
			)
		)
	)
	(zone
		(layer "F.Cu")
		(hatch none 0.5)
		(connect_pads
			(clearance 0)
		)
		(min_thickness 0.25)
		(keepout
			(tracks allowed)
			(vias allowed)
			(pads allowed)
			(copperpour allowed)
			(footprints not_allowed)
		)
		(placement
			(enabled no)
			(sheetname "")
		)
		(fill
			(thermal_gap 0.5)
			(thermal_bridge_width 0.5)
			(island_removal_mode 0)
		)
		(polygon
			(pts
				(xy 17.649952 -471.65006) (xy 31.34995 -471.65006) (xy 31.34995 -453.520048)
				(arc
					(start 30.249876 -453.520048)
					(mid 28.549854 -451.820026)
					(end 30.249876 -450.120004)
				)
				(xy 31.34995 -450.120004) (xy 31.34995 -429.250094) (xy 17.649952 -429.250094)
			)
		)
	)
	(zone
		(net "P3V3")
		(layer "F.Cu")
		(hatch none 0.5)
		(connect_pads
			(clearance 0.5)
		)
		(min_thickness 0.25)
		(fill yes
			(thermal_gap 0.5)
			(thermal_bridge_width 0.5)
			(island_removal_mode 0)
		)
		(polygon
			(pts
				(xy 26.797 -234.95) (xy 26.416 -234.95) (xy 25.781 -235.585) (xy 25.781 -237.363) (xy 25.908 -237.49)
				(xy 27.178 -237.49) (xy 28.067 -238.379) (xy 31.115 -238.379) (xy 31.369 -238.125) (xy 31.369 -237.49)
				(xy 31.242 -237.363) (xy 29.21 -237.363)
			)
		)
	)
	(zone
		(net "P12V")
		(layer "F.Cu")
		(hatch none 0.5)
		(connect_pads
			(clearance 0.5)
		)
		(min_thickness 0.25)
		(fill yes
			(thermal_gap 0.5)
			(thermal_bridge_width 0.5)
			(island_removal_mode 0)
		)
		(polygon
			(pts
				(xy 35.052 -383.54) (xy 13.843 -383.54) (xy 12.446 -384.937) (xy 12.446 -400.558) (xy 12.954 -401.066)
				(xy 44.323 -401.066) (xy 44.45 -400.939) (xy 44.45 -384.81) (xy 44.704 -384.556) (xy 44.704 -378.206)
				(xy 37.592 -371.094) (xy 36.322 -371.094) (xy 36.195 -371.221) (xy 36.195 -372.618) (xy 36.449 -372.872)
				(xy 36.83 -372.872) (xy 37.084 -373.126) (xy 37.084 -373.634) (xy 37.338 -373.888) (xy 38.1 -373.888)
				(xy 39.624 -375.412) (xy 39.624 -380.619) (xy 39.37 -380.873) (xy 37.719 -380.873)
			)
		)
	)
	(zone
		(net "P3V3_AUX")
		(layer "F.Cu")
		(hatch none 0.5)
		(connect_pads
			(clearance 0.5)
		)
		(min_thickness 0.25)
		(fill yes
			(thermal_gap 0.5)
			(thermal_bridge_width 0.5)
			(island_removal_mode 0)
		)
		(polygon
			(pts
				(xy 44.1198 -174.498) (xy 40.5892 -174.498) (xy 40.2336 -174.8536) (xy 40.2336 -174.879) (xy 39.9796 -175.133)
				(xy 38.735 -175.133) (xy 37.973 -175.895) (xy 37.973 -176.403) (xy 37.084 -177.292) (xy 35.814 -177.292)
				(xy 35.56 -177.546) (xy 35.56 -181.991) (xy 35.433 -182.118) (xy 34.671 -182.118) (xy 34.417 -182.372)
				(xy 34.417 -183.515) (xy 34.798 -183.896) (xy 38.354 -183.896) (xy 39.243 -184.785) (xy 39.243 -186.69)
				(xy 39.37 -186.817) (xy 40.513 -186.817) (xy 40.513 -184.9628) (xy 40.64 -184.8358) (xy 41.7576 -184.8358)
				(xy 41.91 -184.9882) (xy 41.91 -186.817) (xy 42.291 -186.817) (xy 42.418 -186.69) (xy 42.418 -184.023)
				(xy 42.1513 -183.7563) (xy 41.4655 -183.7563) (xy 39.3192 -181.61) (xy 38.227 -181.61) (xy 37.592 -180.975)
				(xy 37.592 -180.467) (xy 37.846 -180.213) (xy 38.227 -180.213) (xy 38.354 -180.086) (xy 38.354 -179.324)
				(xy 38.1 -179.07) (xy 37.719 -179.07) (xy 37.465 -178.816) (xy 37.465 -178.308) (xy 37.719 -178.054)
				(xy 40.513 -178.054) (xy 40.767 -177.8) (xy 40.767 -176.276) (xy 41.148 -175.895) (xy 42.291 -175.895)
				(xy 42.291 -177.8) (xy 42.418 -177.927) (xy 42.926 -177.927) (xy 43.1038 -177.7492) (xy 43.1038 -177.1396)
				(xy 44.577 -175.6664) (xy 44.577 -174.9552)
			)
		)
	)
	(zone
		(net "P12V_FAN6")
		(layer "F.Cu")
		(hatch none 0.5)
		(connect_pads
			(clearance 0.5)
		)
		(min_thickness 0.25)
		(fill yes
			(thermal_gap 0.5)
			(thermal_bridge_width 0.5)
			(island_removal_mode 0)
		)
		(polygon
			(pts
				(xy 8.5852 -18.669) (xy 2.667 -18.669) (xy 2.286 -19.05) (xy 2.286 -20.701) (xy 2.794 -21.209) (xy 3.302 -21.209)
				(xy 3.429 -21.082) (xy 7.112 -21.082) (xy 13.2207 -27.1907) (xy 13.2334 -27.1907) (xy 15.4305 -29.3878)
				(xy 18.4658 -29.3878) (xy 20.0279 -27.8257) (xy 20.7137 -27.8257) (xy 20.8788 -27.6606) (xy 20.8788 -20.6248)
				(xy 19.304 -19.05) (xy 17.3101 -19.05) (xy 16.129 -20.2311) (xy 10.1473 -20.2311)
			)
		)
	)
	(zone
		(net "P12V_FAN1")
		(layer "F.Cu")
		(hatch none 0.5)
		(connect_pads
			(clearance 0.5)
		)
		(min_thickness 0.25)
		(fill yes
			(thermal_gap 0.5)
			(thermal_bridge_width 0.5)
			(island_removal_mode 0)
		)
		(polygon
			(pts
				(xy 26.924 -481.711) (xy 17.018 -481.711) (xy 14.478 -484.251) (xy 7.874 -484.251) (xy 7.112 -483.489)
				(xy 2.667 -483.489) (xy 2.413 -483.743) (xy 2.413 -485.775) (xy 3.048 -486.41) (xy 4.826 -486.41)
				(xy 5.715 -487.299) (xy 27.305 -487.299) (xy 27.559 -487.045) (xy 27.559 -482.346)
			)
		)
	)
	(zone
		(layer "F.Cu")
		(hatch none 0.5)
		(connect_pads
			(clearance 0)
		)
		(min_thickness 0.25)
		(keepout
			(tracks allowed)
			(vias allowed)
			(pads allowed)
			(copperpour allowed)
			(footprints not_allowed)
		)
		(placement
			(enabled no)
			(sheetname "")
		)
		(fill
			(thermal_gap 0.5)
			(thermal_bridge_width 0.5)
			(island_removal_mode 0)
		)
		(polygon
			(pts
				(arc
					(start 45.500036 -484.000048)
					(mid 41.500044 -480.000056)
					(end 45.500036 -476.000064)
				)
				(arc
					(start 45.500036 -476.000064)
					(mid 49.500028 -480.000056)
					(end 45.500036 -484.000048)
				)
			)
		)
	)
	(zone
		(layer "F.Cu")
		(hatch none 0.5)
		(connect_pads
			(clearance 0)
		)
		(min_thickness 0.25)
		(keepout
			(tracks allowed)
			(vias allowed)
			(pads allowed)
			(copperpour allowed)
			(footprints not_allowed)
		)
		(placement
			(enabled no)
			(sheetname "")
		)
		(fill
			(thermal_gap 0.5)
			(thermal_bridge_width 0.5)
			(island_removal_mode 0)
		)
		(polygon
			(pts
				(xy 34.150046 -471.65006) (xy 47.850044 -471.65006) (xy 47.850044 -429.250094) (xy 34.150046 -429.250094)
				(xy 34.150046 -450.120004)
				(arc
					(start 35.25012 -450.120004)
					(mid 36.950142 -451.820026)
					(end 35.25012 -453.520048)
				)
				(xy 34.150046 -453.520048)
			)
		)
	)
	(zone
		(net "GND")
		(layer "F.Cu")
		(hatch none 0.5)
		(connect_pads
			(clearance 0.5)
		)
		(min_thickness 0.25)
		(fill yes
			(thermal_gap 0.5)
			(thermal_bridge_width 0.5)
			(island_removal_mode 0)
		)
		(polygon
			(pts
				(xy 18.161 -145.161) (xy 17.399 -145.161) (xy 17.272 -145.288) (xy 17.272 -146.685) (xy 18.034 -147.447)
				(xy 18.669 -147.447) (xy 19.177 -147.955) (xy 19.177 -149.225) (xy 19.431 -149.479) (xy 20.193 -149.479)
				(xy 20.828 -150.114) (xy 20.828 -151.13) (xy 21.59 -151.892) (xy 22.86 -151.892) (xy 23.114 -151.638)
				(xy 23.114 -148.844) (xy 24.1935 -147.7645) (xy 24.1935 -147.1295) (xy 23.368 -146.304) (xy 21.971 -146.304)
				(xy 21.209 -145.542) (xy 18.542 -145.542)
			)
		)
	)
	(zone
		(net "P12V_FAN5")
		(layer "F.Cu")
		(hatch none 0.5)
		(connect_pads
			(clearance 0.5)
		)
		(min_thickness 0.25)
		(fill yes
			(thermal_gap 0.5)
			(thermal_bridge_width 0.5)
			(island_removal_mode 0)
		)
		(polygon
			(pts
				(xy 6.1976 -129.032) (xy 2.286 -129.032) (xy 1.9558 -129.3622) (xy 1.9558 -149.6568) (xy 9.271 -156.972)
				(xy 20.828 -156.972) (xy 21.7297 -156.0703) (xy 21.7297 -152.8953) (xy 20.8534 -152.019) (xy 9.398 -152.019)
				(xy 5.5372 -148.1582) (xy 5.5372 -136.652) (xy 5.5499 -136.6393) (xy 5.5499 -134.7597) (xy 7.5438 -132.7658)
				(xy 7.5438 -130.3782)
			)
		)
	)
	(zone
		(layer "F.Cu")
		(hatch none 0.5)
		(connect_pads
			(clearance 0)
		)
		(min_thickness 0.25)
		(keepout
			(tracks allowed)
			(vias allowed)
			(pads allowed)
			(copperpour allowed)
			(footprints not_allowed)
		)
		(placement
			(enabled no)
			(sheetname "")
		)
		(fill
			(thermal_gap 0.5)
			(thermal_bridge_width 0.5)
			(island_removal_mode 0)
		)
		(polygon
			(pts
				(arc
					(start 45.500036 -23.999952)
					(mid 41.500044 -19.99996)
					(end 45.500036 -15.999968)
				)
				(arc
					(start 45.500036 -15.999968)
					(mid 49.500028 -19.99996)
					(end 45.500036 -23.999952)
				)
			)
		)
	)
	(zone
		(layer "F.Cu")
		(hatch none 0.5)
		(connect_pads
			(clearance 0)
		)
		(min_thickness 0.25)
		(keepout
			(tracks allowed)
			(vias allowed)
			(pads allowed)
			(copperpour allowed)
			(footprints not_allowed)
		)
		(placement
			(enabled no)
			(sheetname "")
		)
		(fill
			(thermal_gap 0.5)
			(thermal_bridge_width 0.5)
			(island_removal_mode 0)
		)
		(polygon
			(pts
				(xy 8.999982 -351.199958) (xy 8.999982 -323.799962) (xy 38.699948 -323.799962) (xy 38.699948 -329.149964)
				(arc
					(start 44.04995 -329.149964)
					(mid 49.954289 -331.595621)
					(end 52.399946 -337.49996)
				)
				(arc
					(start 52.399946 -337.49996)
					(mid 49.954289 -343.404299)
					(end 44.04995 -345.849956)
				)
				(xy 38.699948 -345.849956) (xy 38.699948 -351.199958)
			)
		)
	)
	(zone
		(layer "F.Cu")
		(hatch none 0.5)
		(connect_pads
			(clearance 0)
		)
		(min_thickness 0.25)
		(keepout
			(tracks allowed)
			(vias allowed)
			(pads allowed)
			(copperpour allowed)
			(footprints allowed)
		)
		(placement
			(enabled no)
			(sheetname "")
		)
		(fill
			(thermal_gap 0.5)
			(thermal_bridge_width 0.5)
			(island_removal_mode 0)
		)
		(polygon
			(pts
				(xy 24.5364 -144.3736) (xy 19.4564 -144.3736) (xy 19.4564 -136.7282) (xy 24.5364 -136.7282)
			)
		)
	)
	(zone
		(layer "F.Cu")
		(hatch none 0.5)
		(connect_pads
			(clearance 0)
		)
		(min_thickness 0.25)
		(keepout
			(tracks allowed)
			(vias allowed)
			(pads allowed)
			(copperpour allowed)
			(footprints not_allowed)
		)
		(placement
			(enabled no)
			(sheetname "")
		)
		(fill
			(thermal_gap 0.5)
			(thermal_bridge_width 0.5)
			(island_removal_mode 0)
		)
		(polygon
			(pts
				(arc
					(start 15.999968 -387.160008)
					(mid 15.267774 -388.927682)
					(end 13.5001 -389.659876)
				)
				(xy 0 -389.659876) (xy 0 -355.659944)
				(arc
					(start 13.5001 -355.659944)
					(mid 15.267789 -356.392303)
					(end 15.999968 -358.160066)
				)
			)
		)
	)
	(zone
		(net "P3V3_LX_COPPER")
		(layer "F.Cu")
		(hatch none 0.5)
		(connect_pads
			(clearance 0.5)
		)
		(min_thickness 0.25)
		(fill yes
			(thermal_gap 0.5)
			(thermal_bridge_width 0.5)
			(island_removal_mode 0)
		)
		(polygon
			(pts
				(xy 27.178 -238.125) (xy 23.876 -238.125) (xy 23.368 -238.633) (xy 23.368 -239.268) (xy 22.86 -239.776)
				(xy 21.463 -239.776) (xy 21.209 -240.03) (xy 21.209 -242.316) (xy 22.479 -243.586) (xy 24.257 -243.586)
				(xy 24.511 -243.332) (xy 24.511 -240.665) (xy 25.146 -240.03) (xy 26.924 -240.03) (xy 27.432 -239.522)
				(xy 27.432 -238.379)
			)
		)
	)
	(zone
		(net "P12VL_NET")
		(layer "F.Cu")
		(hatch none 0.5)
		(connect_pads
			(clearance 0.5)
		)
		(min_thickness 0.25)
		(fill yes
			(thermal_gap 0.5)
			(thermal_bridge_width 0.5)
			(island_removal_mode 0)
		)
		(polygon
			(pts
				(xy 51.308 -112.649) (xy 33.528 -112.649) (xy 32.639 -113.538) (xy 32.639 -120.904) (xy 33.274 -121.539)
				(xy 51.308 -121.539) (xy 51.689 -121.158) (xy 51.689 -113.03)
			)
		)
	)
	(zone
		(net "P12V_FAN2")
		(layer "F.Cu")
		(hatch none 0.5)
		(connect_pads
			(clearance 0.5)
		)
		(min_thickness 0.25)
		(fill yes
			(thermal_gap 0.5)
			(thermal_bridge_width 0.5)
			(island_removal_mode 0)
		)
		(polygon
			(pts
				(xy 32.9946 -289.7378) (xy 25.4 -289.7378) (xy 24.7396 -290.3982) (xy 24.7396 -292.2524) (xy 24.384 -292.608)
				(xy 24.384 -295.8592) (xy 15.5448 -304.6984) (xy 15.5448 -338.963) (xy 2.667 -351.8408) (xy 2.667 -364.7948)
				(xy 4.699 -366.8268) (xy 4.699 -373.507) (xy 4.191 -374.015) (xy 2.667 -374.015) (xy 2.159 -374.523)
				(xy 2.159 -376.047) (xy 2.54 -376.428) (xy 6.35 -376.428) (xy 7.747 -375.031) (xy 7.747 -364.744)
				(xy 5.588 -362.585) (xy 5.588 -353.822) (xy 18.6182 -340.7918) (xy 18.6182 -306.07) (xy 29.4386 -295.2496)
				(xy 32.6644 -295.2496) (xy 33.655 -294.259) (xy 33.655 -290.3982)
			)
		)
	)
	(zone
		(net "GND")
		(layer "F.Cu")
		(hatch none 0.5)
		(connect_pads
			(clearance 0.5)
		)
		(min_thickness 0.25)
		(fill yes
			(thermal_gap 0.5)
			(thermal_bridge_width 0.5)
			(island_removal_mode 0)
		)
		(polygon
			(pts
				(xy 17.78 -184.785) (xy 15.621 -184.785) (xy 12.446 -187.96) (xy 6.477 -187.96) (xy 5.207 -189.23)
				(xy 5.207 -192.278) (xy 5.588 -192.659) (xy 6.096 -192.659) (xy 7.62 -191.135) (xy 14.732 -191.135)
				(xy 17.272 -188.595) (xy 18.669 -188.595) (xy 19.558 -187.706) (xy 19.558 -186.69) (xy 19.812 -186.436)
				(xy 19.812 -185.42) (xy 19.685 -185.293) (xy 18.288 -185.293)
			)
		)
	)
	(zone
		(net "P12V_SENSE_TRACE")
		(layer "F.Cu")
		(hatch none 0.5)
		(connect_pads
			(clearance 0.5)
		)
		(min_thickness 0.25)
		(fill yes
			(thermal_gap 0.5)
			(thermal_bridge_width 0.5)
			(island_removal_mode 0)
		)
		(polygon
			(pts
				(xy 46.7106 -401.2946) (xy 12.7 -401.2946) (xy 12.4206 -401.574) (xy 12.4206 -408.9146) (xy 13.97 -410.464)
				(xy 46.863 -410.464) (xy 47.625 -409.702) (xy 47.625 -402.209)
			)
		)
	)
	(zone
		(layer "F.Cu")
		(hatch none 0.5)
		(connect_pads
			(clearance 0)
		)
		(min_thickness 0.25)
		(keepout
			(tracks allowed)
			(vias allowed)
			(pads allowed)
			(copperpour allowed)
			(footprints not_allowed)
		)
		(placement
			(enabled no)
			(sheetname "")
		)
		(fill
			(thermal_gap 0.5)
			(thermal_bridge_width 0.5)
			(island_removal_mode 0)
		)
		(polygon
			(pts
				(arc
					(start 13.5001 -110.339886)
					(mid 15.267789 -111.072245)
					(end 15.999968 -112.840008)
				)
				(arc
					(start 15.999968 -141.83995)
					(mid 15.267789 -143.607713)
					(end 13.5001 -144.340072)
				)
				(xy 0 -144.340072) (xy 0 -110.339886)
			)
		)
	)
	(zone
		(net "P12V_AUX")
		(layer "F.Cu")
		(hatch none 0.5)
		(connect_pads
			(clearance 0.5)
		)
		(min_thickness 0.25)
		(fill yes
			(thermal_gap 0.5)
			(thermal_bridge_width 0.5)
			(island_removal_mode 0)
		)
		(polygon
			(pts
				(xy 45.847 -410.718) (xy 13.97 -410.718) (xy 13.716 -410.972) (xy 13.208 -411.48) (xy 13.208 -416.306)
				(xy 13.208 -442.595) (xy 15.494 -444.881) (xy 15.494 -453.32142) (xy 15.494 -474.726) (xy 16.1925 -475.4245)
				(xy 30.353 -475.4245) (xy 32.512 -473.2655) (xy 32.512 -453.517) (xy 31.877 -452.882) (xy 29.718 -452.882)
				(xy 29.083 -452.247) (xy 29.083 -451.358) (xy 29.718 -450.723) (xy 32.004 -450.723) (xy 32.512 -450.215)
				(xy 32.512 -425.831) (xy 34.925 -423.418) (xy 46.101 -423.418) (xy 46.736 -422.783) (xy 46.736 -411.607)
			)
		)
	)
	(zone
		(layer "F.Cu")
		(hatch none 0.5)
		(connect_pads
			(clearance 0)
		)
		(min_thickness 0.25)
		(keepout
			(tracks allowed)
			(vias allowed)
			(pads allowed)
			(copperpour allowed)
			(footprints not_allowed)
		)
		(placement
			(enabled no)
			(sheetname "")
		)
		(fill
			(thermal_gap 0.5)
			(thermal_bridge_width 0.5)
			(island_removal_mode 0)
		)
		(polygon
			(pts
				(arc
					(start 13.5001 -465.70011)
					(mid 15.267774 -466.432304)
					(end 15.999968 -468.199978)
				)
				(arc
					(start 15.999968 -497.19992)
					(mid 15.267789 -498.967683)
					(end 13.5001 -499.700042)
				)
				(arc
					(start 0.28575 -499.700042)
					(mid 0.074121 -499.378086)
					(end 0 -499.000018)
				)
				(xy 0 -465.70011)
			)
		)
	)
	(zone
		(net "P12V")
		(layer "F.Cu")
		(hatch none 0.5)
		(connect_pads
			(clearance 0.5)
		)
		(min_thickness 0.25)
		(fill yes
			(thermal_gap 0.5)
			(thermal_bridge_width 0.5)
			(island_removal_mode 0)
		)
		(polygon
			(pts
				(xy 15.3924 -121.92) (xy 10.16 -121.92) (xy 7.874 -124.206) (xy 7.874 -131.445) (xy 7.8994 -131.4704)
				(xy 7.8994 -132.4102) (xy 9.0424 -133.5532) (xy 23.2664 -133.5532) (xy 23.3045 -133.5151) (xy 24.4729 -133.5151)
				(xy 24.511 -133.5532) (xy 28.2194 -133.5532) (xy 28.2956 -133.6294) (xy 39.3954 -133.6294) (xy 39.5732 -133.4516)
				(xy 43.942 -133.4516) (xy 44.1198 -133.6294) (xy 51.5366 -133.6294) (xy 51.689 -133.477) (xy 51.689 -122.174)
				(xy 51.435 -121.92) (xy 47.0662 -121.92) (xy 46.8122 -122.174) (xy 46.8122 -123.1646) (xy 46.6344 -123.3424)
				(xy 38.4556 -123.3424) (xy 38.3032 -123.19) (xy 38.3032 -122.2756) (xy 37.9476 -121.92) (xy 25.2476 -121.92)
				(xy 24.8158 -122.3518) (xy 24.8158 -123.0376) (xy 24.3332 -123.5202) (xy 16.9926 -123.5202)
			)
		)
	)
	(zone
		(layer "F.Cu")
		(hatch none 0.5)
		(connect_pads
			(clearance 0)
		)
		(min_thickness 0.25)
		(keepout
			(tracks allowed)
			(vias allowed)
			(pads allowed)
			(copperpour allowed)
			(footprints not_allowed)
		)
		(placement
			(enabled no)
			(sheetname "")
		)
		(fill
			(thermal_gap 0.5)
			(thermal_bridge_width 0.5)
			(island_removal_mode 0)
		)
		(polygon
			(pts
				(arc
					(start 6.999986 -43.999912)
					(mid 2.999994 -39.99992)
					(end 6.999986 -35.999928)
				)
				(arc
					(start 6.999986 -35.999928)
					(mid 10.999978 -39.99992)
					(end 6.999986 -43.999912)
				)
			)
		)
	)
	(zone
		(layer "F.Cu")
		(hatch none 0.5)
		(connect_pads
			(clearance 0)
		)
		(min_thickness 0.25)
		(keepout
			(tracks allowed)
			(vias allowed)
			(pads allowed)
			(copperpour allowed)
			(footprints not_allowed)
		)
		(placement
			(enabled no)
			(sheetname "")
		)
		(fill
			(thermal_gap 0.5)
			(thermal_bridge_width 0.5)
			(island_removal_mode 0)
		)
		(polygon
			(pts
				(arc
					(start 45.500036 -476.000064)
					(mid 49.500028 -480.000056)
					(end 45.500036 -484.000048)
				)
				(arc
					(start 45.500036 -484.000048)
					(mid 41.500044 -480.000056)
					(end 45.500036 -476.000064)
				)
			)
		)
	)
	(zone
		(net "GND")
		(layer "F.Cu")
		(hatch none 0.5)
		(connect_pads
			(clearance 0.5)
		)
		(min_thickness 0.25)
		(fill yes
			(thermal_gap 0.5)
			(thermal_bridge_width 0.5)
			(island_removal_mode 0)
		)
		(polygon
			(pts
				(xy 29.2608 -89.6112) (xy 23.876 -89.6112) (xy 23.6982 -89.789) (xy 23.6982 -94.361) (xy 24.384 -95.0468)
				(xy 24.384 -108.331) (xy 26.289 -110.236) (xy 28.448 -110.236) (xy 28.829 -109.855) (xy 28.829 -95.377)
				(xy 29.464 -94.742) (xy 29.464 -89.8144)
			)
		)
	)
	(zone
		(net "P12VL")
		(layer "F.Cu")
		(hatch none 0.5)
		(connect_pads
			(clearance 0.5)
		)
		(min_thickness 0.25)
		(fill yes
			(thermal_gap 0.5)
			(thermal_bridge_width 0.5)
			(island_removal_mode 0)
		)
		(polygon
			(pts
				(xy 47.117 -63.754) (xy 36.957 -63.754) (xy 35.687 -65.024) (xy 35.687 -72.517) (xy 27.813 -80.391)
				(xy 27.813 -88.646) (xy 28.194 -89.027) (xy 29.083 -89.027) (xy 29.8196 -89.7636) (xy 29.8196 -94.8182)
				(xy 28.956 -95.6818) (xy 28.956 -108.7882) (xy 32.639 -112.4712) (xy 44.831 -112.4712) (xy 44.831 -112.395)
				(xy 45.593 -112.395) (xy 45.72 -112.268) (xy 45.72 -109.601) (xy 45.085 -108.966) (xy 45.085 -81.661)
				(xy 45.0342 -81.6102) (xy 47.5107 -79.1337) (xy 47.498 -79.121) (xy 47.498 -64.135)
			)
		)
	)
	(zone
		(layer "F.Cu")
		(hatch none 0.5)
		(connect_pads
			(clearance 0)
		)
		(min_thickness 0.25)
		(keepout
			(tracks allowed)
			(vias allowed)
			(pads allowed)
			(copperpour allowed)
			(footprints not_allowed)
		)
		(placement
			(enabled no)
			(sheetname "")
		)
		(fill
			(thermal_gap 0.5)
			(thermal_bridge_width 0.5)
			(island_removal_mode 0)
		)
		(polygon
			(pts
				(arc
					(start 6.999986 -464.000088)
					(mid 2.999994 -460.000096)
					(end 6.999986 -456.000104)
				)
				(arc
					(start 6.999986 -456.000104)
					(mid 10.999978 -460.000096)
					(end 6.999986 -464.000088)
				)
			)
		)
	)
	(zone
		(layer "F.Cu")
		(hatch none 0.5)
		(connect_pads
			(clearance 0)
		)
		(min_thickness 0.25)
		(keepout
			(tracks allowed)
			(vias allowed)
			(pads allowed)
			(copperpour allowed)
			(footprints not_allowed)
		)
		(placement
			(enabled no)
			(sheetname "")
		)
		(fill
			(thermal_gap 0.5)
			(thermal_bridge_width 0.5)
			(island_removal_mode 0)
		)
		(polygon
			(pts
				(arc
					(start 15.999968 -207.840072)
					(mid 15.267774 -209.607746)
					(end 13.5001 -210.33994)
				)
				(xy 0 -210.33994) (xy 0 -176.340008)
				(arc
					(start 13.5001 -176.340008)
					(mid 15.267774 -177.072202)
					(end 15.999968 -178.839876)
				)
			)
		)
	)
	(zone
		(layer "F.Cu")
		(hatch none 0.5)
		(connect_pads
			(clearance 0)
		)
		(min_thickness 0.25)
		(keepout
			(tracks allowed)
			(vias allowed)
			(pads allowed)
			(copperpour allowed)
			(footprints not_allowed)
		)
		(placement
			(enabled no)
			(sheetname "")
		)
		(fill
			(thermal_gap 0.5)
			(thermal_bridge_width 0.5)
			(island_removal_mode 0)
		)
		(polygon
			(pts
				(arc
					(start 13.5001 -289.660076)
					(mid 15.267774 -290.39227)
					(end 15.999968 -292.159944)
				)
				(arc
					(start 15.999968 -321.159886)
					(mid 15.267863 -322.927724)
					(end 13.5001 -323.660008)
				)
				(xy 0 -323.660008) (xy 0 -289.660076)
			)
		)
	)
	(zone
		(layer "F.Cu")
		(hatch none 0.5)
		(connect_pads
			(clearance 0)
		)
		(min_thickness 0.25)
		(keepout
			(tracks allowed)
			(vias allowed)
			(pads allowed)
			(copperpour allowed)
			(footprints not_allowed)
		)
		(placement
			(enabled no)
			(sheetname "")
		)
		(fill
			(thermal_gap 0.5)
			(thermal_bridge_width 0.5)
			(island_removal_mode 0)
		)
		(polygon
			(pts
				(arc
					(start 15.999968 -31.800038)
					(mid 15.267774 -33.567712)
					(end 13.5001 -34.299906)
				)
				(xy 0 -34.299906)
				(arc
					(start 0 -0.999998)
					(mid 0.074208 -0.621966)
					(end 0.28575 -0.299974)
				)
				(arc
					(start 13.5001 -0.299974)
					(mid 15.267789 -1.032333)
					(end 15.999968 -2.800096)
				)
			)
		)
	)
	(zone
		(net "GND")
		(layer "F.Cu")
		(hatch none 0.5)
		(connect_pads
			(clearance 0.5)
		)
		(min_thickness 0.25)
		(fill yes
			(thermal_gap 0.5)
			(thermal_bridge_width 0.5)
			(island_removal_mode 0)
		)
		(polygon
			(pts
				(arc
					(start 0.999998 -0.762254)
					(mid 0.831888 -0.831888)
					(end 0.762254 -0.999998)
				)
				(arc
					(start 0.762254 -499.000018)
					(mid 0.831888 -499.168128)
					(end 0.999998 -499.237762)
				)
				(arc
					(start 16.500094 -499.237762)
					(mid 16.668204 -499.168128)
					(end 16.737838 -499.000018)
				)
				(arc
					(start 16.737838 -491.000034)
					(mid 17.25399 -489.753934)
					(end 18.50009 -489.237782)
				)
				(arc
					(start 51.500024 -489.237782)
					(mid 51.668134 -489.168148)
					(end 51.737768 -489.000038)
				)
				(xy 51.737768 -134.211568) (xy 51.4604 -133.9342) (xy 44.1198 -133.9342) (xy 43.942 -134.112) (xy 43.942 -136.652)
				(xy 43.688 -136.906) (xy 42.799 -136.906) (xy 42.545 -137.16) (xy 42.545 -138.43) (xy 43.18 -139.065)
				(xy 43.18 -140.0302) (xy 42.9641 -140.2461) (xy 42.926 -140.208) (xy 42.164 -140.208) (xy 39.624 -142.748)
				(xy 38.227 -142.748) (xy 36.322 -140.843) (xy 36.322 -136.906) (xy 37.846 -135.382) (xy 38.7096 -135.382)
				(xy 38.862 -135.2296) (xy 38.862 -134.239) (xy 38.5064 -133.8834) (xy 25.273 -133.8834) (xy 24.9555 -134.2009)
				(xy 24.9555 -135.0137) (xy 23.9268 -136.0424) (xy 23.9268 -137.9982) (xy 23.876 -138.049) (xy 23.876 -138.938)
				(xy 25.4 -138.938) (xy 26.289 -138.049) (xy 27.559 -138.049) (xy 28.448 -138.938) (xy 28.448 -139.827)
				(xy 27.813 -140.462) (xy 26.797 -140.462) (xy 26.67 -140.589) (xy 26.67 -142.494) (xy 26.797 -142.621)
				(xy 32.258 -142.621) (xy 35.1917 -145.5547) (xy 35.1917 -145.8341) (xy 35.2679 -145.9103) (xy 35.2679 -146.6977)
				(xy 35.433 -146.8628) (xy 36.3474 -146.8628) (xy 36.6014 -146.6088) (xy 36.8808 -146.6088) (xy 37.6936 -147.4216)
				(xy 37.6936 -147.5994) (xy 37.6428 -147.6502) (xy 37.6428 -148.1836) (xy 41.8592 -152.4) (xy 45.339 -152.4)
				(xy 47.371 -154.432) (xy 47.371 -164.719) (xy 46.609 -165.481) (xy 42.545 -165.481) (xy 41.656 -164.592)
				(xy 41.656 -162.941) (xy 39.624 -162.941) (xy 39.37 -163.195) (xy 39.37 -169.037) (xy 40.132 -169.799)
				(xy 40.132 -170.307) (xy 39.37 -171.069) (xy 39.37 -171.831) (xy 40.767 -173.228) (xy 44.196 -173.228)
				(xy 45.72 -174.752) (xy 45.72 -178.689) (xy 45.466 -178.943) (xy 39.37 -178.943) (xy 38.862 -179.451)
				(xy 38.862 -181.102) (xy 39.0525 -181.2925) (xy 39.4589 -181.2925) (xy 41.5671 -183.4007) (xy 42.3037 -183.4007)
				(xy 42.799 -183.896) (xy 42.799 -185.1152) (xy 43.7134 -185.1152) (xy 43.8404 -185.2422) (xy 43.8404 -186.8932)
				(xy 43.6626 -187.071) (xy 41.6814 -187.071) (xy 41.6306 -187.0202) (xy 41.6306 -185.2676) (xy 41.5544 -185.1914)
				(xy 40.8686 -185.1914) (xy 40.767 -185.293) (xy 40.767 -187.0456) (xy 40.64 -187.1726) (xy 39.243 -187.1726)
				(xy 39.0017 -186.9313) (xy 39.0017 -184.5437) (xy 38.6842 -184.2262) (xy 36.3474 -184.2262) (xy 35.8902 -184.6834)
				(xy 34.163 -184.6834) (xy 34.0106 -184.531) (xy 34.0106 -183.8452) (xy 34.0868 -183.769) (xy 34.0868 -182.245)
				(xy 34.7726 -181.5592) (xy 35.2044 -181.5592) (xy 35.2806 -181.483) (xy 35.2806 -179.197) (xy 35.2044 -179.1208)
				(xy 35.2044 -177.5206) (xy 35.7632 -176.9618) (xy 36.2712 -176.9618) (xy 36.3982 -176.8348) (xy 36.3982 -176.6824)
				(xy 37.2491 -175.8315) (xy 38.0365 -175.8315) (xy 38.735 -175.133) (xy 39.878 -175.133) (xy 40.513 -174.498)
				(xy 39.37 -174.498) (xy 38.608 -173.736) (xy 38.608 -172.085) (xy 38.227 -171.704) (xy 37.973 -171.704)
				(xy 36.703 -172.974) (xy 35.433 -172.974) (xy 35.052 -172.593) (xy 34.29 -172.593) (xy 34.163 -172.466)
				(xy 34.163 -171.069) (xy 32.893 -169.799) (xy 22.86 -169.799) (xy 22.225 -169.164) (xy 22.225 -165.481)
				(xy 23.495 -164.211) (xy 23.495 -162.179) (xy 21.844 -162.179) (xy 21.844 -162.687) (xy 19.431 -165.1)
				(xy 17.018 -165.1) (xy 15.621 -166.497) (xy 15.621 -169.037) (xy 16.383 -169.799) (xy 16.891 -169.799)
				(xy 18.161 -171.069) (xy 18.161 -171.958) (xy 20.828 -171.958) (xy 21.336 -172.466) (xy 22.352 -172.466)
				(xy 22.352 -171.704) (xy 22.733 -171.323) (xy 24.765 -171.323) (xy 24.892 -171.45) (xy 24.892 -176.403)
				(xy 24.384 -176.911) (xy 20.574 -176.911) (xy 20.574 -176.022) (xy 20.447 -175.895) (xy 17.145 -175.895)
				(xy 13.843 -172.593) (xy 10.16 -172.593) (xy 9.017 -171.45) (xy 9.017 -156.972) (xy 1.8542 -149.8092)
				(xy 1.8542 -130.5306) (xy 1.651 -130.3274) (xy 1.651 -128.651) (xy 2.032 -128.27) (xy 6.35 -128.27)
				(xy 7.62 -127) (xy 7.62 -123.825) (xy 9.525 -121.92) (xy 9.525 -90.551) (xy 9.398 -90.424) (xy 9.398 -89.789)
				(xy 9.271 -89.662) (xy 9.271 -85.852) (xy 8.255 -84.836) (xy 4.191 -84.836) (xy 3.683 -84.328) (xy 3.683 -77.089)
				(xy 4.445 -76.327) (xy 9.017 -76.327) (xy 9.144 -76.2) (xy 9.144 -73.025) (xy 10.287 -71.882) (xy 17.3228 -71.882)
				(xy 17.3228 -68.5292) (xy 13.716 -64.9224) (xy 13.716 -63.881) (xy 14.097 -63.5) (xy 14.6304 -63.5)
				(xy 15.5194 -62.611) (xy 15.5194 -59.7916) (xy 15.1384 -59.4106) (xy 15.1384 -58.8264) (xy 14.859 -58.547)
				(xy 12.319 -58.547) (xy 11.811 -59.055) (xy 11.811 -59.2455) (xy 11.5443 -59.2455) (xy 11.5062 -59.2074)
				(xy 10.795 -59.2074) (xy 10.6172 -59.0296) (xy 10.6172 -43.2562) (xy 13.7414 -40.132) (xy 13.7414 -39.5732)
				(xy 14.4018 -38.9128) (xy 14.6812 -38.9128) (xy 14.9352 -39.1668) (xy 14.9352 -39.6748) (xy 15.3416 -40.0812)
				(xy 19.431 -40.0812) (xy 20.0406 -39.4716) (xy 27.813 -39.4716) (xy 27.8257 -39.4843) (xy 28.8163 -39.4843)
				(xy 35.814 -46.482) (xy 35.814 -49.149) (xy 36.8046 -50.1396) (xy 47.117 -50.1396) (xy 48.006 -51.0286)
				(xy 48.006 -79.375) (xy 45.339 -82.042) (xy 45.339 -108.331) (xy 46.482 -109.474) (xy 47.371 -109.474)
				(xy 48.387 -110.49) (xy 49.784 -110.49) (xy 49.911 -110.617) (xy 49.911 -112.141) (xy 50.038 -112.268)
				(xy 51.229768 -112.268) (xy 51.737768 -111.76) (xy 51.737768 -70.914768) (xy 51.649884 -70.826884)
				(xy 51.737768 -70.739)
				(arc
					(start 51.737768 -10.999978)
					(mid 51.668134 -10.831868)
					(end 51.500024 -10.762234)
				)
				(arc
					(start 18.50009 -10.762234)
					(mid 17.25399 -10.246082)
					(end 16.737838 -8.999982)
				)
				(arc
					(start 16.737838 -0.999998)
					(mid 16.668204 -0.831888)
					(end 16.500094 -0.762254)
				)
			)
		)
		(polygon
			(pts
				(xy 13.639546 -454.152508) (xy 13.436854 -454.152508) (xy 13.424154 -454.165208) (xy 11.843004 -454.165208)
				(xy 11.843004 -455.863452) (xy 13.866622 -457.88707) (xy 14.426692 -457.326746) (xy 14.426692 -454.939654)
			)
		)
		(polygon
			(pts
				(arc
					(start 11.093196 -453.927972)
					(mid 11.046069 -453.842209)
					(end 10.948416 -453.836024)
				)
				(arc
					(start 10.948416 -453.836024)
					(mid 10.889137 -453.860429)
					(end 10.827766 -453.87895)
				)
				(xy 10.81405 -453.882252) (xy 10.338308 -454.358248)
				(arc
					(start 10.338308 -454.3806)
					(mid 10.326501 -454.477658)
					(end 10.291826 -454.569068)
				)
				(arc
					(start 10.291826 -454.569068)
					(mid 10.283186 -454.64088)
					(end 10.324592 -454.700132)
				)
				(arc
					(start 10.324592 -454.700132)
					(mid 10.540684 -454.946199)
					(end 10.61212 -455.26579)
				)
				(xy 10.611358 -455.287634)
				(arc
					(start 10.919714 -455.595736)
					(mid 11.030381 -455.617821)
					(end 11.093196 -455.524108)
				)
			)
		)
		(polygon
			(pts
				(xy 7.26313 -451.072504) (xy 5.597906 -451.072504)
				(arc
					(start 5.582666 -451.089268)
					(mid 5.426843 -451.215019)
					(end 5.240528 -451.288404)
				)
				(xy 5.200904 -451.297548) (xy 5.200904 -451.621652) (xy 5.203698 -451.624192) (xy 6.426708 -451.624192)
				(xy 6.426708 -452.449692) (xy 6.562598 -452.449692) (xy 7.210298 -453.097392) (xy 7.210552 -453.097392)
				(xy 7.604252 -453.491092)
				(arc
					(start 7.8994 -453.491092)
					(mid 8.111679 -453.550852)
					(end 8.261604 -453.71258)
				)
				(arc
					(start 8.261604 -453.71258)
					(mid 8.336298 -453.766682)
					(end 8.42391 -453.73798)
				)
				(arc
					(start 8.42391 -453.73798)
					(mid 8.556093 -453.649278)
					(end 8.7122 -453.618092)
				)
				(arc
					(start 9.0678 -453.618092)
					(mid 9.098753 -453.619329)
					(end 9.129522 -453.622918)
				)
				(xy 9.154922 -453.626728) (xy 9.209024 -453.572626) (xy 8.759952 -453.123808) (xy 7.797292 -453.123808)
				(xy 7.797292 -451.624192) (xy 9.804908 -451.624192) (xy 9.804908 -452.576692)
				(arc
					(start 10.598912 -452.576692)
					(mid 10.645845 -452.545332)
					(end 10.634726 -452.490078)
				)
				(xy 10.597896 -452.453248)
				(arc
					(start 10.597896 -451.26275)
					(mid 10.524861 -451.165248)
					(end 10.410698 -451.207886)
				)
				(arc
					(start 10.410698 -451.207886)
					(mid 9.896803 -451.509492)
					(end 9.348978 -451.274942)
				)
				(xy 9.333738 -451.256908) (xy 8.980932 -451.256908)
				(arc
					(start 8.972804 -451.259702)
					(mid 8.906951 -451.276625)
					(end 8.8392 -451.282308)
				)
				(arc
					(start 8.4836 -451.282308)
					(mid 8.349026 -451.259321)
					(end 8.2296 -451.193154)
				)
				(arc
					(start 8.2296 -451.193154)
					(mid 8.11019 -451.259366)
					(end 7.9756 -451.282308)
				)
				(arc
					(start 7.62 -451.282308)
					(mid 7.425297 -451.232667)
					(end 7.278116 -451.095872)
				)
			)
		)
		(polygon
			(pts
				(xy 11.8618 -444.1698) (xy 9.4996 -444.1698) (xy 9.4996 -449.707) (xy 10.033 -450.2404) (xy 11.5316 -450.2404)
				(xy 11.8618 -449.9102)
			)
		)
		(polygon
			(pts
				(xy 8.4074 -433.9336) (xy 4.7498 -433.9336) (xy 4.2418 -434.4416) (xy 4.2418 -436.245) (xy 4.5466 -436.5498)
				(xy 5.0292 -436.5498) (xy 4.953 -436.626) (xy 4.953 -443.0014) (xy 7.5184 -445.5668) (xy 8.2804 -445.5668)
				(xy 8.2804 -446.3034) (xy 8.636 -446.659) (xy 9.3218 -445.9732) (xy 9.3218 -436.8038) (xy 9.2456 -436.7276)
				(xy 9.2456 -434.7718)
			)
		)
		(polygon
			(pts
				(arc
					(start 5.816346 -430.555654)
					(mid 5.681909 -430.532789)
					(end 5.5626 -430.466754)
				)
				(arc
					(start 5.5626 -430.466754)
					(mid 5.44319 -430.532966)
					(end 5.3086 -430.555908)
				)
				(xy 4.953508 -430.555908) (xy 4.953508 -432.727608) (xy 4.572508 -432.727608)
				(arc
					(start 4.572508 -432.922426)
					(mid 4.613792 -433.004185)
					(end 4.70408 -433.019454)
				)
				(arc
					(start 4.70408 -433.019454)
					(mid 4.913474 -432.994419)
					(end 5.1181 -433.045362)
				)
				(arc
					(start 5.1181 -433.045362)
					(mid 5.215225 -433.038377)
					(end 5.261864 -432.952906)
				)
				(xy 5.261864 -432.794664) (xy 5.57276 -432.794664) (xy 5.57276 -432.300634) (xy 5.866892 -432.006502)
				(arc
					(start 5.866892 -430.606454)
					(mid 5.852103 -430.570623)
					(end 5.816346 -430.555654)
				)
			)
		)
		(polygon
			(pts
				(arc
					(start 5.200904 -418.178742)
					(mid 5.178032 -418.163998)
					(end 5.1562 -418.147754)
				)
				(arc
					(start 5.1562 -418.147754)
					(mid 5.03679 -418.213966)
					(end 4.9022 -418.236908)
				)
				(arc
					(start 4.5466 -418.236908)
					(mid 4.478855 -418.231186)
					(end 4.412996 -418.214302)
				)
				(xy 4.404868 -418.211508)
				(arc
					(start 4.033774 -418.211508)
					(mid 3.939942 -418.274144)
					(end 3.961892 -418.384736)
				)
				(xy 4.674108 -419.096952) (xy 4.674108 -419.772592) (xy 5.055108 -419.772592) (xy 5.055108 -421.786558)
				(arc
					(start 5.090414 -421.797734)
					(mid 5.384005 -421.988868)
					(end 5.538724 -422.303194)
				)
				(xy 5.546598 -422.344596) (xy 7.815072 -422.344596)
				(arc
					(start 7.830058 -422.319704)
					(mid 7.844802 -422.296832)
					(end 7.861046 -422.275)
				)
				(arc
					(start 7.861046 -422.275)
					(mid 7.805286 -422.182156)
					(end 7.775956 -422.077896)
				)
				(xy 7.76986 -422.034208) (xy 5.968492 -422.034208) (xy 5.968492 -420.493698) (xy 5.225796 -419.750748)
				(xy 5.225796 -418.193728)
			)
		)
		(polygon
			(pts
				(xy 8.89 -411.734) (xy 6.985 -411.734) (xy 5.842 -412.877) (xy 5.842 -418.084) (xy 5.6896 -418.2364)
				(xy 5.6896 -419.608) (xy 6.2738 -420.1922) (xy 8.3312 -420.1922) (xy 8.382 -420.243) (xy 9.779 -420.243)
				(xy 10.033 -419.989) (xy 10.033 -415.544) (xy 9.144 -414.655) (xy 9.144 -411.988)
			)
		)
		(polygon
			(pts
				(xy 43.942 -346.583) (xy 40.513 -346.583) (xy 38.354 -348.742) (xy 38.354 -349.504) (xy 37.592 -350.266)
				(xy 29.21 -350.266) (xy 28.321 -351.155) (xy 28.321 -353.441) (xy 28.702 -353.822) (xy 28.702 -354.203)
				(xy 28.575 -354.33) (xy 27.178 -354.33) (xy 26.035 -355.473) (xy 26.035 -358.013) (xy 24.0284 -360.0196)
				(xy 22.479 -360.0196) (xy 22.098 -360.4006) (xy 22.098 -363.1184) (xy 22.5806 -363.601) (xy 23.368 -363.601)
				(xy 23.495 -363.728) (xy 23.495 -364.8964) (xy 23.3172 -365.0742) (xy 21.844 -365.0742) (xy 21.4757 -365.4425)
				(xy 21.4757 -365.7473) (xy 21.463 -365.76) (xy 21.463 -366.0394) (xy 21.844 -366.4204) (xy 22.5552 -366.4204)
				(xy 22.8346 -366.141) (xy 23.4188 -366.141) (xy 23.495 -366.2172) (xy 23.495 -367.792) (xy 23.241 -368.046)
				(xy 21.717 -368.046) (xy 21.336 -368.427) (xy 21.336 -368.935) (xy 21.463 -369.062) (xy 23.114 -369.062)
				(xy 23.241 -369.189) (xy 23.241 -370.078) (xy 22.987 -370.332) (xy 21.082 -370.332) (xy 20.828 -370.586)
				(xy 20.447 -370.586) (xy 20.447 -372.872) (xy 21.082 -373.507) (xy 21.082 -376.047) (xy 20.701 -376.428)
				(xy 20.701 -378.333) (xy 21.844 -379.476) (xy 24.765 -379.476) (xy 25.654 -380.365) (xy 25.654 -382.143)
				(xy 25.146 -382.651) (xy 13.6652 -382.651) (xy 12.2682 -384.048) (xy 12.2682 -415.8742) (xy 12.319 -415.925)
				(xy 12.319 -442.341) (xy 15.0495 -445.0715) (xy 15.0495 -449.2625) (xy 13.9065 -450.4055) (xy 13.843 -450.342)
				(xy 12.5222 -450.342) (xy 12.452096 -450.412104) (xy 12.169648 -450.412104) (xy 11.398504 -451.183248)
				(xy 11.398504 -453.005952) (xy 11.4554 -453.062848) (xy 11.4554 -453.9742) (xy 11.6459 -454.1647)
				(xy 13.4239 -454.1647) (xy 13.4366 -454.152) (xy 13.6398 -454.152) (xy 14.4272 -454.9394) (xy 14.4272 -457.327)
				(xy 13.6652 -458.089) (xy 13.081 -458.089) (xy 12.446 -458.724) (xy 12.446 -459.359) (xy 12.446 -473.964)
				(xy 6.985 -479.425) (xy 5.842 -479.425) (xy 5.842 -478.536) (xy 4.064 -476.758) (xy 2.794 -476.758)
				(xy 2.286 -477.266) (xy 2.286 -485.14) (xy 2.032 -485.394) (xy 2.032 -486.664) (xy 2.921 -487.553)
				(xy 27.559 -487.553) (xy 28.194 -486.918) (xy 28.194 -482.219) (xy 28.702 -481.711) (xy 35.941 -481.711)
				(xy 36.83 -480.822) (xy 36.83 -476.504) (xy 35.814 -475.488) (xy 34.671 -475.488) (xy 33.655 -474.472)
				(xy 33.655 -453.771) (xy 34.544 -452.882) (xy 35.687 -452.882) (xy 36.322 -452.247) (xy 36.322 -451.358)
				(xy 35.687 -450.723) (xy 34.417 -450.723) (xy 33.655 -449.961) (xy 33.655 -425.958) (xy 35.56 -424.053)
				(xy 46.355 -424.053) (xy 46.863 -424.053) (xy 47.371 -423.545) (xy 47.371 -410.464) (xy 47.879 -409.956)
				(xy 47.879 -401.955) (xy 45.974 -400.05) (xy 45.974 -398.653) (xy 44.958 -397.637) (xy 44.958 -347.599)
			)
		)
		(polygon
			(pts
				(xy 30.353 -318.135) (xy 26.416 -318.135) (xy 25.527 -319.024) (xy 25.527 -320.802) (xy 26.543 -321.818)
				(xy 30.226 -321.818) (xy 30.988 -321.056) (xy 30.988 -318.77)
			)
		)
		(polygon
			(pts
				(xy 17.272 -253.365) (xy 15.875 -253.365) (xy 15.748 -253.492) (xy 15.748 -254.381) (xy 15.113 -255.016)
				(xy 15.113 -255.778) (xy 14.224 -256.667) (xy 12.192 -256.667) (xy 10.922 -257.937) (xy 10.922 -296.672)
				(xy 7.239 -300.355) (xy 2.921 -300.355) (xy 1.651 -301.625) (xy 1.651 -310.769) (xy 1.905 -311.023)
				(xy 6.604 -311.023) (xy 10.033 -307.594) (xy 10.033 -303.657) (xy 15.113 -298.577) (xy 15.113 -297.688)
				(xy 15.367 -297.434) (xy 15.748 -297.434) (xy 16.383 -298.069) (xy 16.383 -303.149) (xy 15.24 -304.292)
				(xy 15.24 -338.709) (xy 2.413 -351.536) (xy 2.413 -364.744) (xy 4.318 -366.649) (xy 4.318 -372.999)
				(xy 3.683 -373.634) (xy 2.667 -373.634) (xy 1.905 -374.396) (xy 1.905 -376.555) (xy 2.159 -376.809)
				(xy 6.858 -376.809) (xy 8.128 -375.539) (xy 8.128 -364.49) (xy 9.525 -363.093) (xy 9.525 -361.061)
				(xy 7.874 -359.41) (xy 6.223 -359.41) (xy 5.969 -359.156) (xy 5.969 -353.949) (xy 18.923 -340.995)
				(xy 18.923 -306.451) (xy 29.718 -295.656) (xy 32.766 -295.656) (xy 34.036 -294.386) (xy 34.036 -290.322)
				(xy 34.798 -289.56) (xy 40.132 -289.56) (xy 40.64 -289.052) (xy 40.64 -283.718) (xy 39.878 -282.956)
				(xy 26.416 -282.956) (xy 25.908 -282.448) (xy 25.908 -255.651) (xy 24.638 -254.381) (xy 18.288 -254.381)
			)
		)
		(polygon
			(pts
				(xy 31.623 -248.158) (xy 28.067 -248.158) (xy 27.94 -248.285) (xy 27.94 -248.539) (xy 26.543 -249.936)
				(xy 26.543 -251.968) (xy 26.797 -252.222) (xy 28.321 -252.222) (xy 28.829 -252.73) (xy 28.829 -253.365)
				(xy 29.591 -254.127) (xy 29.591 -255.524) (xy 30.226 -256.159) (xy 30.861 -256.159) (xy 31.369 -255.651)
				(xy 31.369 -252.984) (xy 31.242 -252.857) (xy 31.242 -249.174) (xy 31.623 -248.793)
			)
		)
		(polygon
			(pts
				(xy 39.497 -247.269) (xy 38.1 -247.269) (xy 38.1 -247.777) (xy 37.719 -248.158) (xy 34.417 -248.158)
				(xy 34.29 -248.285) (xy 34.29 -252.8824) (xy 32.004 -252.8824) (xy 31.75 -253.1364) (xy 31.75 -256.2606)
				(xy 34.0106 -258.5212) (xy 36.7284 -258.5212) (xy 36.8808 -258.3688) (xy 36.8808 -257.1242) (xy 36.576 -256.8194)
				(xy 36.576 -255.6764) (xy 36.8554 -255.397) (xy 39.37 -255.397) (xy 41.148 -253.619) (xy 41.148 -251.841)
				(xy 39.878 -250.571) (xy 39.878 -247.65)
			)
		)
		(polygon
			(pts
				(xy 36.322 -240.792) (xy 33.274 -240.792) (xy 33.02 -241.046) (xy 33.02 -242.189) (xy 33.775904 -242.944904)
				(xy 33.775904 -243.049552) (xy 34.064448 -243.338096) (xy 34.169096 -243.338096) (xy 34.417 -243.586)
				(xy 34.417 -244.729) (xy 39.243 -244.729) (xy 39.243 -243.713)
			)
		)
		(polygon
			(pts
				(xy 30.1752 -239.2172) (xy 28.067 -239.2172) (xy 27.1526 -240.1316) (xy 27.1526 -241.554) (xy 27.94 -242.3414)
				(xy 30.1244 -242.3414) (xy 30.353 -242.1128) (xy 30.353 -239.395)
			)
		)
		(polygon
			(pts
				(xy 21.082 -239.141) (xy 15.113 -239.141) (xy 14.605 -239.649) (xy 14.605 -245.999) (xy 14.478 -246.126)
				(xy 14.097 -246.126) (xy 13.7922 -246.4308) (xy 13.081 -246.4308) (xy 12.573 -246.9388) (xy 12.573 -247.7008)
				(xy 12.8524 -247.9802) (xy 13.4366 -247.9802) (xy 13.716 -248.2596) (xy 13.716 -248.92) (xy 14.097 -249.301)
				(xy 14.097 -249.428) (xy 14.605 -249.936) (xy 18.669 -249.936) (xy 18.669 -251.079) (xy 18.923 -251.333)
				(xy 22.987 -251.333) (xy 24.765 -249.555) (xy 26.035 -249.555) (xy 26.67 -248.92) (xy 26.67 -245.618)
				(xy 24.638 -243.586) (xy 24.511 -243.586) (xy 24.384 -243.713) (xy 22.606 -243.713) (xy 21.082 -242.189)
				(xy 21.082 -240.03) (xy 21.463 -239.649) (xy 21.463 -239.522)
			)
		)
		(polygon
			(pts
				(xy 15.875 -225.171) (xy 13.2334 -225.171) (xy 12.5349 -225.8695) (xy 12.5095 -225.8695) (xy 11.303 -227.076)
				(xy 11.303 -229.235) (xy 14.859 -232.791) (xy 14.859 -233.172) (xy 18.542 -229.489) (xy 18.542 -227.838)
			)
		)
		(polygon
			(pts
				(xy 29.083 -214.63) (xy 22.733 -214.63) (xy 21.463 -215.9) (xy 20.828 -215.9) (xy 20.828 -221.742)
				(xy 21.59 -222.504) (xy 24.003 -222.504) (xy 24.892 -223.393) (xy 26.737564 -223.393) (xy 26.737564 -223.79686)
				(xy 26.645108 -223.88957)
				(arc
					(start 26.645108 -224.0534)
					(mid 26.622121 -224.187974)
					(end 26.555954 -224.3074)
				)
				(arc
					(start 26.555954 -224.3074)
					(mid 26.596056 -224.36795)
					(end 26.624788 -224.434654)
				)
				(arc
					(start 26.624788 -224.434654)
					(mid 26.697768 -224.501747)
					(end 26.79319 -224.474786)
				)
				(xy 26.94813 -224.319592)
				(arc
					(start 27.509978 -224.319592)
					(mid 27.592611 -224.277105)
					(end 27.60599 -224.185226)
				)
				(arc
					(start 27.60599 -224.185226)
					(mid 27.589459 -224.120232)
					(end 27.583892 -224.0534)
				)
				(arc
					(start 27.583892 -223.6978)
					(mid 27.592509 -223.614759)
					(end 27.617928 -223.53524)
				)
				(arc
					(start 27.617928 -223.53524)
					(mid 27.60985 -223.438991)
					(end 27.524964 -223.393)
				)
				(arc
					(start 28.812236 -223.393)
					(mid 28.727427 -223.439041)
					(end 28.719272 -223.53524)
				)
				(arc
					(start 28.719272 -223.53524)
					(mid 28.744653 -223.614767)
					(end 28.753308 -223.6978)
				)
				(arc
					(start 28.753308 -224.0534)
					(mid 28.730321 -224.187974)
					(end 28.664154 -224.3074)
				)
				(arc
					(start 28.664154 -224.3074)
					(mid 28.704503 -224.368541)
					(end 28.733242 -224.435924)
				)
				(arc
					(start 28.733242 -224.435924)
					(mid 28.810049 -224.504394)
					(end 28.907232 -224.470722)
				)
				(arc
					(start 28.907232 -224.470722)
					(mid 29.054768 -224.359214)
					(end 29.2354 -224.319592)
				)
				(arc
					(start 29.643578 -224.319592)
					(mid 29.726211 -224.277105)
					(end 29.73959 -224.185226)
				)
				(arc
					(start 29.73959 -224.185226)
					(mid 29.723059 -224.120232)
					(end 29.717492 -224.0534)
				)
				(xy 29.717746 -223.88957) (xy 29.221176 -223.393) (xy 30.226 -223.393) (xy 30.607 -223.012) (xy 30.607 -217.17)
				(xy 29.337 -215.9) (xy 29.337 -214.884)
			)
		)
		(polygon
			(pts
				(arc
					(start 28.84932 -211.74583)
					(mid 28.7782 -211.716739)
					(end 28.70708 -211.74583)
				)
				(arc
					(start 28.70708 -211.74583)
					(mid 28.576224 -211.831768)
					(end 28.4226 -211.861908)
				)
				(xy 28.27655 -211.861908) (xy 27.991816 -212.146642) (xy 27.991816 -213.087458) (xy 27.992324 -213.087966)
				(xy 27.992324 -213.893908) (xy 28.427172 -213.893908) (xy 28.427172 -213.22665) (xy 29.48813 -212.165692)
				(xy 29.801566 -212.165692)
				(arc
					(start 29.816806 -212.149436)
					(mid 29.86812 -212.099662)
					(end 29.924502 -212.05571)
				)
				(xy 29.946092 -212.04047) (xy 29.946092 -211.773262) (xy 29.929328 -211.758022)
				(arc
					(start 29.91612 -211.74583)
					(mid 29.845 -211.716739)
					(end 29.77388 -211.74583)
				)
				(arc
					(start 29.77388 -211.74583)
					(mid 29.643024 -211.831768)
					(end 29.4894 -211.861908)
				)
				(arc
					(start 29.1338 -211.861908)
					(mid 28.980174 -211.831773)
					(end 28.84932 -211.74583)
				)
			)
		)
		(polygon
			(pts
				(xy 27.26563 -210.033108)
				(arc
					(start 26.812748 -210.033108)
					(mid 26.734208 -210.070256)
					(end 26.71318 -210.15452)
				)
				(arc
					(start 26.71318 -210.15452)
					(mid 26.719248 -210.19445)
					(end 26.721308 -210.234784)
				)
				(arc
					(start 26.721308 -210.590384)
					(mid 26.698321 -210.724958)
					(end 26.632154 -210.844384)
				)
				(arc
					(start 26.632154 -210.844384)
					(mid 26.698366 -210.963794)
					(end 26.721308 -211.098384)
				)
				(arc
					(start 26.721308 -211.453984)
					(mid 26.715586 -211.521729)
					(end 26.698702 -211.587588)
				)
				(xy 26.695908 -211.595716) (xy 26.695908 -212.427566)
				(arc
					(start 26.712164 -212.442806)
					(mid 26.854987 -212.633109)
					(end 26.921206 -212.861652)
				)
				(arc
					(start 26.921206 -212.861652)
					(mid 26.95433 -212.927012)
					(end 27.022806 -212.953092)
				)
				(arc
					(start 27.025854 -212.953092)
					(mid 27.097532 -212.923244)
					(end 27.1272 -212.851492)
				)
				(xy 27.1272 -211.788502) (xy 27.660092 -211.25561)
				(arc
					(start 27.660092 -211.0994)
					(mid 27.683079 -210.964826)
					(end 27.749246 -210.8454)
				)
				(arc
					(start 27.749246 -210.8454)
					(mid 27.683034 -210.72599)
					(end 27.660092 -210.5914)
				)
				(xy 27.660092 -210.590384) (xy 27.660346 -210.42757)
			)
		)
		(polygon
			(pts
				(xy 28.216352 -209.416904) (xy 27.604466 -209.416904)
				(arc
					(start 27.589734 -209.431636)
					(mid 27.475609 -209.519856)
					(end 27.343354 -209.577432)
				)
				(arc
					(start 27.343354 -209.577432)
					(mid 27.273535 -209.649853)
					(end 27.300174 -209.74685)
				)
				(xy 27.382978 -209.829654)
				(arc
					(start 27.400758 -209.831432)
					(mid 27.53521 -209.870633)
					(end 27.648408 -209.953098)
				)
				(xy 27.663394 -209.968592) (xy 27.759406 -209.968592)
				(arc
					(start 27.774392 -209.953098)
					(mid 27.908054 -209.861203)
					(end 28.067 -209.828892)
				)
				(xy 28.403296 -209.828892) (xy 28.403296 -209.603848)
			)
		)
		(polygon
			(pts
				(xy 21.59 -177.673) (xy 19.812 -177.673) (xy 19.812 -177.8) (xy 19.939 -177.927) (xy 19.939 -179.578)
				(xy 19.558 -179.959) (xy 19.558 -181.8005) (xy 19.431 -181.9275) (xy 15.6845 -181.9275) (xy 11.049 -186.563)
				(xy 2.794 -186.563) (xy 2.667 -186.69) (xy 2.667 -199.263) (xy 2.921 -199.517) (xy 4.445 -199.517)
				(xy 4.953 -199.009) (xy 4.953 -198.247) (xy 5.207 -197.993) (xy 15.24 -197.993) (xy 17.653 -200.406)
				(xy 21.971 -200.406) (xy 22.225 -200.66) (xy 22.225 -200.406) (xy 22.479 -200.152) (xy 22.479 -199.39)
				(xy 22.733 -199.136) (xy 22.733 -182.753) (xy 22.225 -182.245) (xy 23.241 -181.229) (xy 23.749 -181.229)
				(xy 24.003 -180.975) (xy 24.003 -178.943) (xy 23.622 -178.562) (xy 22.479 -178.562)
			)
		)
		(polygon
			(pts
				(xy 27.7114 -171.1452) (xy 27.6098 -171.1452) (xy 27.559 -171.196) (xy 27.559 -176.276) (xy 27.813 -176.53)
				(xy 28.702 -176.53) (xy 28.829 -176.403) (xy 33.274 -176.403) (xy 33.528 -176.149) (xy 33.528 -171.958)
				(xy 32.893 -171.323) (xy 27.8892 -171.323)
			)
		)
		(polygon
			(pts
				(xy 36.321492 -137.058908) (xy 35.393884 -137.058908) (xy 35.32632 -137.126218)
				(arc
					(start 35.32632 -137.254234)
					(mid 35.319893 -137.326757)
					(end 35.300666 -137.396982)
				)
				(arc
					(start 35.300666 -137.396982)
					(mid 35.312167 -137.49055)
					(end 35.395662 -137.534396)
				)
				(xy 36.321492 -137.534396)
			)
		)
		(polygon
			(pts
				(arc
					(start 8.98652 -67.695572)
					(mid 8.852217 -67.672665)
					(end 8.733028 -67.606672)
				)
				(arc
					(start 8.733028 -67.606672)
					(mid 8.613833 -67.67265)
					(end 8.479536 -67.695572)
				)
				(xy 8.367014 -67.695572) (xy 7.737094 -68.325492)
				(arc
					(start 7.74065 -68.350892)
					(mid 7.747177 -68.423143)
					(end 7.74573 -68.495672)
				)
				(arc
					(start 7.74573 -68.495672)
					(mid 7.77248 -68.572317)
					(end 7.846822 -68.604892)
				)
				(xy 8.011668 -68.604892)
				(arc
					(start 8.019796 -68.602098)
					(mid 8.085649 -68.585175)
					(end 8.1534 -68.579492)
				)
				(arc
					(start 8.509 -68.579492)
					(mid 8.643574 -68.602479)
					(end 8.763 -68.668646)
				)
				(arc
					(start 8.763 -68.668646)
					(mid 8.88241 -68.602434)
					(end 9.017 -68.579492)
				)
				(arc
					(start 9.3726 -68.579492)
					(mid 9.526226 -68.609627)
					(end 9.65708 -68.69557)
				)
				(arc
					(start 9.65708 -68.69557)
					(mid 9.7282 -68.724661)
					(end 9.79932 -68.69557)
				)
				(arc
					(start 9.79932 -68.69557)
					(mid 9.930176 -68.609632)
					(end 10.0838 -68.579492)
				)
				(xy 10.303002 -68.579492)
				(arc
					(start 10.592562 -68.290186)
					(mid 10.614398 -68.179641)
					(end 10.52068 -68.116958)
				)
				(xy 9.652762 -68.116958) (xy 9.23163 -67.695572)
			)
		)
		(polygon
			(pts
				(xy 8.330692 -17.674844) (xy 4.985512 -17.674844)
				(arc
					(start 4.972304 -17.705578)
					(mid 4.766813 -18.010872)
					(end 4.466082 -18.222976)
				)
				(arc
					(start 4.466082 -18.222976)
					(mid 4.437062 -18.261688)
					(end 4.453636 -18.30705)
				)
				(arc
					(start 4.453636 -18.30705)
					(mid 4.474941 -18.326882)
					(end 4.495292 -18.34769)
				)
				(xy 4.510278 -18.363692) (xy 8.711692 -18.363692) (xy 10.273792 -19.925792) (xy 16.928592 -19.925792)
				(xy 16.928592 -18.947892)
				(arc
					(start 18.533872 -18.947892)
					(mid 18.627496 -18.885753)
					(end 18.606516 -18.775426)
				)
				(arc
					(start 18.606516 -18.775426)
					(mid 18.560598 -18.718999)
					(end 18.52549 -18.655284)
				)
				(arc
					(start 18.52549 -18.655284)
					(mid 18.498445 -18.628889)
					(end 18.46072 -18.628614)
				)
				(arc
					(start 18.46072 -18.628614)
					(mid 18.388574 -18.649022)
					(end 18.313908 -18.655792)
				)
				(arc
					(start 17.907254 -18.655792)
					(mid 17.750473 -18.624354)
					(end 17.617948 -18.534888)
				)
				(arc
					(start 17.617948 -18.534888)
					(mid 17.584841 -18.519885)
					(end 17.55013 -18.530824)
				)
				(arc
					(start 17.55013 -18.530824)
					(mid 17.431004 -18.59649)
					(end 17.296892 -18.619216)
				)
				(xy 17.07769 -18.619216) (xy 15.891002 -19.805904) (xy 10.461752 -19.805904)
			)
		)
	)
	(zone
		(layer "F.Cu")
		(hatch none 0.5)
		(connect_pads
			(clearance 0)
		)
		(min_thickness 0.25)
		(keepout
			(tracks allowed)
			(vias allowed)
			(pads allowed)
			(copperpour allowed)
			(footprints allowed)
		)
		(placement
			(enabled no)
			(sheetname "")
		)
		(fill
			(thermal_gap 0.5)
			(thermal_bridge_width 0.5)
			(island_removal_mode 0)
		)
		(polygon
			(pts
				(xy 40.2082 -144.0942) (xy 35.8902 -144.0942) (xy 35.8902 -136.7536) (xy 40.2082 -136.7536)
			)
		)
	)
	(zone
		(net "P3V3_IN")
		(layer "F.Cu")
		(hatch none 0.5)
		(connect_pads
			(clearance 0.5)
		)
		(min_thickness 0.25)
		(fill yes
			(thermal_gap 0.5)
			(thermal_bridge_width 0.5)
			(island_removal_mode 0)
		)
		(polygon
			(pts
				(xy 17.78 -246.634) (xy 14.097 -246.634) (xy 13.97 -246.761) (xy 13.97 -247.777) (xy 14.224 -248.031)
				(xy 14.986 -248.031) (xy 15.113 -248.158) (xy 15.113 -248.285) (xy 17.399 -248.285) (xy 17.526 -248.412)
				(xy 20.066 -248.412) (xy 20.193 -248.285) (xy 20.193 -247.65) (xy 18.796 -247.65)
			)
		)
	)
	(zone
		(net "P12V")
		(layer "F.Cu")
		(hatch none 0.5)
		(connect_pads
			(clearance 0.5)
		)
		(min_thickness 0.25)
		(fill yes
			(thermal_gap 0.5)
			(thermal_bridge_width 0.5)
			(island_removal_mode 0)
		)
		(polygon
			(pts
				(xy 27.686 -180.848) (xy 23.114 -180.848) (xy 22.4536 -181.5084) (xy 22.4536 -207.2386) (xy 22.606 -207.391)
				(xy 27.178 -207.391) (xy 28.1686 -206.4004) (xy 28.1686 -181.3306)
			)
		)
	)
	(zone
		(net "GND")
		(layer "F.Cu")
		(hatch none 0.5)
		(connect_pads
			(clearance 0.5)
		)
		(min_thickness 0.25)
		(fill yes
			(thermal_gap 0.5)
			(thermal_bridge_width 0.5)
			(island_removal_mode 0)
		)
		(polygon
			(pts
				(xy 17.018 -289.687) (xy 15.621 -289.687) (xy 15.113 -290.195) (xy 15.113 -293.497) (xy 15.748 -294.132)
				(xy 17.399 -294.132) (xy 17.78 -293.751) (xy 17.78 -290.449)
			)
		)
	)
	(zone
		(net "P3V3_AUX_BJT_B")
		(layer "F.Cu")
		(hatch none 0.5)
		(connect_pads
			(clearance 0.5)
		)
		(min_thickness 0.25)
		(fill yes
			(thermal_gap 0.5)
			(thermal_bridge_width 0.5)
			(island_removal_mode 0)
		)
		(polygon
			(pts
				(xy 35.052 -179.07) (xy 32.385 -179.07) (xy 32.131 -179.324) (xy 32.131 -181.483) (xy 30.734 -182.88)
				(xy 30.099 -182.88) (xy 29.21 -183.769) (xy 29.21 -184.404) (xy 29.464 -184.658) (xy 30.48 -184.658)
				(xy 31.115 -184.023) (xy 33.655 -184.023) (xy 34.036 -183.642) (xy 34.036 -182.245) (xy 34.798 -181.483)
				(xy 35.179 -181.483) (xy 35.2425 -181.4195) (xy 35.2425 -179.2605)
			)
		)
	)
	(zone
		(layer "F.Cu")
		(hatch none 0.5)
		(connect_pads
			(clearance 0)
		)
		(min_thickness 0.25)
		(keepout
			(tracks allowed)
			(vias allowed)
			(pads allowed)
			(copperpour allowed)
			(footprints not_allowed)
		)
		(placement
			(enabled no)
			(sheetname "")
		)
		(fill
			(thermal_gap 0.5)
			(thermal_bridge_width 0.5)
			(island_removal_mode 0)
		)
		(polygon
			(pts
				(arc
					(start 45.500036 -140.999972)
					(mid 49.500028 -144.999964)
					(end 45.500036 -148.999956)
				)
				(arc
					(start 45.500036 -148.999956)
					(mid 41.500044 -144.999964)
					(end 45.500036 -140.999972)
				)
			)
		)
	)
	(zone
		(net "P12V_FAN3")
		(layer "F.Cu")
		(hatch none 0.5)
		(connect_pads
			(clearance 0.5)
		)
		(min_thickness 0.25)
		(fill yes
			(thermal_gap 0.5)
			(thermal_bridge_width 0.5)
			(island_removal_mode 0)
		)
		(polygon
			(pts
				(xy 18.034 -263.652) (xy 13.081 -263.652) (xy 12.573 -264.16) (xy 12.573 -297.434) (xy 7.493 -302.514)
				(xy 7.493 -305.943) (xy 5.461 -307.975) (xy 2.667 -307.975) (xy 2.032 -308.61) (xy 2.032 -310.134)
				(xy 2.54 -310.642) (xy 5.842 -310.642) (xy 9.398 -307.086) (xy 9.398 -303.53) (xy 14.732 -298.196)
				(xy 14.732 -275.30425) (xy 15.875 -274.16125) (xy 17.93875 -274.16125) (xy 18.161 -273.939) (xy 18.161 -263.779)
			)
		)
	)
	(zone
		(layer "F.Cu")
		(hatch none 0.5)
		(connect_pads
			(clearance 0)
		)
		(min_thickness 0.25)
		(keepout
			(tracks allowed)
			(vias allowed)
			(pads allowed)
			(copperpour allowed)
			(footprints allowed)
		)
		(placement
			(enabled no)
			(sheetname "")
		)
		(fill
			(thermal_gap 0.5)
			(thermal_bridge_width 0.5)
			(island_removal_mode 0)
		)
		(polygon
			(pts
				(xy 40.6908 -136.906) (xy 40.6908 -136.0678) (xy 42.037 -136.0678) (xy 42.037 -136.906)
			)
		)
	)
	(zone
		(net "P12V")
		(layer "F.Cu")
		(hatch none 0.5)
		(connect_pads
			(clearance 0.5)
		)
		(min_thickness 0.25)
		(fill yes
			(thermal_gap 0.5)
			(thermal_bridge_width 0.5)
			(island_removal_mode 0)
		)
		(polygon
			(pts
				(xy 26.9748 -11.8364) (xy 21.9456 -11.8364) (xy 21.1836 -12.5984) (xy 21.1836 -13.3604) (xy 22.1742 -14.351)
				(xy 23.9776 -14.351) (xy 24.1046 -14.478) (xy 24.1046 -19.177) (xy 21.336 -19.177) (xy 21.209 -19.304)
				(xy 21.209 -19.812) (xy 21.1455 -19.8755) (xy 21.1455 -29.2481) (xy 21.4122 -29.5148) (xy 27.559 -29.5148)
				(xy 30.3784 -26.6954) (xy 30.3784 -15.24)
			)
		)
	)
	(zone
		(layer "F.Cu")
		(hatch none 0.5)
		(connect_pads
			(clearance 0)
		)
		(min_thickness 0.25)
		(keepout
			(tracks allowed)
			(vias allowed)
			(pads allowed)
			(copperpour allowed)
			(footprints not_allowed)
		)
		(placement
			(enabled no)
			(sheetname "")
		)
		(fill
			(thermal_gap 0.5)
			(thermal_bridge_width 0.5)
			(island_removal_mode 0)
		)
		(polygon
			(pts
				(arc
					(start 6.999986 -35.999928)
					(mid 10.999978 -39.99992)
					(end 6.999986 -43.999912)
				)
				(arc
					(start 6.999986 -43.999912)
					(mid 2.999994 -39.99992)
					(end 6.999986 -35.999928)
				)
			)
		)
	)
	(zone
		(layer "F.Cu")
		(hatch none 0.5)
		(connect_pads
			(clearance 0)
		)
		(min_thickness 0.25)
		(keepout
			(tracks allowed)
			(vias allowed)
			(pads allowed)
			(copperpour allowed)
			(footprints not_allowed)
		)
		(placement
			(enabled no)
			(sheetname "")
		)
		(fill
			(thermal_gap 0.5)
			(thermal_bridge_width 0.5)
			(island_removal_mode 0)
		)
		(polygon
			(pts
				(arc
					(start 6.999986 -456.000104)
					(mid 10.999978 -460.000096)
					(end 6.999986 -464.000088)
				)
				(arc
					(start 6.999986 -464.000088)
					(mid 2.999994 -460.000096)
					(end 6.999986 -456.000104)
				)
			)
		)
	)
	(zone
		(net "P12V")
		(layer "F.Cu")
		(hatch none 0.5)
		(connect_pads
			(clearance 0.5)
		)
		(min_thickness 0.25)
		(fill yes
			(thermal_gap 0.5)
			(thermal_bridge_width 0.5)
			(island_removal_mode 0)
		)
		(polygon
			(pts
				(xy 36.322 -476.504) (xy 17.907 -476.504) (xy 17.526 -476.885) (xy 17.526 -480.568) (xy 18.415 -481.457)
				(xy 34.925 -481.457) (xy 36.576 -479.806) (xy 36.576 -476.758)
			)
		)
	)
	(zone
		(layer "F.Cu")
		(hatch none 0.5)
		(connect_pads
			(clearance 0)
		)
		(min_thickness 0.25)
		(keepout
			(tracks allowed)
			(vias allowed)
			(pads allowed)
			(copperpour allowed)
			(footprints not_allowed)
		)
		(placement
			(enabled no)
			(sheetname "")
		)
		(fill
			(thermal_gap 0.5)
			(thermal_bridge_width 0.5)
			(island_removal_mode 0)
		)
		(polygon
			(pts
				(arc
					(start 4.500118 -336.00009)
					(mid 8.50011 -340.000082)
					(end 4.500118 -344.000074)
				)
				(arc
					(start 4.500118 -344.000074)
					(mid 0.500126 -340.000082)
					(end 4.500118 -336.00009)
				)
			)
		)
	)
	(zone
		(layer "F.Cu")
		(hatch none 0.5)
		(connect_pads
			(clearance 0)
		)
		(min_thickness 0.25)
		(keepout
			(tracks allowed)
			(vias allowed)
			(pads allowed)
			(copperpour allowed)
			(footprints not_allowed)
		)
		(placement
			(enabled no)
			(sheetname "")
		)
		(fill
			(thermal_gap 0.5)
			(thermal_bridge_width 0.5)
			(island_removal_mode 0)
		)
		(polygon
			(pts
				(arc
					(start 45.500036 -15.999968)
					(mid 49.500028 -19.99996)
					(end 45.500036 -23.999952)
				)
				(arc
					(start 45.500036 -23.999952)
					(mid 41.500044 -19.99996)
					(end 45.500036 -15.999968)
				)
			)
		)
	)
	(zone
		(layer "F.Cu")
		(hatch none 0.5)
		(connect_pads
			(clearance 0)
		)
		(min_thickness 0.25)
		(keepout
			(tracks allowed)
			(vias allowed)
			(pads allowed)
			(copperpour allowed)
			(footprints not_allowed)
		)
		(placement
			(enabled no)
			(sheetname "")
		)
		(fill
			(thermal_gap 0.5)
			(thermal_bridge_width 0.5)
			(island_removal_mode 0)
		)
		(polygon
			(pts
				(arc
					(start 45.500036 -148.999956)
					(mid 41.500044 -144.999964)
					(end 45.500036 -140.999972)
				)
				(arc
					(start 45.500036 -140.999972)
					(mid 49.500028 -144.999964)
					(end 45.500036 -148.999956)
				)
			)
		)
	)
	(zone
		(net "P3V3")
		(layer "F.Cu")
		(hatch none 0.5)
		(connect_pads
			(clearance 0.5)
		)
		(min_thickness 0.25)
		(fill yes
			(thermal_gap 0.5)
			(thermal_bridge_width 0.5)
			(island_removal_mode 0)
		)
		(polygon
			(pts
				(xy 28.702 -357.251) (xy 27.051 -357.251) (xy 26.924 -357.378) (xy 26.924 -358.1654) (xy 26.67 -358.4194)
				(xy 26.3906 -358.4194) (xy 26.2382 -358.5718) (xy 26.2382 -360.934) (xy 26.416 -361.1118) (xy 26.924 -361.1118)
				(xy 27.1018 -360.934) (xy 27.1018 -359.6894) (xy 27.3304 -359.4608) (xy 28.575 -359.4608) (xy 29.6164 -360.5022)
				(xy 29.6164 -361.0864) (xy 29.718 -361.188) (xy 30.353 -361.188) (xy 30.48 -361.061) (xy 30.48 -359.791)
				(xy 28.829 -358.14) (xy 28.829 -357.378)
			)
		)
	)
	(zone
		(net "P12V_FAN4")
		(layer "F.Cu")
		(hatch none 0.5)
		(connect_pads
			(clearance 0.5)
		)
		(min_thickness 0.25)
		(fill yes
			(thermal_gap 0.5)
			(thermal_bridge_width 0.5)
			(island_removal_mode 0)
		)
		(polygon
			(pts
				(xy 20.574 -189.23) (xy 17.653 -189.23) (xy 17.018 -189.865) (xy 17.018 -193.04) (xy 16.002 -194.056)
				(xy 3.429 -194.056) (xy 2.54 -194.945) (xy 2.54 -196.723) (xy 3.175 -197.358) (xy 15.24 -197.358)
				(xy 17.78 -199.898) (xy 20.574 -199.898) (xy 21.336 -199.136) (xy 21.336 -195.4276) (xy 21.1582 -195.2498)
				(xy 21.1582 -189.8142)
			)
		)
	)
	(zone
		(layer "F.Cu")
		(hatch none 0.5)
		(connect_pads
			(clearance 0)
		)
		(min_thickness 0.25)
		(keepout
			(tracks allowed)
			(vias allowed)
			(pads allowed)
			(copperpour allowed)
			(footprints allowed)
		)
		(placement
			(enabled no)
			(sheetname "")
		)
		(fill
			(thermal_gap 0.5)
			(thermal_bridge_width 0.5)
			(island_removal_mode 0)
		)
		(polygon
			(pts
				(xy 25.1968 -370.1288) (xy 25.1968 -368.7572) (xy 27.686 -368.7572) (xy 27.686 -370.1288)
			)
		)
	)
	(zone
		(net "P12VU")
		(layer "F.Cu")
		(hatch none 0.5)
		(connect_pads
			(clearance 0.5)
		)
		(min_thickness 0.25)
		(fill yes
			(thermal_gap 0.5)
			(thermal_bridge_width 0.5)
			(island_removal_mode 0)
		)
		(polygon
			(pts
				(xy 28.3718 -64.5414) (xy 19.9136 -64.5414) (xy 18.3134 -66.1416) (xy 18.3134 -71.4248) (xy 17.4752 -72.263)
				(xy 10.414 -72.263) (xy 9.652 -73.025) (xy 9.652 -80.137) (xy 11.43 -81.915) (xy 11.43 -88.519)
				(xy 9.8425 -90.1065) (xy 9.8425 -110.5535) (xy 11.938 -112.649) (xy 27.432 -112.649) (xy 27.559 -112.522)
				(xy 27.559 -110.744) (xy 27.305 -110.49) (xy 26.162 -110.49) (xy 24.13 -108.458) (xy 24.13 -95.3262)
				(xy 24.1554 -95.3008) (xy 24.1554 -95.2246) (xy 23.495 -94.5642) (xy 23.495 -89.5858) (xy 23.9268 -89.154)
				(xy 26.289 -89.154) (xy 27.051 -88.392) (xy 27.051 -80.391) (xy 30.48 -76.962) (xy 30.48 -66.6496)
			)
		)
	)
	(zone
		(layer "F.Cu")
		(hatch none 0.5)
		(connect_pads
			(clearance 0)
		)
		(min_thickness 0.25)
		(keepout
			(tracks allowed)
			(vias allowed)
			(pads allowed)
			(copperpour allowed)
			(footprints not_allowed)
		)
		(placement
			(enabled no)
			(sheetname "")
		)
		(fill
			(thermal_gap 0.5)
			(thermal_bridge_width 0.5)
			(island_removal_mode 0)
		)
		(polygon
			(pts
				(arc
					(start 6.999986 -155.999942)
					(mid 10.999978 -159.999934)
					(end 6.999986 -163.999926)
				)
				(arc
					(start 6.999986 -163.999926)
					(mid 2.999994 -159.999934)
					(end 6.999986 -155.999942)
				)
			)
		)
	)
	(zone
		(net "P12VU_NET")
		(layer "F.Cu")
		(hatch none 0.5)
		(connect_pads
			(clearance 0.5)
		)
		(min_thickness 0.25)
		(fill yes
			(thermal_gap 0.5)
			(thermal_bridge_width 0.5)
			(island_removal_mode 0)
		)
		(polygon
			(pts
				(xy 30.1625 -112.8395) (xy 10.6045 -112.8395) (xy 10.287 -113.157) (xy 10.287 -121.031) (xy 10.922 -121.666)
				(xy 24.638 -121.666) (xy 24.7015 -121.6025) (xy 30.6705 -121.6025) (xy 31.623 -120.65) (xy 31.623 -114.3)
			)
		)
	)
	(zone
		(layer "F.Cu")
		(hatch none 0.5)
		(connect_pads
			(clearance 0)
		)
		(min_thickness 0.25)
		(keepout
			(tracks allowed)
			(vias allowed)
			(pads allowed)
			(copperpour allowed)
			(footprints not_allowed)
		)
		(placement
			(enabled no)
			(sheetname "")
		)
		(fill
			(thermal_gap 0.5)
			(thermal_bridge_width 0.5)
			(island_removal_mode 0)
		)
		(polygon
			(pts
				(arc
					(start 4.500118 -344.000074)
					(mid 0.500126 -340.000082)
					(end 4.500118 -336.00009)
				)
				(arc
					(start 4.500118 -336.00009)
					(mid 8.50011 -340.000082)
					(end 4.500118 -344.000074)
				)
			)
		)
	)
	(zone
		(layer "F.Cu")
		(hatch none 0.5)
		(connect_pads
			(clearance 0)
		)
		(min_thickness 0.25)
		(keepout
			(tracks allowed)
			(vias allowed)
			(pads allowed)
			(copperpour allowed)
			(footprints not_allowed)
		)
		(placement
			(enabled no)
			(sheetname "")
		)
		(fill
			(thermal_gap 0.5)
			(thermal_bridge_width 0.5)
			(island_removal_mode 0)
		)
		(polygon
			(pts
				(arc
					(start 6.999986 -163.999926)
					(mid 2.999994 -159.999934)
					(end 6.999986 -155.999942)
				)
				(arc
					(start 6.999986 -155.999942)
					(mid 10.999978 -159.999934)
					(end 6.999986 -163.999926)
				)
			)
		)
	)
	(zone
		(layer "F.Cu")
		(hatch none 0.5)
		(connect_pads
			(clearance 0)
		)
		(min_thickness 0.25)
		(keepout
			(tracks allowed)
			(vias allowed)
			(pads allowed)
			(copperpour allowed)
			(footprints not_allowed)
		)
		(placement
			(enabled no)
			(sheetname "")
		)
		(fill
			(thermal_gap 0.5)
			(thermal_bridge_width 0.5)
			(island_removal_mode 0)
		)
		(polygon
			(pts
				(arc
					(start 16.500094 0)
					(mid 17.207199 -0.292893)
					(end 17.500092 -0.999998)
				)
				(arc
					(start 17.500092 -8.999982)
					(mid 17.792985 -9.707087)
					(end 18.50009 -9.99998)
				)
				(arc
					(start 51.500024 -9.99998)
					(mid 52.207129 -10.292873)
					(end 52.500022 -10.999978)
				)
				(arc
					(start 52.500022 -489.000038)
					(mid 52.207129 -489.707143)
					(end 51.500024 -490.000036)
				)
				(arc
					(start 18.50009 -490.000036)
					(mid 17.792985 -490.292929)
					(end 17.500092 -491.000034)
				)
				(arc
					(start 17.500092 -499.000018)
					(mid 17.207199 -499.707123)
					(end 16.500094 -500.000016)
				)
				(arc
					(start 0.999998 -500.000016)
					(mid 0.612674 -499.92196)
					(end 0.28575 -499.700042)
				)
				(arc
					(start 13.5001 -499.700042)
					(mid 15.267789 -498.967683)
					(end 15.999968 -497.19992)
				)
				(arc
					(start 15.999968 -468.199978)
					(mid 15.267774 -466.432304)
					(end 13.5001 -465.70011)
				)
				(xy 0 -465.70011) (xy 0 -389.659876)
				(arc
					(start 13.5001 -389.659876)
					(mid 15.267774 -388.927682)
					(end 15.999968 -387.160008)
				)
				(arc
					(start 15.999968 -358.160066)
					(mid 15.267789 -356.392303)
					(end 13.5001 -355.659944)
				)
				(xy 0 -355.659944) (xy 0 -323.660008)
				(arc
					(start 13.5001 -323.660008)
					(mid 15.267863 -322.927724)
					(end 15.999968 -321.159886)
				)
				(arc
					(start 15.999968 -292.159944)
					(mid 15.267774 -290.39227)
					(end 13.5001 -289.660076)
				)
				(xy 0 -289.660076) (xy 0 -210.33994)
				(arc
					(start 13.5001 -210.33994)
					(mid 15.267774 -209.607746)
					(end 15.999968 -207.840072)
				)
				(arc
					(start 15.999968 -178.839876)
					(mid 15.267774 -177.072202)
					(end 13.5001 -176.340008)
				)
				(xy 0 -176.340008) (xy 0 -144.340072)
				(arc
					(start 13.5001 -144.340072)
					(mid 15.267789 -143.607713)
					(end 15.999968 -141.83995)
				)
				(arc
					(start 15.999968 -112.840008)
					(mid 15.267789 -111.072245)
					(end 13.5001 -110.339886)
				)
				(xy 0 -110.339886) (xy 0 -34.299906)
				(arc
					(start 13.5001 -34.299906)
					(mid 15.267774 -33.567712)
					(end 15.999968 -31.800038)
				)
				(arc
					(start 15.999968 -2.800096)
					(mid 15.267789 -1.032333)
					(end 13.5001 -0.299974)
				)
				(arc
					(start 0.28575 -0.299974)
					(mid 0.612638 -0.07797)
					(end 0.999998 0)
				)
			)
		)
	)
	(zone
		(net "GND")
		(layer "F.Cu")
		(hatch none 0.5)
		(connect_pads
			(clearance 0.5)
		)
		(min_thickness 0.25)
		(fill yes
			(thermal_gap 0.5)
			(thermal_bridge_width 0.5)
			(island_removal_mode 0)
		)
		(polygon
			(pts
				(xy 32.766 -143.764) (xy 29.845 -143.764) (xy 29.718 -143.891) (xy 29.718 -145.034) (xy 30.226 -145.542)
				(xy 30.226 -148.717) (xy 30.607 -149.098) (xy 33.528 -149.098) (xy 34.671 -150.241) (xy 35.687 -150.241)
				(xy 36.83 -151.384) (xy 36.83 -154.686) (xy 36.957 -154.813) (xy 37.338 -154.813) (xy 37.592 -154.559)
				(xy 37.592 -153.924) (xy 37.846 -153.67) (xy 39.243 -153.67) (xy 39.37 -153.543) (xy 39.37 -153.416)
				(xy 40.005 -152.781) (xy 40.005 -151.003) (xy 37.6936 -148.6916) (xy 36.2712 -148.6916) (xy 35.0647 -147.4851)
				(xy 35.0647 -146.0627)
			)
		)
	)
	(zone
		(layer "F.Cu")
		(hatch none 0.5)
		(connect_pads
			(clearance 0)
		)
		(min_thickness 0.25)
		(keepout
			(tracks allowed)
			(vias allowed)
			(pads allowed)
			(copperpour allowed)
			(footprints allowed)
		)
		(placement
			(enabled no)
			(sheetname "")
		)
		(fill
			(thermal_gap 0.5)
			(thermal_bridge_width 0.5)
			(island_removal_mode 0)
		)
		(polygon
			(pts
				(xy 32.0548 -370.1288) (xy 32.0548 -368.7572) (xy 33.7058 -368.7572) (xy 33.7058 -370.1288)
			)
		)
	)
	(zone
		(net "P12V")
		(layer "F.Cu")
		(hatch none 0.5)
		(connect_pads
			(clearance 0.5)
		)
		(min_thickness 0.25)
		(fill yes
			(thermal_gap 0.5)
			(thermal_bridge_width 0.5)
			(island_removal_mode 0)
		)
		(polygon
			(pts
				(xy 20.574 -158.115) (xy 12.5984 -158.115) (xy 11.9888 -158.7246) (xy 11.9888 -161.29) (xy 9.271 -164.0078)
				(xy 9.271 -171.323) (xy 10.287 -172.339) (xy 14.224 -172.339) (xy 15.367 -171.196) (xy 15.367 -166.497)
				(xy 17.526 -164.338) (xy 19.6088 -164.338) (xy 21.5519 -162.3949) (xy 21.5519 -159.0929)
			)
		)
	)
	(zone
		(net "GND")
		(layer "F.Cu")
		(hatch none 0.5)
		(connect_pads
			(clearance 0.5)
		)
		(min_thickness 0.25)
		(fill yes
			(thermal_gap 0.5)
			(thermal_bridge_width 0.5)
			(island_removal_mode 0)
		)
		(polygon
			(pts
				(xy 21.1582 -133.9342) (xy 6.9596 -133.9342) (xy 6.858 -134.0358) (xy 6.858 -135.636) (xy 8.509 -137.287)
				(xy 8.509 -142.113) (xy 8.89 -142.494) (xy 14.859 -142.494) (xy 15.494 -143.129) (xy 18.415 -143.129)
				(xy 19.304 -144.018) (xy 20.193 -144.018) (xy 20.193 -143.891) (xy 20.828 -143.256) (xy 20.828 -141.605)
				(xy 20.701 -141.478) (xy 18.669 -141.478) (xy 18.161 -140.97) (xy 18.161 -136.271) (xy 18.669 -135.763)
				(xy 21.209 -135.763) (xy 21.59 -135.382) (xy 21.59 -134.366)
			)
		)
	)
	(zone
		(net "GND")
		(layer "F.Cu")
		(hatch none 0.5)
		(connect_pads
			(clearance 0.5)
		)
		(min_thickness 0.25)
		(fill yes
			(thermal_gap 0.5)
			(thermal_bridge_width 0.5)
			(island_removal_mode 0)
		)
		(polygon
			(pts
				(xy 16.129 -475.996) (xy 13.335 -475.996) (xy 8.001 -481.33) (xy 6.604 -481.33) (xy 6.35 -481.584)
				(xy 6.35 -482.473) (xy 6.858 -482.981) (xy 7.493 -482.981) (xy 8.255 -483.743) (xy 14.351 -483.743)
				(xy 17.272 -480.822) (xy 17.272 -477.139)
			)
		)
	)
	(zone
		(layers "F.Cu" "B.Cu" "In1.Cu" "In2.Cu")
		(name "Package Keepin")
		(hatch none 0.5)
		(connect_pads
			(clearance 0)
		)
		(min_thickness 0.25)
		(keepout
			(tracks allowed)
			(vias allowed)
			(pads allowed)
			(copperpour allowed)
			(footprints allowed)
		)
		(placement
			(enabled no)
			(sheetname "")
		)
		(fill
			(thermal_gap 0.5)
			(thermal_bridge_width 0.5)
			(island_removal_mode 0)
		)
		(polygon
			(pts
				(xy 13.436092 -4.064) (xy 4.064 -4.064) (xy 4.064 -495.936016) (xy 13.436092 -495.936016)
				(arc
					(start 13.436092 -491.000034)
					(mid 14.919303 -487.419247)
					(end 18.50009 -485.936036)
				)
				(xy 48.436022 -485.936036) (xy 48.436022 -14.06398)
				(arc
					(start 18.50009 -14.06398)
					(mid 14.919303 -12.580769)
					(end 13.436092 -8.999982)
				)
			)
		)
	)
	(zone
		(layers "F.Cu" "B.Cu" "In1.Cu" "In2.Cu")
		(name "Route Keepin")
		(hatch none 0.5)
		(connect_pads
			(clearance 0)
		)
		(min_thickness 0.25)
		(keepout
			(tracks allowed)
			(vias allowed)
			(pads allowed)
			(copperpour allowed)
			(footprints allowed)
		)
		(placement
			(enabled no)
			(sheetname "")
		)
		(fill
			(thermal_gap 0.5)
			(thermal_bridge_width 0.5)
			(island_removal_mode 0)
		)
		(polygon
			(pts
				(arc
					(start 0.999998 -0.762)
					(mid 0.831708 -0.831708)
					(end 0.762 -0.999998)
				)
				(arc
					(start 0.762 -499.000018)
					(mid 0.831708 -499.168308)
					(end 0.999998 -499.238016)
				)
				(arc
					(start 16.500094 -499.238016)
					(mid 16.668384 -499.168308)
					(end 16.738092 -499.000018)
				)
				(arc
					(start 16.738092 -491.000034)
					(mid 17.254169 -489.754113)
					(end 18.50009 -489.238036)
				)
				(arc
					(start 51.500024 -489.238036)
					(mid 51.668314 -489.168328)
					(end 51.738022 -489.000038)
				)
				(arc
					(start 51.738022 -10.999978)
					(mid 51.668314 -10.831688)
					(end 51.500024 -10.76198)
				)
				(arc
					(start 18.50009 -10.76198)
					(mid 17.254169 -10.245903)
					(end 16.738092 -8.999982)
				)
				(arc
					(start 16.738092 -0.999998)
					(mid 16.668384 -0.831708)
					(end 16.500094 -0.762)
				)
			)
		)
	)
	(zone
		(layer "B.Cu")
		(hatch none 0.5)
		(connect_pads
			(clearance 0)
		)
		(min_thickness 0.25)
		(keepout
			(tracks allowed)
			(vias allowed)
			(pads allowed)
			(copperpour allowed)
			(footprints not_allowed)
		)
		(placement
			(enabled no)
			(sheetname "")
		)
		(fill
			(thermal_gap 0.5)
			(thermal_bridge_width 0.5)
			(island_removal_mode 0)
		)
		(polygon
			(pts
				(arc
					(start 7.599934 -313.660028)
					(mid 3.599942 -317.66002)
					(end 7.599934 -321.660012)
				)
				(arc
					(start 7.599934 -321.660012)
					(mid 11.599926 -317.66002)
					(end 7.599934 -313.660028)
				)
			)
		)
	)
	(zone
		(layer "B.Cu")
		(hatch none 0.5)
		(connect_pads
			(clearance 0)
		)
		(min_thickness 0.25)
		(keepout
			(tracks allowed)
			(vias allowed)
			(pads allowed)
			(copperpour allowed)
			(footprints not_allowed)
		)
		(placement
			(enabled no)
			(sheetname "")
		)
		(fill
			(thermal_gap 0.5)
			(thermal_bridge_width 0.5)
			(island_removal_mode 0)
		)
		(polygon
			(pts
				(arc
					(start 7.599934 -475.70009)
					(mid 11.599926 -471.700098)
					(end 7.599934 -467.700106)
				)
				(arc
					(start 7.599934 -467.700106)
					(mid 3.599942 -471.700098)
					(end 7.599934 -475.70009)
				)
			)
		)
	)
	(zone
		(layer "B.Cu")
		(hatch none 0.5)
		(connect_pads
			(clearance 0)
		)
		(min_thickness 0.25)
		(keepout
			(tracks allowed)
			(vias allowed)
			(pads allowed)
			(copperpour allowed)
			(footprints not_allowed)
		)
		(placement
			(enabled no)
			(sheetname "")
		)
		(fill
			(thermal_gap 0.5)
			(thermal_bridge_width 0.5)
			(island_removal_mode 0)
		)
		(polygon
			(pts
				(arc
					(start 7.599934 -489.700062)
					(mid 3.599942 -493.700054)
					(end 7.599934 -497.700046)
				)
				(arc
					(start 7.599934 -497.700046)
					(mid 11.599926 -493.700054)
					(end 7.599934 -489.700062)
				)
			)
		)
	)
	(zone
		(layer "B.Cu")
		(hatch none 0.5)
		(connect_pads
			(clearance 0)
		)
		(min_thickness 0.25)
		(keepout
			(tracks allowed)
			(vias allowed)
			(pads allowed)
			(copperpour allowed)
			(footprints not_allowed)
		)
		(placement
			(enabled no)
			(sheetname "")
		)
		(fill
			(thermal_gap 0.5)
			(thermal_bridge_width 0.5)
			(island_removal_mode 0)
		)
		(polygon
			(pts
				(arc
					(start 7.599934 -299.660056)
					(mid 11.599926 -295.660064)
					(end 7.599934 -291.660072)
				)
				(arc
					(start 7.599934 -291.660072)
					(mid 3.599942 -295.660064)
					(end 7.599934 -299.660056)
				)
			)
		)
	)
	(zone
		(layer "B.Cu")
		(hatch none 0.5)
		(connect_pads
			(clearance 0)
		)
		(min_thickness 0.25)
		(keepout
			(tracks allowed)
			(vias allowed)
			(pads allowed)
			(copperpour allowed)
			(footprints not_allowed)
		)
		(placement
			(enabled no)
			(sheetname "")
		)
		(fill
			(thermal_gap 0.5)
			(thermal_bridge_width 0.5)
			(island_removal_mode 0)
		)
		(polygon
			(pts
				(arc
					(start 7.599934 -2.29997)
					(mid 3.599942 -6.299962)
					(end 7.599934 -10.299954)
				)
				(arc
					(start 7.599934 -10.299954)
					(mid 11.599926 -6.299962)
					(end 7.599934 -2.29997)
				)
			)
		)
	)
	(zone
		(layer "B.Cu")
		(hatch none 0.5)
		(connect_pads
			(clearance 0)
		)
		(min_thickness 0.25)
		(keepout
			(tracks allowed)
			(vias allowed)
			(pads allowed)
			(copperpour allowed)
			(footprints not_allowed)
		)
		(placement
			(enabled no)
			(sheetname "")
		)
		(fill
			(thermal_gap 0.5)
			(thermal_bridge_width 0.5)
			(island_removal_mode 0)
		)
		(polygon
			(pts
				(arc
					(start 6.999986 -155.999942)
					(mid 2.999994 -159.999934)
					(end 6.999986 -163.999926)
				)
				(arc
					(start 6.999986 -163.999926)
					(mid 10.999978 -159.999934)
					(end 6.999986 -155.999942)
				)
			)
		)
	)
	(zone
		(net "GND")
		(layer "B.Cu")
		(hatch none 0.5)
		(connect_pads
			(clearance 0.5)
		)
		(min_thickness 0.25)
		(fill yes
			(thermal_gap 0.5)
			(thermal_bridge_width 0.5)
			(island_removal_mode 0)
		)
		(polygon
			(pts
				(arc
					(start 0.999998 -0.762254)
					(mid 0.831888 -0.831888)
					(end 0.762254 -0.999998)
				)
				(arc
					(start 0.762254 -499.000018)
					(mid 0.831888 -499.168128)
					(end 0.999998 -499.237762)
				)
				(arc
					(start 16.500094 -499.237762)
					(mid 16.668204 -499.168128)
					(end 16.737838 -499.000018)
				)
				(arc
					(start 16.737838 -491.000034)
					(mid 17.25399 -489.753934)
					(end 18.50009 -489.237782)
				)
				(arc
					(start 51.500024 -489.237782)
					(mid 51.668134 -489.168148)
					(end 51.737768 -489.000038)
				)
				(arc
					(start 51.737768 -10.999978)
					(mid 51.668134 -10.831868)
					(end 51.500024 -10.762234)
				)
				(arc
					(start 18.50009 -10.762234)
					(mid 17.25399 -10.246082)
					(end 16.737838 -8.999982)
				)
				(arc
					(start 16.737838 -0.999998)
					(mid 16.668204 -0.831888)
					(end 16.500094 -0.762254)
				)
			)
		)
		(polygon
			(pts
				(arc
					(start 4.76885 -423.077132)
					(mid 4.685224 -423.098958)
					(end 4.648708 -423.177208)
				)
				(arc
					(start 4.648708 -432.903376)
					(mid 4.685453 -432.981583)
					(end 4.769104 -433.003198)
				)
				(arc
					(start 4.769104 -433.003198)
					(mid 4.837667 -432.994537)
					(end 4.906772 -432.994054)
				)
				(xy 4.929124 -432.995324) (xy 5.066792 -432.857402)
				(arc
					(start 5.066792 -423.186098)
					(mid 5.033441 -423.110834)
					(end 4.955286 -423.085006)
				)
				(arc
					(start 4.955286 -423.085006)
					(mid 4.86179 -423.087671)
					(end 4.76885 -423.077132)
				)
			)
		)
		(polygon
			(pts
				(xy 17.653 -407.6192) (xy 16.3068 -407.6192) (xy 15.494 -408.432) (xy 15.494 -409.448) (xy 14.478 -410.464)
				(xy 13.462 -410.464) (xy 12.573 -411.353) (xy 12.573 -415.036) (xy 12.573 -442.722) (xy 14.986 -445.135)
				(xy 14.986 -475.107) (xy 15.748 -475.869) (xy 30.607 -475.869) (xy 33.655 -472.821) (xy 33.655 -453.771)
				(xy 34.544 -452.882) (xy 35.687 -452.882) (xy 36.322 -452.247) (xy 36.322 -451.358) (xy 35.687 -450.723)
				(xy 34.417 -450.723) (xy 33.655 -449.961) (xy 33.655 -425.958) (xy 35.56 -424.053) (xy 46.863 -424.053)
				(xy 47.371 -423.545) (xy 47.371 -415.29) (xy 47.371 -410.845) (xy 46.609 -410.083) (xy 20.1168 -410.083)
			)
		)
		(polygon
			(pts
				(arc
					(start 3.605276 -368.498628)
					(mid 3.507202 -368.504522)
					(end 3.459988 -368.590576)
				)
				(xy 3.459988 -368.92865) (xy 3.694684 -369.163346)
				(arc
					(start 3.724402 -369.153694)
					(mid 4.080912 -369.104238)
					(end 4.4323 -369.182142)
				)
				(arc
					(start 4.4323 -369.182142)
					(mid 4.527727 -369.172936)
					(end 4.573016 -369.088416)
				)
				(arc
					(start 4.573016 -368.611404)
					(mid 4.527749 -368.526851)
					(end 4.4323 -368.517678)
				)
				(arc
					(start 4.4323 -368.517678)
					(mid 4.016758 -368.596111)
					(end 3.605276 -368.498628)
				)
			)
		)
		(polygon
			(pts
				(arc
					(start 38.178486 -365.87938)
					(mid 38.07605 -365.877791)
					(end 38.024308 -365.966248)
				)
				(xy 38.024308 -368.849402)
				(arc
					(start 38.049454 -368.864134)
					(mid 38.280666 -369.088236)
					(end 38.378638 -369.394994)
				)
				(xy 38.379908 -369.414044) (xy 38.429692 -369.464082) (xy 38.474904 -369.41887)
				(arc
					(start 38.47846 -369.406424)
					(mid 38.670998 -369.116299)
					(end 38.994334 -368.98707)
				)
				(xy 39.012876 -368.985546) (xy 38.979856 -369.018566) (xy 39.294308 -369.332764) (xy 39.294308 -369.471448)
				(arc
					(start 39.30142 -369.483386)
					(mid 39.314859 -369.506871)
					(end 39.327328 -369.530884)
				)
				(arc
					(start 39.327328 -369.530884)
					(mid 39.386865 -369.557065)
					(end 39.42334 -369.503198)
				)
				(arc
					(start 39.42334 -369.503198)
					(mid 39.446829 -369.268992)
					(end 39.560754 -369.063016)
				)
				(xy 39.572692 -369.048792) (xy 39.572692 -368.3254)
				(arc
					(start 39.529258 -368.31905)
					(mid 39.43102 -368.297161)
					(end 39.337234 -368.26063)
				)
				(arc
					(start 39.337234 -368.26063)
					(mid 39.239282 -368.266192)
					(end 39.191692 -368.35207)
				)
				(xy 39.191692 -368.165634)
				(arc
					(start 39.175436 -368.150394)
					(mid 38.963079 -367.665)
					(end 39.175436 -367.179606)
				)
				(xy 39.191692 -367.164366) (xy 39.191692 -366.70107) (xy 38.454076 -365.963454)
				(arc
					(start 38.435534 -365.96193)
					(mid 38.302184 -365.935686)
					(end 38.178486 -365.87938)
				)
			)
		)
		(polygon
			(pts
				(arc
					(start 4.07797 -364.958122)
					(mid 3.967425 -364.936286)
					(end 3.904742 -365.030004)
				)
				(arc
					(start 3.904488 -366.46231)
					(mid 3.935422 -366.53531)
					(end 4.00939 -366.56391)
				)
				(arc
					(start 4.00939 -366.56391)
					(mid 4.225029 -366.580405)
					(end 4.4323 -366.642142)
				)
				(arc
					(start 4.4323 -366.642142)
					(mid 4.527727 -366.632936)
					(end 4.573016 -366.548416)
				)
				(xy 4.573016 -365.453422)
			)
		)
		(polygon
			(pts
				(arc
					(start 5.97662 -363.006132)
					(mid 5.863966 -362.975348)
					(end 5.796788 -363.070902)
				)
				(xy 5.796788 -363.177836) (xy 6.771132 -364.151926)
				(arc
					(start 6.771132 -377.565666)
					(mid 6.833768 -377.659498)
					(end 6.94436 -377.637548)
				)
				(xy 7.213092 -377.368562) (xy 7.213092 -366.141508) (xy 9.40308 -363.95152)
				(arc
					(start 9.40308 -363.070902)
					(mid 9.335914 -362.975315)
					(end 9.223248 -363.006132)
				)
				(arc
					(start 9.223248 -363.006132)
					(mid 8.964374 -363.267863)
					(end 8.66394 -363.480604)
				)
				(arc
					(start 8.66394 -363.480604)
					(mid 8.617761 -363.538892)
					(end 8.623808 -363.612938)
				)
				(arc
					(start 8.623808 -363.612938)
					(mid 8.566289 -363.565935)
					(end 8.492236 -363.570774)
				)
				(arc
					(start 8.492236 -363.570774)
					(mid 7.138087 -363.717653)
					(end 5.97662 -363.006132)
				)
			)
		)
		(polygon
			(pts
				(arc
					(start 16.876522 -299.427646)
					(mid 16.821174 -299.416789)
					(end 16.789908 -299.463714)
				)
				(arc
					(start 16.789908 -336.583528)
					(mid 16.852662 -336.677155)
					(end 16.963136 -336.655156)
				)
				(xy 17.042892 -336.5754) (xy 17.042892 -299.809408)
				(arc
					(start 17.030954 -299.795184)
					(mid 16.935048 -299.638935)
					(end 16.89227 -299.460666)
				)
				(xy 16.890746 -299.442124)
			)
		)
		(polygon
			(pts
				(arc
					(start 17.892522 -291.071046)
					(mid 17.837174 -291.060189)
					(end 17.805908 -291.107114)
				)
				(arc
					(start 17.805908 -294.334692)
					(mid 17.835576 -294.406444)
					(end 17.907254 -294.436292)
				)
				(arc
					(start 17.946878 -294.437562)
					(mid 17.98662 -294.422486)
					(end 18.00098 -294.382444)
				)
				(arc
					(start 18.00098 -294.382444)
					(mid 18.034872 -294.127469)
					(end 18.17497 -293.911782)
				)
				(arc
					(start 18.17497 -293.911782)
					(mid 18.205511 -293.839677)
					(end 18.175732 -293.767256)
				)
				(xy 17.931892 -293.52367) (xy 17.931892 -291.11067)
			)
		)
		(polygon
			(pts
				(arc
					(start 32.619696 -259.372354)
					(mid 32.582567 -259.29383)
					(end 32.498284 -259.272532)
				)
				(arc
					(start 32.498284 -259.272532)
					(mid 32.406861 -259.283204)
					(end 32.314896 -259.27939)
				)
				(arc
					(start 32.314896 -259.27939)
					(mid 32.235235 -259.304301)
					(end 32.201104 -259.380482)
				)
				(arc
					(start 32.201104 -274.49018)
					(mid 32.263823 -274.584046)
					(end 32.374586 -274.562062)
				)
				(xy 32.619696 -274.316952)
			)
		)
		(polygon
			(pts
				(arc
					(start 44.329096 -252.20422)
					(mid 44.266377 -252.110354)
					(end 44.155614 -252.132338)
				)
				(xy 37.844476 -258.443476)
				(arc
					(start 37.863526 -258.477004)
					(mid 37.930633 -258.951794)
					(end 37.659056 -259.346954)
				)
				(xy 37.636704 -259.362194)
				(arc
					(start 37.636704 -259.421884)
					(mid 37.699423 -259.51575)
					(end 37.810186 -259.493766)
				)
				(xy 44.329096 -252.97511)
			)
		)
		(polygon
			(pts
				(arc
					(start 37.875718 -248.49836)
					(mid 37.76909 -248.488584)
					(end 37.712904 -248.57964)
				)
				(arc
					(start 37.712904 -251.78258)
					(mid 37.775623 -251.876446)
					(end 37.886386 -251.854462)
				)
				(xy 38.518592 -251.222002)
				(arc
					(start 38.518592 -248.690384)
					(mid 38.478147 -248.609251)
					(end 38.389052 -248.592848)
				)
				(arc
					(start 38.389052 -248.592848)
					(mid 38.121237 -248.606107)
					(end 37.875718 -248.49836)
				)
			)
		)
		(polygon
			(pts
				(arc
					(start 39.706296 -248.167906)
					(mid 39.662957 -248.08467)
					(end 39.569898 -248.072402)
				)
				(arc
					(start 39.569898 -248.072402)
					(mid 39.471619 -248.098782)
					(end 39.370254 -248.107708)
				)
				(arc
					(start 39.370254 -248.107708)
					(mid 39.298576 -248.137556)
					(end 39.268908 -248.209308)
				)
				(arc
					(start 39.268908 -250.86183)
					(mid 39.331544 -250.955662)
					(end 39.442136 -250.933712)
				)
				(xy 39.706296 -250.669552)
			)
		)
		(polygon
			(pts
				(arc
					(start 38.657784 -242.496086)
					(mid 38.621146 -242.501084)
					(end 38.597586 -242.529614)
				)
				(arc
					(start 38.597586 -242.529614)
					(mid 38.397259 -242.81136)
					(end 38.072822 -242.93068)
				)
				(xy 38.053264 -242.931696) (xy 37.712904 -243.272056) (xy 37.712904 -247.646698) (xy 37.785802 -247.646698)
				(xy 37.800788 -247.630696) (xy 37.835332 -247.596914) (xy 37.852096 -247.581928) (xy 37.852096 -243.856002)
				(xy 38.931596 -242.776502)
				(arc
					(start 38.931596 -242.613942)
					(mid 38.900113 -242.540415)
					(end 38.82517 -242.512342)
				)
				(arc
					(start 38.82517 -242.512342)
					(mid 38.740891 -242.510252)
					(end 38.657784 -242.496086)
				)
			)
		)
		(polygon
			(pts
				(arc
					(start 36.802314 -242.487704)
					(mid 36.766754 -242.473195)
					(end 36.731194 -242.487704)
				)
				(xy 36.713668 -242.504214) (xy 36.696904 -242.5192) (xy 36.696904 -251.361448) (xy 32.201104 -255.857248)
				(arc
					(start 32.201104 -256.55778)
					(mid 32.263823 -256.651646)
					(end 32.374586 -256.629662)
				)
				(xy 36.963096 -252.041152) (xy 36.963096 -242.96116)
				(arc
					(start 37.116766 -242.80749)
					(mid 37.142852 -242.708472)
					(end 37.069522 -242.637056)
				)
				(arc
					(start 37.069522 -242.637056)
					(mid 36.925977 -242.580169)
					(end 36.802314 -242.487704)
				)
			)
		)
		(polygon
			(pts
				(arc
					(start 15.830296 -230.263192)
					(mid 15.767459 -230.169531)
					(end 15.656814 -230.191564)
				)
				(xy 15.291308 -230.55707) (xy 15.291308 -231.274366)
				(arc
					(start 15.307564 -231.289606)
					(mid 15.519921 -231.775)
					(end 15.307564 -232.260394)
				)
				(xy 15.291308 -232.275634) (xy 15.291308 -232.97007)
				(arc
					(start 13.71346 -234.547664)
					(mid 13.690945 -234.657272)
					(end 13.782802 -234.721146)
				)
				(arc
					(start 13.782802 -234.721146)
					(mid 13.822271 -234.723269)
					(end 13.861542 -234.72775)
				)
				(xy 13.886942 -234.731306) (xy 15.830296 -232.787952)
			)
		)
		(polygon
			(pts
				(arc
					(start 14.197584 -216.982802)
					(mid 14.085959 -216.957035)
					(end 14.021308 -217.051636)
				)
				(arc
					(start 14.021308 -222.8342)
					(mid 14.052334 -222.907288)
					(end 14.126464 -222.9358)
				)
				(arc
					(start 14.126464 -222.9358)
					(mid 14.162305 -222.935591)
					(end 14.198092 -222.937578)
				)
				(arc
					(start 14.198092 -222.937578)
					(mid 14.275529 -222.911145)
					(end 14.308328 -222.836232)
				)
				(xy 14.308328 -217.07983)
				(arc
					(start 14.288008 -217.06459)
					(mid 14.240911 -217.02578)
					(end 14.197584 -216.982802)
				)
			)
		)
		(polygon
			(pts
				(arc
					(start 29.755846 -212.028786)
					(mid 29.693127 -211.93492)
					(end 29.582364 -211.956904)
				)
				(xy 27.626564 -213.912704) (xy 27.475688 -213.912704)
				(arc
					(start 27.460702 -213.929468)
					(mid 27.078284 -214.120179)
					(end 26.668222 -213.999826)
				)
				(xy 26.654252 -213.988904) (xy 25.925272 -213.988904)
				(arc
					(start 25.910286 -214.005668)
					(mid 25.713844 -214.148191)
					(end 25.476454 -214.198708)
				)
				(arc
					(start 25.476454 -214.198708)
					(mid 25.404776 -214.228556)
					(end 25.375108 -214.300308)
				)
				(arc
					(start 25.375108 -218.85148)
					(mid 25.44003 -218.945975)
					(end 25.551638 -218.919806)
				)
				(arc
					(start 25.551638 -218.919806)
					(mid 25.761504 -218.772589)
					(end 26.014172 -218.729306)
				)
				(xy 26.036524 -218.730576) (xy 26.121614 -218.645232) (xy 26.770584 -218.645232)
				(arc
					(start 26.78557 -218.628722)
					(mid 27.420665 -218.471364)
					(end 27.80411 -219.001594)
				)
				(arc
					(start 27.80411 -219.001594)
					(mid 27.835007 -219.07133)
					(end 27.90571 -219.099892)
				)
				(arc
					(start 28.117292 -219.099892)
					(mid 28.189044 -219.070224)
					(end 28.218892 -218.998546)
				)
				(xy 28.219654 -218.968828) (xy 28.220924 -218.946476) (xy 27.946096 -218.671648) (xy 27.946096 -216.755472)
				(arc
					(start 27.929332 -216.740486)
					(mid 27.736334 -216.3064)
					(end 27.929332 -215.872314)
				)
				(xy 27.946096 -215.857328) (xy 27.946096 -214.017352) (xy 29.755592 -212.207602)
			)
		)
		(polygon
			(pts
				(arc
					(start 16.064992 -210.945984)
					(mid 16.00851 -210.854952)
					(end 15.901924 -210.865212)
				)
				(arc
					(start 15.901924 -210.865212)
					(mid 15.648544 -210.976625)
					(end 15.372334 -210.958938)
				)
				(arc
					(start 15.372334 -210.958938)
					(mid 15.281874 -210.974113)
					(end 15.240508 -211.055966)
				)
				(xy 15.240508 -213.995254)
				(arc
					(start 15.250922 -214.00897)
					(mid 15.365864 -214.216003)
					(end 15.416276 -214.447374)
				)
				(arc
					(start 15.416276 -214.447374)
					(mid 15.482054 -214.535428)
					(end 15.589504 -214.512144)
				)
				(xy 16.064992 -214.036402)
			)
		)
		(polygon
			(pts
				(arc
					(start 13.613892 -194.435476)
					(mid 13.54372 -194.338859)
					(end 13.43025 -194.375786)
				)
				(arc
					(start 13.43025 -194.375786)
					(mid 12.114171 -195.102231)
					(end 10.715244 -194.551808)
				)
				(arc
					(start 10.715244 -194.551808)
					(mid 10.604103 -194.527318)
					(end 10.539984 -194.621404)
				)
				(xy 10.539984 -195.221606) (xy 13.437108 -198.11873) (xy 13.437108 -209.663792)
				(arc
					(start 13.449046 -209.678016)
					(mid 13.486497 -209.726605)
					(end 13.518642 -209.778854)
				)
				(xy 13.53312 -209.805524) (xy 13.613892 -209.805524)
			)
		)
		(polygon
			(pts
				(arc
					(start 15.506192 -177.719736)
					(mid 15.434809 -177.622733)
					(end 15.321026 -177.662078)
				)
				(arc
					(start 15.321026 -177.662078)
					(mid 15.288668 -177.705754)
					(end 15.253462 -177.747168)
				)
				(xy 15.240508 -177.761646)
				(arc
					(start 15.240508 -209.745834)
					(mid 15.28189 -209.827665)
					(end 15.372334 -209.842862)
				)
				(arc
					(start 15.372334 -209.842862)
					(mid 15.417138 -209.830781)
					(end 15.462758 -209.822288)
				)
				(xy 15.506192 -209.815938)
			)
		)
		(polygon
			(pts
				(arc
					(start 37.943536 -176.522888)
					(mid 37.832991 -176.501052)
					(end 37.770308 -176.59477)
				)
				(xy 37.770308 -176.946052) (xy 38.189408 -177.365152)
				(arc
					(start 38.189408 -185.896758)
					(mid 38.252162 -185.990385)
					(end 38.362636 -185.968386)
				)
				(xy 39.01186 -185.319162)
				(arc
					(start 39.01186 -179.982368)
					(mid 38.982192 -179.910616)
					(end 38.910514 -179.880768)
				)
				(arc
					(start 38.910514 -179.880768)
					(mid 38.364959 -179.505765)
					(end 38.5191 -178.861974)
				)
				(xy 38.535864 -178.846988) (xy 38.535864 -177.36312)
				(arc
					(start 38.4937 -177.355754)
					(mid 38.061555 -177.076593)
					(end 37.960554 -176.572164)
				)
				(xy 37.965888 -176.545494)
			)
		)
		(polygon
			(pts
				(arc
					(start 38.969696 -175.14316)
					(mid 38.903462 -175.047914)
					(end 38.791134 -175.076866)
				)
				(arc
					(start 38.791134 -175.076866)
					(mid 38.66588 -175.185923)
					(end 38.515036 -175.255428)
				)
				(arc
					(start 38.515036 -175.255428)
					(mid 38.456939 -175.300517)
					(end 38.444424 -175.37303)
				)
				(arc
					(start 38.444424 -175.37303)
					(mid 38.444833 -175.603662)
					(end 38.356032 -175.816514)
				)
				(xy 38.332664 -175.851312) (xy 38.529514 -176.048162)
				(arc
					(start 38.552882 -176.04613)
					(mid 38.695117 -176.049594)
					(end 38.833298 -176.083468)
				)
				(arc
					(start 38.833298 -176.083468)
					(mid 38.926383 -176.071238)
					(end 38.969696 -175.987964)
				)
			)
		)
		(polygon
			(pts
				(arc
					(start 21.518118 -173.337728)
					(mid 21.443876 -173.295279)
					(end 21.363432 -173.32452)
				)
				(xy 21.09216 -173.595792)
				(arc
					(start 21.095716 -173.621192)
					(mid 20.908976 -174.183244)
					(end 20.346924 -174.369984)
				)
				(xy 20.321524 -174.366428) (xy 19.840448 -174.847504) (xy 19.778472 -174.847504)
				(arc
					(start 19.763486 -174.864268)
					(mid 19.567044 -175.006791)
					(end 19.329654 -175.057308)
				)
				(arc
					(start 19.329654 -175.057308)
					(mid 19.257976 -175.087156)
					(end 19.228308 -175.158908)
				)
				(xy 19.228308 -175.308514)
				(arc
					(start 19.27225 -175.314356)
					(mid 19.732451 -175.663519)
					(end 19.668236 -176.237646)
				)
				(arc
					(start 19.668236 -176.237646)
					(mid 19.65991 -176.343414)
					(end 19.750278 -176.398936)
				)
				(xy 20.290282 -176.398936)
				(arc
					(start 20.514564 -176.623218)
					(mid 20.625109 -176.645054)
					(end 20.687792 -176.551336)
				)
				(xy 20.687792 -175.60417) (xy 21.62048 -174.671482) (xy 21.62048 -173.449234)
				(arc
					(start 21.60397 -173.434248)
					(mid 21.558371 -173.388365)
					(end 21.518118 -173.337728)
				)
			)
		)
		(polygon
			(pts
				(arc
					(start 38.902386 -171.191936)
					(mid 38.791602 -171.1699)
					(end 38.728904 -171.263818)
				)
				(xy 38.728904 -174.25035)
				(arc
					(start 38.745414 -174.26559)
					(mid 38.768933 -174.288574)
					(end 38.791134 -174.312834)
				)
				(arc
					(start 38.791134 -174.312834)
					(mid 38.903454 -174.341765)
					(end 38.969696 -174.24654)
				)
				(xy 38.969696 -172.965364)
				(arc
					(start 38.958774 -172.951394)
					(mid 38.930535 -172.274324)
					(end 39.560754 -172.02531)
				)
				(xy 39.566596 -172.026834) (xy 39.623492 -172.026834) (xy 39.623492 -171.913296)
			)
		)
		(polygon
			(pts
				(arc
					(start 35.339528 -170.077384)
					(mid 35.228983 -170.055548)
					(end 35.1663 -170.149266)
				)
				(xy 35.1663 -170.398694) (xy 35.897058 -171.129706)
				(arc
					(start 35.922458 -171.12615)
					(mid 36.002613 -171.119485)
					(end 36.082986 -171.122594)
				)
				(arc
					(start 36.082986 -171.122594)
					(mid 36.161125 -171.096748)
					(end 36.194492 -171.021502)
				)
				(xy 36.194492 -170.932602)
			)
		)
		(polygon
			(pts
				(arc
					(start 37.469572 -168.557448)
					(mid 37.406936 -168.463616)
					(end 37.296344 -168.485566)
				)
				(xy 36.815268 -168.966642)
				(arc
					(start 36.816538 -168.988994)
					(mid 36.817307 -169.018966)
					(end 36.816538 -169.048938)
				)
				(xy 36.815268 -169.07129)
				(arc
					(start 37.296344 -169.552366)
					(mid 37.406889 -169.574202)
					(end 37.469572 -169.480484)
				)
			)
		)
		(polygon
			(pts
				(xy 43.660822 -159.56026) (xy 43.61053 -159.510222) (xy 43.504104 -159.616648) (xy 43.504104 -159.82315)
				(xy 43.504358 -166.535354)
				(arc
					(start 43.504358 -168.28135)
					(mid 43.535635 -168.328249)
					(end 43.590972 -168.317418)
				)
				(xy 43.686476 -168.22166) (xy 43.686476 -159.732726)
				(arc
					(start 43.684444 -159.725868)
					(mid 43.668274 -159.653829)
					(end 43.66133 -159.580326)
				)
			)
		)
		(polygon
			(pts
				(arc
					(start 39.420292 -157.721554)
					(mid 39.358187 -157.62769)
					(end 39.247572 -157.648656)
				)
				(arc
					(start 39.247572 -157.648656)
					(mid 39.215364 -157.678198)
					(end 39.181278 -157.705552)
				)
				(xy 39.160704 -157.720792) (xy 39.160704 -158.016448) (xy 37.458904 -159.718248) (xy 37.458904 -162.37077)
				(arc
					(start 37.479478 -162.38601)
					(mid 37.74496 -162.9156)
					(end 37.479478 -163.44519)
				)
				(xy 37.458904 -163.46043)
				(arc
					(start 37.458904 -166.568628)
					(mid 37.5037 -166.652865)
					(end 37.598604 -166.662862)
				)
				(arc
					(start 37.598604 -166.662862)
					(mid 37.766353 -166.620054)
					(end 37.939472 -166.622222)
				)
				(xy 37.964872 -166.625778) (xy 38.055296 -166.535354) (xy 38.055296 -159.82315) (xy 39.420292 -158.458154)
			)
		)
		(polygon
			(pts
				(xy 38.24097 -157.55112)
				(arc
					(start 36.177982 -157.55112)
					(mid 36.08415 -157.613756)
					(end 36.1061 -157.724348)
				)
				(xy 36.652708 -158.270702)
				(arc
					(start 36.652708 -159.21863)
					(mid 36.715344 -159.312462)
					(end 36.825936 -159.290512)
				)
				(arc
					(start 38.324028 -157.79242)
					(mid 38.353802 -157.720088)
					(end 38.323266 -157.648148)
				)
				(arc
					(start 38.323266 -157.648148)
					(mid 38.288249 -157.611095)
					(end 38.25621 -157.57144)
				)
			)
		)
		(polygon
			(pts
				(xy 36.66109 -154.343608)
				(arc
					(start 33.69437 -154.343608)
					(mid 33.600538 -154.406244)
					(end 33.622488 -154.516836)
				)
				(xy 35.90671 -156.800804) (xy 38.24097 -156.800804)
				(arc
					(start 38.25621 -156.780484)
					(mid 38.422472 -156.62382)
					(end 38.63213 -156.533088)
				)
				(arc
					(start 38.63213 -156.533088)
					(mid 38.706083 -156.461888)
					(end 38.680136 -156.362654)
				)
			)
		)
		(polygon
			(pts
				(arc
					(start 29.528008 -152.20696)
					(mid 29.501885 -152.209307)
					(end 29.475684 -152.210516)
				)
				(xy 29.453332 -152.232868) (xy 29.452824 -152.253188) (xy 29.452316 -152.268174) (xy 29.451046 -152.290526)
				(arc
					(start 35.815778 -158.655258)
					(mid 35.870974 -158.666237)
					(end 35.902392 -158.619444)
				)
				(xy 35.902392 -158.581598)
			)
		)
		(polygon
			(pts
				(xy 28.881324 -151.511508) (xy 24.952198 -151.511508) (xy 23.670514 -152.792938)
				(arc
					(start 23.67407 -152.818338)
					(mid 23.574021 -153.273414)
					(end 23.198582 -153.54935)
				)
				(arc
					(start 23.198582 -153.54935)
					(mid 23.127758 -153.621427)
					(end 23.154132 -153.719022)
				)
				(arc
					(start 33.709864 -164.274754)
					(mid 33.820409 -164.29659)
					(end 33.883092 -164.202872)
				)
				(xy 33.883092 -163.552124) (xy 33.360614 -163.029392)
				(arc
					(start 33.338262 -163.030662)
					(mid 32.894834 -162.03326)
					(end 33.892236 -162.476688)
				)
				(xy 33.890966 -162.49904) (xy 34.633408 -163.241228)
				(arc
					(start 34.633408 -164.709348)
					(mid 34.702542 -164.805621)
					(end 34.81578 -164.770816)
				)
				(arc
					(start 34.81578 -164.770816)
					(mid 35.050632 -164.587904)
					(end 35.345116 -164.544248)
				)
				(arc
					(start 35.345116 -164.544248)
					(mid 35.423965 -164.518998)
					(end 35.457892 -164.44341)
				)
				(xy 35.457892 -159.35833) (xy 28.920694 -152.820878)
				(arc
					(start 28.898342 -152.822148)
					(mid 28.284603 -152.271481)
					(end 28.831794 -151.654764)
				)
				(arc
					(start 28.831794 -151.654764)
					(mid 28.865376 -151.639051)
					(end 28.879292 -151.604726)
				)
				(xy 28.88107 -151.566118) (xy 28.881324 -151.564086)
			)
		)
		(polygon
			(pts
				(xy 16.297656 -148.990304)
				(arc
					(start 16.21282 -148.990304)
					(mid 16.118954 -149.053023)
					(end 16.140938 -149.163786)
				)
				(xy 17.908016 -150.930864) (xy 17.944084 -150.894796)
				(arc
					(start 17.944338 -150.894796)
					(mid 17.969733 -150.870221)
					(end 17.996408 -150.847044)
				)
				(arc
					(start 17.996408 -150.847044)
					(mid 18.033647 -150.773519)
					(end 18.004028 -150.696676)
				)
			)
		)
		(polygon
			(pts
				(arc
					(start 3.68046 -142.80642)
					(mid 3.569915 -142.784584)
					(end 3.507232 -142.878302)
				)
				(xy 3.507232 -143.70304) (xy 4.460748 -144.65681)
				(arc
					(start 4.486148 -144.653254)
					(mid 5.0482 -144.839994)
					(end 5.23494 -145.402046)
				)
				(xy 5.231384 -145.427446) (xy 5.903976 -146.100038)
				(arc
					(start 5.926328 -146.098768)
					(mid 6.148043 -146.13023)
					(end 6.341618 -146.242786)
				)
				(xy 6.355842 -146.255486) (xy 6.425692 -146.255486) (xy 6.425692 -146.139408)
				(arc
					(start 6.413754 -146.125184)
					(mid 6.290087 -145.883828)
					(end 6.288532 -145.612612)
				)
				(arc
					(start 6.288532 -145.612612)
					(mid 6.282238 -145.574451)
					(end 6.25094 -145.551652)
				)
				(arc
					(start 6.25094 -145.551652)
					(mid 5.919278 -145.333191)
					(end 5.803646 -144.953228)
				)
				(xy 5.804916 -144.930876)
			)
		)
		(polygon
			(pts
				(arc
					(start 47.840392 -129.191766)
					(mid 47.79055 -129.104338)
					(end 47.690024 -129.102866)
				)
				(arc
					(start 47.690024 -129.102866)
					(mid 47.503605 -129.171517)
					(end 47.305214 -129.181606)
				)
				(arc
					(start 47.305214 -129.181606)
					(mid 47.227075 -129.207452)
					(end 47.193708 -129.282698)
				)
				(arc
					(start 47.193708 -129.670302)
					(mid 47.227059 -129.745566)
					(end 47.305214 -129.771394)
				)
				(arc
					(start 47.305214 -129.771394)
					(mid 47.503592 -129.781549)
					(end 47.690024 -129.850134)
				)
				(arc
					(start 47.690024 -129.850134)
					(mid 47.790447 -129.848488)
					(end 47.840392 -129.761234)
				)
			)
		)
		(polygon
			(pts
				(arc
					(start 49.491392 -128.965198)
					(mid 49.420714 -128.868418)
					(end 49.306988 -128.90627)
				)
				(arc
					(start 49.306988 -128.90627)
					(mid 49.041717 -129.12543)
					(end 48.702214 -129.181606)
				)
				(arc
					(start 48.702214 -129.181606)
					(mid 48.624075 -129.207452)
					(end 48.590708 -129.282698)
				)
				(arc
					(start 48.590708 -129.670302)
					(mid 48.624059 -129.745566)
					(end 48.702214 -129.771394)
				)
				(arc
					(start 48.702214 -129.771394)
					(mid 49.041759 -129.827477)
					(end 49.306988 -130.04673)
				)
				(arc
					(start 49.306988 -130.04673)
					(mid 49.420723 -130.084612)
					(end 49.491392 -129.987802)
				)
			)
		)
		(polygon
			(pts
				(arc
					(start 47.840392 -127.159766)
					(mid 47.79055 -127.072338)
					(end 47.690024 -127.070866)
				)
				(arc
					(start 47.690024 -127.070866)
					(mid 47.503605 -127.139517)
					(end 47.305214 -127.149606)
				)
				(arc
					(start 47.305214 -127.149606)
					(mid 47.227075 -127.175452)
					(end 47.193708 -127.250698)
				)
				(arc
					(start 47.193708 -127.765302)
					(mid 47.227059 -127.840566)
					(end 47.305214 -127.866394)
				)
				(arc
					(start 47.305214 -127.866394)
					(mid 47.503592 -127.876549)
					(end 47.690024 -127.945134)
				)
				(arc
					(start 47.690024 -127.945134)
					(mid 47.790447 -127.943488)
					(end 47.840392 -127.856234)
				)
			)
		)
		(polygon
			(pts
				(arc
					(start 49.491392 -126.933198)
					(mid 49.420714 -126.836418)
					(end 49.306988 -126.87427)
				)
				(arc
					(start 49.306988 -126.87427)
					(mid 49.041717 -127.09343)
					(end 48.702214 -127.149606)
				)
				(arc
					(start 48.702214 -127.149606)
					(mid 48.624075 -127.175452)
					(end 48.590708 -127.250698)
				)
				(arc
					(start 48.590708 -127.765302)
					(mid 48.624059 -127.840566)
					(end 48.702214 -127.866394)
				)
				(arc
					(start 48.702214 -127.866394)
					(mid 49.041759 -127.922477)
					(end 49.306988 -128.14173)
				)
				(arc
					(start 49.306988 -128.14173)
					(mid 49.420723 -128.179612)
					(end 49.491392 -128.082802)
				)
			)
		)
		(polygon
			(pts
				(arc
					(start 13.549884 -125.027436)
					(mid 13.431741 -125.008745)
					(end 13.377672 -125.115574)
				)
				(arc
					(start 13.377672 -125.115574)
					(mid 13.329827 -125.489308)
					(end 13.085572 -125.776228)
				)
				(arc
					(start 13.085572 -125.776228)
					(mid 13.0393 -125.857302)
					(end 13.078714 -125.941836)
				)
				(arc
					(start 13.078714 -125.941836)
					(mid 13.347265 -126.198273)
					(end 13.556234 -126.505208)
				)
				(arc
					(start 13.556234 -126.505208)
					(mid 13.670643 -126.55585)
					(end 13.747496 -126.457202)
				)
				(xy 13.747496 -125.225048)
			)
		)
		(polygon
			(pts
				(arc
					(start 49.491392 -124.901198)
					(mid 49.420714 -124.804418)
					(end 49.306988 -124.84227)
				)
				(arc
					(start 49.306988 -124.84227)
					(mid 49.041717 -125.06143)
					(end 48.702214 -125.117606)
				)
				(arc
					(start 48.702214 -125.117606)
					(mid 48.624075 -125.143452)
					(end 48.590708 -125.218698)
				)
				(arc
					(start 48.590708 -125.733302)
					(mid 48.624059 -125.808566)
					(end 48.702214 -125.834394)
				)
				(arc
					(start 48.702214 -125.834394)
					(mid 49.041759 -125.890477)
					(end 49.306988 -126.10973)
				)
				(arc
					(start 49.306988 -126.10973)
					(mid 49.420723 -126.147612)
					(end 49.491392 -126.050802)
				)
			)
		)
		(polygon
			(pts
				(arc
					(start 47.840646 -124.28347)
					(mid 47.777927 -124.189604)
					(end 47.667164 -124.211588)
				)
				(xy 47.193708 -124.685298)
				(arc
					(start 47.193708 -125.733302)
					(mid 47.227059 -125.808566)
					(end 47.305214 -125.834394)
				)
				(arc
					(start 47.305214 -125.834394)
					(mid 47.503592 -125.844549)
					(end 47.690024 -125.913134)
				)
				(arc
					(start 47.690024 -125.913134)
					(mid 47.790447 -125.911488)
					(end 47.840392 -125.824234)
				)
				(xy 47.840392 -125.733302) (xy 47.840646 -124.685298)
			)
		)
		(polygon
			(pts
				(arc
					(start 11.690096 -123.12142)
					(mid 11.627377 -123.027554)
					(end 11.516614 -123.049538)
				)
				(xy 10.534904 -124.031248)
				(arc
					(start 10.534904 -124.476002)
					(mid 10.572552 -124.555204)
					(end 10.65784 -124.57557)
				)
				(arc
					(start 10.65784 -124.57557)
					(mid 10.784897 -124.561158)
					(end 10.912348 -124.571506)
				)
				(arc
					(start 10.912348 -124.571506)
					(mid 10.989437 -124.554213)
					(end 11.030712 -124.486924)
				)
				(arc
					(start 11.030712 -124.486924)
					(mid 11.70243 -123.926348)
					(end 12.34186 -124.5235)
				)
				(arc
					(start 12.34186 -124.5235)
					(mid 12.390099 -124.600337)
					(end 12.480544 -124.608082)
				)
				(arc
					(start 12.480544 -124.608082)
					(mid 12.653575 -124.564968)
					(end 12.831826 -124.569728)
				)
				(arc
					(start 12.831826 -124.569728)
					(mid 12.938835 -124.515752)
					(end 12.919964 -124.397516)
				)
				(xy 11.690096 -123.167648)
			)
		)
		(polygon
			(pts
				(arc
					(start 51.231292 -121.85777)
					(mid 51.168656 -121.763938)
					(end 51.058064 -121.785888)
				)
				(arc
					(start 49.101502 -123.74245)
					(mid 49.072567 -123.825637)
					(end 49.119536 -123.900184)
				)
				(arc
					(start 49.119536 -123.900184)
					(mid 49.222006 -123.979724)
					(end 49.306988 -124.07773)
				)
				(arc
					(start 49.306988 -124.07773)
					(mid 49.420723 -124.115612)
					(end 49.491392 -124.018802)
				)
				(xy 49.491392 -123.987306) (xy 51.231292 -122.247406)
			)
		)
		(polygon
			(pts
				(arc
					(start 49.09566 -113.759742)
					(mid 49.0093 -113.711698)
					(end 48.92294 -113.759742)
				)
				(arc
					(start 48.92294 -113.759742)
					(mid 48.386854 -114.071368)
					(end 47.828454 -113.801652)
				)
				(arc
					(start 47.828454 -113.801652)
					(mid 47.754321 -113.760586)
					(end 47.674784 -113.789968)
				)
				(xy 46.749208 -114.715798)
				(arc
					(start 46.749208 -123.82373)
					(mid 46.811844 -123.917562)
					(end 46.922436 -123.895612)
				)
				(arc
					(start 49.460912 -121.357136)
					(mid 49.483085 -121.247413)
					(end 49.390808 -121.183908)
				)
				(arc
					(start 49.390808 -121.183908)
					(mid 48.759837 -120.370392)
					(end 49.689004 -119.927116)
				)
				(arc
					(start 49.689004 -119.927116)
					(mid 49.786909 -119.921311)
					(end 49.834292 -119.835422)
				)
				(arc
					(start 49.834292 -119.480076)
					(mid 49.794292 -119.39928)
					(end 49.705768 -119.382032)
				)
				(arc
					(start 49.705768 -119.382032)
					(mid 49.289287 -119.360436)
					(end 48.96866 -119.093742)
				)
				(arc
					(start 48.96866 -119.093742)
					(mid 48.8823 -119.045698)
					(end 48.79594 -119.093742)
				)
				(arc
					(start 48.79594 -119.093742)
					(mid 47.573749 -118.745)
					(end 48.79594 -118.396258)
				)
				(arc
					(start 48.79594 -118.396258)
					(mid 48.8823 -118.444302)
					(end 48.96866 -118.396258)
				)
				(arc
					(start 48.96866 -118.396258)
					(mid 49.289281 -118.129551)
					(end 49.705768 -118.107968)
				)
				(arc
					(start 49.705768 -118.107968)
					(mid 49.794336 -118.090779)
					(end 49.834292 -118.009924)
				)
				(arc
					(start 49.834292 -117.702076)
					(mid 49.794292 -117.62128)
					(end 49.705768 -117.604032)
				)
				(arc
					(start 49.705768 -117.604032)
					(mid 49.289287 -117.582436)
					(end 48.96866 -117.315742)
				)
				(arc
					(start 48.96866 -117.315742)
					(mid 48.8823 -117.267698)
					(end 48.79594 -117.315742)
				)
				(arc
					(start 48.79594 -117.315742)
					(mid 47.573749 -116.967)
					(end 48.79594 -116.618258)
				)
				(arc
					(start 48.79594 -116.618258)
					(mid 48.8823 -116.666302)
					(end 48.96866 -116.618258)
				)
				(arc
					(start 48.96866 -116.618258)
					(mid 49.289281 -116.351551)
					(end 49.705768 -116.329968)
				)
				(arc
					(start 49.705768 -116.329968)
					(mid 49.794336 -116.312779)
					(end 49.834292 -116.231924)
				)
				(arc
					(start 49.834292 -115.947698)
					(mid 49.800941 -115.872434)
					(end 49.722786 -115.846606)
				)
				(arc
					(start 49.722786 -115.846606)
					(mid 49.365028 -115.781896)
					(end 49.09566 -115.537742)
				)
				(arc
					(start 49.09566 -115.537742)
					(mid 49.0093 -115.489698)
					(end 48.92294 -115.537742)
				)
				(arc
					(start 48.92294 -115.537742)
					(mid 47.700749 -115.189)
					(end 48.92294 -114.840258)
				)
				(arc
					(start 48.92294 -114.840258)
					(mid 49.0093 -114.888302)
					(end 49.09566 -114.840258)
				)
				(arc
					(start 49.09566 -114.840258)
					(mid 49.365045 -114.596138)
					(end 49.722786 -114.531394)
				)
				(arc
					(start 49.722786 -114.531394)
					(mid 49.800925 -114.505548)
					(end 49.834292 -114.430302)
				)
				(arc
					(start 49.834292 -114.169698)
					(mid 49.800941 -114.094434)
					(end 49.722786 -114.068606)
				)
				(arc
					(start 49.722786 -114.068606)
					(mid 49.365028 -114.003896)
					(end 49.09566 -113.759742)
				)
			)
		)
		(polygon
			(pts
				(xy 49.834292 -111.978948) (xy 49.660048 -111.804704)
				(arc
					(start 48.740568 -112.724184)
					(mid 48.711083 -112.803729)
					(end 48.752252 -112.877854)
				)
				(arc
					(start 48.752252 -112.877854)
					(mid 48.846425 -112.961881)
					(end 48.92294 -113.062258)
				)
				(arc
					(start 48.92294 -113.062258)
					(mid 49.0093 -113.110302)
					(end 49.09566 -113.062258)
				)
				(arc
					(start 49.09566 -113.062258)
					(mid 49.365045 -112.818138)
					(end 49.722786 -112.753394)
				)
				(arc
					(start 49.722786 -112.753394)
					(mid 49.800925 -112.727548)
					(end 49.834292 -112.652302)
				)
			)
		)
		(polygon
			(pts
				(arc
					(start 46.768766 -64.844168)
					(mid 46.644057 -64.829198)
					(end 46.60011 -64.946784)
				)
				(arc
					(start 46.60011 -64.946784)
					(mid 46.63341 -65.437946)
					(end 46.434756 -65.888362)
				)
				(xy 46.407578 -65.923668)
				(arc
					(start 49.368964 -68.885054)
					(mid 49.479509 -68.90689)
					(end 49.542192 -68.813172)
				)
				(xy 49.542192 -67.617848)
			)
		)
		(polygon
			(pts
				(arc
					(start 42.6339 -63.007494)
					(mid 42.535563 -63.012991)
					(end 42.488104 -63.099188)
				)
				(xy 42.488104 -63.643256)
				(arc
					(start 42.153586 -63.308738)
					(mid 42.042802 -63.286702)
					(end 41.980104 -63.38062)
				)
				(arc
					(start 41.980104 -64.72809)
					(mid 42.057091 -64.826664)
					(end 42.171366 -64.775842)
				)
				(arc
					(start 42.171366 -64.775842)
					(mid 42.303301 -64.584212)
					(end 42.474896 -64.4271)
				)
				(arc
					(start 42.474896 -64.4271)
					(mid 42.514549 -64.366403)
					(end 42.503598 -64.294766)
				)
				(arc
					(start 42.503598 -64.294766)
					(mid 42.561568 -64.338386)
					(end 42.6339 -64.332358)
				)
				(arc
					(start 42.6339 -64.332358)
					(mid 43.791058 -64.516262)
					(end 44.026074 -65.66408)
				)
				(arc
					(start 44.026074 -65.66408)
					(mid 44.034605 -65.760182)
					(end 44.119546 -65.805812)
				)
				(arc
					(start 44.579794 -65.805812)
					(mid 44.664632 -65.760114)
					(end 44.673266 -65.66408)
				)
				(arc
					(start 44.673266 -65.66408)
					(mid 44.858492 -64.567437)
					(end 45.932852 -64.279526)
				)
				(arc
					(start 45.932852 -64.279526)
					(mid 46.050336 -64.235517)
					(end 46.035468 -64.11087)
				)
				(xy 45.520102 -63.595504) (xy 44.064936 -63.595504) (xy 43.492674 -63.023242)
				(arc
					(start 43.461432 -63.035688)
					(mid 43.044698 -63.108515)
					(end 42.6339 -63.007494)
				)
			)
		)
		(polygon
			(pts
				(arc
					(start 46.81728 -61.901832)
					(mid 46.702071 -61.881753)
					(end 46.644306 -61.983366)
				)
				(arc
					(start 46.644306 -61.983366)
					(mid 46.534606 -62.551147)
					(end 46.136052 -62.970156)
				)
				(arc
					(start 46.136052 -62.970156)
					(mid 46.086321 -63.044909)
					(end 46.115224 -63.129922)
				)
				(arc
					(start 49.813718 -66.828416)
					(mid 49.924502 -66.850452)
					(end 49.9872 -66.756534)
				)
				(xy 49.9872 -65.071752)
			)
		)
		(polygon
			(pts
				(arc
					(start 35.243262 -61.457586)
					(mid 35.265098 -61.347041)
					(end 35.17138 -61.284358)
				)
				(arc
					(start 34.01822 -61.284358)
					(mid 33.924388 -61.346994)
					(end 33.946338 -61.457586)
				)
				(xy 34.5948 -62.106048)
			)
		)
		(polygon
			(pts
				(arc
					(start 29.012896 -61.284104)
					(mid 28.921617 -61.341086)
					(end 28.932632 -61.448188)
				)
				(arc
					(start 28.932632 -61.448188)
					(mid 29.077392 -61.701946)
					(end 29.144976 -61.98616)
				)
				(arc
					(start 29.144976 -61.98616)
					(mid 29.211492 -62.07245)
					(end 29.31795 -62.048898)
				)
				(arc
					(start 29.909262 -61.457586)
					(mid 29.931298 -61.346802)
					(end 29.83738 -61.284104)
				)
			)
		)
		(polygon
			(pts
				(arc
					(start 26.472896 -61.284104)
					(mid 26.381617 -61.341086)
					(end 26.392632 -61.448188)
				)
				(arc
					(start 26.392632 -61.448188)
					(mid 26.599167 -61.935847)
					(end 26.535888 -62.461648)
				)
				(xy 26.523442 -62.49289) (xy 26.927048 -62.896496)
				(arc
					(start 27.24404 -62.896496)
					(mid 27.335627 -62.838346)
					(end 27.322526 -62.730634)
				)
				(arc
					(start 27.322526 -62.730634)
					(mid 27.090801 -62.092006)
					(end 27.30754 -61.448188)
				)
				(arc
					(start 27.30754 -61.448188)
					(mid 27.318661 -61.341034)
					(end 27.227276 -61.284104)
				)
			)
		)
		(polygon
			(pts
				(arc
					(start 42.6339 -60.467494)
					(mid 42.535563 -60.472991)
					(end 42.488104 -60.559188)
				)
				(arc
					(start 42.488104 -61.060584)
					(mid 42.535664 -61.14662)
					(end 42.6339 -61.152278)
				)
				(arc
					(start 42.6339 -61.152278)
					(mid 43.782247 -61.327854)
					(end 44.035472 -62.461648)
				)
				(xy 44.023026 -62.49289) (xy 44.375832 -62.845696)
				(arc
					(start 44.704508 -62.845696)
					(mid 44.79482 -62.790145)
					(end 44.78655 -62.684406)
				)
				(arc
					(start 44.78655 -62.684406)
					(mid 44.592234 -62.017361)
					(end 44.866052 -61.378846)
				)
				(arc
					(start 44.866052 -61.378846)
					(mid 44.884956 -61.269041)
					(end 44.791884 -61.207904)
				)
				(xy 44.217336 -61.207904) (xy 43.492674 -60.483242)
				(arc
					(start 43.461432 -60.495688)
					(mid 43.044698 -60.568515)
					(end 42.6339 -60.467494)
				)
			)
		)
		(polygon
			(pts
				(xy 14.3764 -38.5318) (xy 12.065 -38.5318) (xy 11.8872 -38.7096) (xy 11.8872 -42.799) (xy 9.8552 -44.831)
				(xy 8.509 -44.831) (xy 7.9502 -45.3898) (xy 7.9502 -51.816) (xy 8.001 -51.8668) (xy 8.001 -56.8706)
				(xy 4.0894 -60.7822) (xy 4.0894 -79.2988) (xy 2.5908 -80.7974) (xy 2.5908 -133.8834) (xy 3.6068 -134.8994)
				(xy 4.4196 -134.8994) (xy 5.9436 -133.3754) (xy 5.9436 -119.9896) (xy 4.318 -118.364) (xy 4.318 -93.5482)
				(xy 5.588 -93.5482) (xy 6.6548 -92.4814) (xy 6.6548 -91.5924) (xy 7.112 -91.1352) (xy 13.589 -91.1352)
				(xy 14.0716 -90.6526) (xy 14.0716 -74.7268) (xy 15.494 -73.3044) (xy 15.494 -70.358) (xy 18.288 -67.564)
				(xy 18.288 -63.7032) (xy 18.8214 -63.1698) (xy 20.9042 -63.1698) (xy 22.86 -61.214) (xy 40.8686 -61.214)
				(xy 42.7228 -59.3598) (xy 42.7228 -54.0766) (xy 40.7924 -52.1462) (xy 36.8046 -52.1462) (xy 28.6258 -43.9674)
				(xy 20.9804 -43.9674) (xy 17.8562 -47.0916) (xy 15.2146 -47.0916) (xy 14.732 -46.609) (xy 14.732 -38.8874)
			)
		)
	)
	(zone
		(layer "B.Cu")
		(hatch none 0.5)
		(connect_pads
			(clearance 0)
		)
		(min_thickness 0.25)
		(keepout
			(tracks allowed)
			(vias allowed)
			(pads allowed)
			(copperpour allowed)
			(footprints not_allowed)
		)
		(placement
			(enabled no)
			(sheetname "")
		)
		(fill
			(thermal_gap 0.5)
			(thermal_bridge_width 0.5)
			(island_removal_mode 0)
		)
		(polygon
			(pts
				(arc
					(start 7.599934 -291.660072)
					(mid 3.599942 -295.660064)
					(end 7.599934 -299.660056)
				)
				(arc
					(start 7.599934 -299.660056)
					(mid 11.599926 -295.660064)
					(end 7.599934 -291.660072)
				)
			)
		)
	)
	(zone
		(layer "B.Cu")
		(hatch none 0.5)
		(connect_pads
			(clearance 0)
		)
		(min_thickness 0.25)
		(keepout
			(tracks allowed)
			(vias allowed)
			(pads allowed)
			(copperpour allowed)
			(footprints not_allowed)
		)
		(placement
			(enabled no)
			(sheetname "")
		)
		(fill
			(thermal_gap 0.5)
			(thermal_bridge_width 0.5)
			(island_removal_mode 0)
		)
		(polygon
			(pts
				(arc
					(start 24.500078 -448.69989)
					(mid 29.249878 -443.95009)
					(end 24.500078 -439.200036)
				)
				(arc
					(start 24.500078 -439.200036)
					(mid 19.750024 -443.95009)
					(end 24.500078 -448.69989)
				)
			)
		)
	)
	(zone
		(layer "B.Cu")
		(hatch none 0.5)
		(connect_pads
			(clearance 0)
		)
		(min_thickness 0.25)
		(keepout
			(tracks allowed)
			(vias allowed)
			(pads allowed)
			(copperpour allowed)
			(footprints not_allowed)
		)
		(placement
			(enabled no)
			(sheetname "")
		)
		(fill
			(thermal_gap 0.5)
			(thermal_bridge_width 0.5)
			(island_removal_mode 0)
		)
		(polygon
			(pts
				(arc
					(start 6.999986 -35.999928)
					(mid 2.999994 -39.99992)
					(end 6.999986 -43.999912)
				)
				(arc
					(start 6.999986 -43.999912)
					(mid 10.999978 -39.99992)
					(end 6.999986 -35.999928)
				)
			)
		)
	)
	(zone
		(layer "B.Cu")
		(hatch none 0.5)
		(connect_pads
			(clearance 0)
		)
		(min_thickness 0.25)
		(keepout
			(tracks allowed)
			(vias allowed)
			(pads allowed)
			(copperpour allowed)
			(footprints not_allowed)
		)
		(placement
			(enabled no)
			(sheetname "")
		)
		(fill
			(thermal_gap 0.5)
			(thermal_bridge_width 0.5)
			(island_removal_mode 0)
		)
		(polygon
			(pts
				(arc
					(start 40.999918 -448.69989)
					(mid 45.749718 -443.95009)
					(end 40.999918 -439.200036)
				)
				(arc
					(start 40.999918 -439.200036)
					(mid 36.249864 -443.95009)
					(end 40.999918 -448.69989)
				)
			)
		)
	)
	(zone
		(layer "B.Cu")
		(hatch none 0.5)
		(connect_pads
			(clearance 0)
		)
		(min_thickness 0.25)
		(keepout
			(tracks allowed)
			(vias allowed)
			(pads allowed)
			(copperpour allowed)
			(footprints not_allowed)
		)
		(placement
			(enabled no)
			(sheetname "")
		)
		(fill
			(thermal_gap 0.5)
			(thermal_bridge_width 0.5)
			(island_removal_mode 0)
		)
		(polygon
			(pts
				(arc
					(start 6.999986 -163.999926)
					(mid 10.999978 -159.999934)
					(end 6.999986 -155.999942)
				)
				(arc
					(start 6.999986 -155.999942)
					(mid 2.999994 -159.999934)
					(end 6.999986 -163.999926)
				)
			)
		)
	)
	(zone
		(layer "B.Cu")
		(hatch none 0.5)
		(connect_pads
			(clearance 0)
		)
		(min_thickness 0.25)
		(keepout
			(tracks allowed)
			(vias allowed)
			(pads allowed)
			(copperpour allowed)
			(footprints not_allowed)
		)
		(placement
			(enabled no)
			(sheetname "")
		)
		(fill
			(thermal_gap 0.5)
			(thermal_bridge_width 0.5)
			(island_removal_mode 0)
		)
		(polygon
			(pts
				(arc
					(start 24.500078 -458.300074)
					(mid 19.750024 -463.050128)
					(end 24.500078 -467.799928)
				)
				(arc
					(start 24.500078 -467.799928)
					(mid 29.249878 -463.050128)
					(end 24.500078 -458.300074)
				)
			)
		)
	)
	(zone
		(layer "B.Cu")
		(hatch none 0.5)
		(connect_pads
			(clearance 0)
		)
		(min_thickness 0.25)
		(keepout
			(tracks allowed)
			(vias allowed)
			(pads allowed)
			(copperpour allowed)
			(footprints not_allowed)
		)
		(placement
			(enabled no)
			(sheetname "")
		)
		(fill
			(thermal_gap 0.5)
			(thermal_bridge_width 0.5)
			(island_removal_mode 0)
		)
		(polygon
			(pts
				(arc
					(start 45.449998 -332.749906)
					(mid 40.699944 -337.49996)
					(end 45.449998 -342.250014)
				)
				(arc
					(start 45.449998 -342.250014)
					(mid 50.200052 -337.49996)
					(end 45.449998 -332.749906)
				)
			)
		)
	)
	(zone
		(layer "B.Cu")
		(hatch none 0.5)
		(connect_pads
			(clearance 0)
		)
		(min_thickness 0.25)
		(keepout
			(tracks allowed)
			(vias allowed)
			(pads allowed)
			(copperpour allowed)
			(footprints not_allowed)
		)
		(placement
			(enabled no)
			(sheetname "")
		)
		(fill
			(thermal_gap 0.5)
			(thermal_bridge_width 0.5)
			(island_removal_mode 0)
		)
		(polygon
			(pts
				(arc
					(start 7.599934 -186.339988)
					(mid 11.599926 -182.339996)
					(end 7.599934 -178.340004)
				)
				(arc
					(start 7.599934 -178.340004)
					(mid 3.599942 -182.339996)
					(end 7.599934 -186.339988)
				)
			)
		)
	)
	(zone
		(layer "B.Cu")
		(hatch none 0.5)
		(connect_pads
			(clearance 0)
		)
		(min_thickness 0.25)
		(keepout
			(tracks allowed)
			(vias allowed)
			(pads allowed)
			(copperpour allowed)
			(footprints not_allowed)
		)
		(placement
			(enabled no)
			(sheetname "")
		)
		(fill
			(thermal_gap 0.5)
			(thermal_bridge_width 0.5)
			(island_removal_mode 0)
		)
		(polygon
			(pts
				(arc
					(start 6.999986 -43.999912)
					(mid 10.999978 -39.99992)
					(end 6.999986 -35.999928)
				)
				(arc
					(start 6.999986 -35.999928)
					(mid 2.999994 -39.99992)
					(end 6.999986 -43.999912)
				)
			)
		)
	)
	(zone
		(layer "B.Cu")
		(hatch none 0.5)
		(connect_pads
			(clearance 0)
		)
		(min_thickness 0.25)
		(keepout
			(tracks allowed)
			(vias allowed)
			(pads allowed)
			(copperpour allowed)
			(footprints not_allowed)
		)
		(placement
			(enabled no)
			(sheetname "")
		)
		(fill
			(thermal_gap 0.5)
			(thermal_bridge_width 0.5)
			(island_removal_mode 0)
		)
		(polygon
			(pts
				(arc
					(start 45.449998 -342.250014)
					(mid 50.200052 -337.49996)
					(end 45.449998 -332.749906)
				)
				(arc
					(start 45.449998 -332.749906)
					(mid 40.699944 -337.49996)
					(end 45.449998 -342.250014)
				)
			)
		)
	)
	(zone
		(layer "B.Cu")
		(hatch none 0.5)
		(connect_pads
			(clearance 0)
		)
		(min_thickness 0.25)
		(keepout
			(tracks allowed)
			(vias allowed)
			(pads allowed)
			(copperpour allowed)
			(footprints not_allowed)
		)
		(placement
			(enabled no)
			(sheetname "")
		)
		(fill
			(thermal_gap 0.5)
			(thermal_bridge_width 0.5)
			(island_removal_mode 0)
		)
		(polygon
			(pts
				(arc
					(start 7.599934 -32.29991)
					(mid 11.599926 -28.299918)
					(end 7.599934 -24.299926)
				)
				(arc
					(start 7.599934 -24.299926)
					(mid 3.599942 -28.299918)
					(end 7.599934 -32.29991)
				)
			)
		)
	)
	(zone
		(layer "B.Cu")
		(hatch none 0.5)
		(connect_pads
			(clearance 0)
		)
		(min_thickness 0.25)
		(keepout
			(tracks allowed)
			(vias allowed)
			(pads allowed)
			(copperpour allowed)
			(footprints not_allowed)
		)
		(placement
			(enabled no)
			(sheetname "")
		)
		(fill
			(thermal_gap 0.5)
			(thermal_bridge_width 0.5)
			(island_removal_mode 0)
		)
		(polygon
			(pts
				(arc
					(start 7.599934 -321.660012)
					(mid 11.599926 -317.66002)
					(end 7.599934 -313.660028)
				)
				(arc
					(start 7.599934 -313.660028)
					(mid 3.599942 -317.66002)
					(end 7.599934 -321.660012)
				)
			)
		)
	)
	(zone
		(layer "B.Cu")
		(hatch none 0.5)
		(connect_pads
			(clearance 0)
		)
		(min_thickness 0.25)
		(keepout
			(tracks allowed)
			(vias allowed)
			(pads allowed)
			(copperpour allowed)
			(footprints not_allowed)
		)
		(placement
			(enabled no)
			(sheetname "")
		)
		(fill
			(thermal_gap 0.5)
			(thermal_bridge_width 0.5)
			(island_removal_mode 0)
		)
		(polygon
			(pts
				(arc
					(start 7.599934 -379.659896)
					(mid 3.599942 -383.659888)
					(end 7.599934 -387.65988)
				)
				(arc
					(start 7.599934 -387.65988)
					(mid 11.599926 -383.659888)
					(end 7.599934 -379.659896)
				)
			)
		)
	)
	(zone
		(layer "B.Cu")
		(hatch none 0.5)
		(connect_pads
			(clearance 0)
		)
		(min_thickness 0.25)
		(keepout
			(tracks allowed)
			(vias allowed)
			(pads allowed)
			(copperpour allowed)
			(footprints not_allowed)
		)
		(placement
			(enabled no)
			(sheetname "")
		)
		(fill
			(thermal_gap 0.5)
			(thermal_bridge_width 0.5)
			(island_removal_mode 0)
		)
		(polygon
			(pts
				(arc
					(start 45.500036 -298.99991)
					(mid 49.500028 -294.999918)
					(end 45.500036 -290.999926)
				)
				(arc
					(start 45.500036 -290.999926)
					(mid 41.500044 -294.999918)
					(end 45.500036 -298.99991)
				)
			)
		)
	)
	(zone
		(layer "B.Cu")
		(hatch none 0.5)
		(connect_pads
			(clearance 0)
		)
		(min_thickness 0.25)
		(keepout
			(tracks allowed)
			(vias allowed)
			(pads allowed)
			(copperpour allowed)
			(footprints not_allowed)
		)
		(placement
			(enabled no)
			(sheetname "")
		)
		(fill
			(thermal_gap 0.5)
			(thermal_bridge_width 0.5)
			(island_removal_mode 0)
		)
		(polygon
			(pts
				(arc
					(start 7.599934 -112.339882)
					(mid 3.599688 -116.340128)
					(end 7.599934 -120.34012)
				)
				(arc
					(start 7.599934 -120.34012)
					(mid 11.599926 -116.340128)
					(end 7.599934 -112.339882)
				)
			)
		)
	)
	(zone
		(layer "B.Cu")
		(hatch none 0.5)
		(connect_pads
			(clearance 0)
		)
		(min_thickness 0.25)
		(keepout
			(tracks allowed)
			(vias allowed)
			(pads allowed)
			(copperpour allowed)
			(footprints not_allowed)
		)
		(placement
			(enabled no)
			(sheetname "")
		)
		(fill
			(thermal_gap 0.5)
			(thermal_bridge_width 0.5)
			(island_removal_mode 0)
		)
		(polygon
			(pts
				(arc
					(start 40.999918 -467.799928)
					(mid 45.749718 -463.050128)
					(end 40.999918 -458.300074)
				)
				(arc
					(start 40.999918 -458.300074)
					(mid 36.249864 -463.050128)
					(end 40.999918 -467.799928)
				)
			)
		)
	)
	(zone
		(layer "B.Cu")
		(hatch none 0.5)
		(connect_pads
			(clearance 0)
		)
		(min_thickness 0.25)
		(keepout
			(tracks allowed)
			(vias allowed)
			(pads allowed)
			(copperpour allowed)
			(footprints not_allowed)
		)
		(placement
			(enabled no)
			(sheetname "")
		)
		(fill
			(thermal_gap 0.5)
			(thermal_bridge_width 0.5)
			(island_removal_mode 0)
		)
		(polygon
			(pts
				(arc
					(start 45.500036 -290.999926)
					(mid 41.500044 -294.999918)
					(end 45.500036 -298.99991)
				)
				(arc
					(start 45.500036 -298.99991)
					(mid 49.500028 -294.999918)
					(end 45.500036 -290.999926)
				)
			)
		)
	)
	(zone
		(layer "B.Cu")
		(hatch none 0.5)
		(connect_pads
			(clearance 0)
		)
		(min_thickness 0.25)
		(keepout
			(tracks allowed)
			(vias allowed)
			(pads allowed)
			(copperpour allowed)
			(footprints not_allowed)
		)
		(placement
			(enabled no)
			(sheetname "")
		)
		(fill
			(thermal_gap 0.5)
			(thermal_bridge_width 0.5)
			(island_removal_mode 0)
		)
		(polygon
			(pts
				(arc
					(start 24.500078 -439.200036)
					(mid 19.750024 -443.95009)
					(end 24.500078 -448.69989)
				)
				(arc
					(start 24.500078 -448.69989)
					(mid 29.249878 -443.95009)
					(end 24.500078 -439.200036)
				)
			)
		)
	)
	(zone
		(layer "B.Cu")
		(hatch none 0.5)
		(connect_pads
			(clearance 0)
		)
		(min_thickness 0.25)
		(keepout
			(tracks allowed)
			(vias allowed)
			(pads allowed)
			(copperpour allowed)
			(footprints not_allowed)
		)
		(placement
			(enabled no)
			(sheetname "")
		)
		(fill
			(thermal_gap 0.5)
			(thermal_bridge_width 0.5)
			(island_removal_mode 0)
		)
		(polygon
			(pts
				(arc
					(start 6.999986 -456.000104)
					(mid 2.999994 -460.000096)
					(end 6.999986 -464.000088)
				)
				(arc
					(start 6.999986 -464.000088)
					(mid 10.999978 -460.000096)
					(end 6.999986 -456.000104)
				)
			)
		)
	)
	(zone
		(layer "B.Cu")
		(hatch none 0.5)
		(connect_pads
			(clearance 0)
		)
		(min_thickness 0.25)
		(keepout
			(tracks allowed)
			(vias allowed)
			(pads allowed)
			(copperpour allowed)
			(footprints not_allowed)
		)
		(placement
			(enabled no)
			(sheetname "")
		)
		(fill
			(thermal_gap 0.5)
			(thermal_bridge_width 0.5)
			(island_removal_mode 0)
		)
		(polygon
			(pts
				(arc
					(start 45.500036 -15.999968)
					(mid 41.500044 -19.99996)
					(end 45.500036 -23.999952)
				)
				(arc
					(start 45.500036 -23.999952)
					(mid 49.500028 -19.99996)
					(end 45.500036 -15.999968)
				)
			)
		)
	)
	(zone
		(layer "B.Cu")
		(hatch none 0.5)
		(connect_pads
			(clearance 0)
		)
		(min_thickness 0.25)
		(keepout
			(tracks allowed)
			(vias allowed)
			(pads allowed)
			(copperpour allowed)
			(footprints not_allowed)
		)
		(placement
			(enabled no)
			(sheetname "")
		)
		(fill
			(thermal_gap 0.5)
			(thermal_bridge_width 0.5)
			(island_removal_mode 0)
		)
		(polygon
			(pts
				(arc
					(start 45.500036 -140.999972)
					(mid 41.500044 -144.999964)
					(end 45.500036 -148.999956)
				)
				(arc
					(start 45.500036 -148.999956)
					(mid 49.500028 -144.999964)
					(end 45.500036 -140.999972)
				)
			)
		)
	)
	(zone
		(layer "B.Cu")
		(hatch none 0.5)
		(connect_pads
			(clearance 0)
		)
		(min_thickness 0.25)
		(keepout
			(tracks allowed)
			(vias allowed)
			(pads allowed)
			(copperpour allowed)
			(footprints not_allowed)
		)
		(placement
			(enabled no)
			(sheetname "")
		)
		(fill
			(thermal_gap 0.5)
			(thermal_bridge_width 0.5)
			(island_removal_mode 0)
		)
		(polygon
			(pts
				(arc
					(start 4.500118 -336.00009)
					(mid 0.500126 -340.000082)
					(end 4.500118 -344.000074)
				)
				(arc
					(start 4.500118 -344.000074)
					(mid 8.50011 -340.000082)
					(end 4.500118 -336.00009)
				)
			)
		)
	)
	(zone
		(layer "B.Cu")
		(hatch none 0.5)
		(connect_pads
			(clearance 0)
		)
		(min_thickness 0.25)
		(keepout
			(tracks allowed)
			(vias allowed)
			(pads allowed)
			(copperpour allowed)
			(footprints not_allowed)
		)
		(placement
			(enabled no)
			(sheetname "")
		)
		(fill
			(thermal_gap 0.5)
			(thermal_bridge_width 0.5)
			(island_removal_mode 0)
		)
		(polygon
			(pts
				(arc
					(start 7.599934 -357.65994)
					(mid 3.599942 -361.659932)
					(end 7.599934 -365.659924)
				)
				(arc
					(start 7.599934 -365.659924)
					(mid 11.599926 -361.659932)
					(end 7.599934 -357.65994)
				)
			)
		)
	)
	(zone
		(layer "B.Cu")
		(hatch none 0.5)
		(connect_pads
			(clearance 0)
		)
		(min_thickness 0.25)
		(keepout
			(tracks allowed)
			(vias allowed)
			(pads allowed)
			(copperpour allowed)
			(footprints not_allowed)
		)
		(placement
			(enabled no)
			(sheetname "")
		)
		(fill
			(thermal_gap 0.5)
			(thermal_bridge_width 0.5)
			(island_removal_mode 0)
		)
		(polygon
			(pts
				(arc
					(start 7.599934 -387.65988)
					(mid 11.599926 -383.659888)
					(end 7.599934 -379.659896)
				)
				(arc
					(start 7.599934 -379.659896)
					(mid 3.599942 -383.659888)
					(end 7.599934 -387.65988)
				)
			)
		)
	)
	(zone
		(layer "B.Cu")
		(hatch none 0.5)
		(connect_pads
			(clearance 0)
		)
		(min_thickness 0.25)
		(keepout
			(tracks allowed)
			(vias allowed)
			(pads allowed)
			(copperpour allowed)
			(footprints not_allowed)
		)
		(placement
			(enabled no)
			(sheetname "")
		)
		(fill
			(thermal_gap 0.5)
			(thermal_bridge_width 0.5)
			(island_removal_mode 0)
		)
		(polygon
			(pts
				(arc
					(start 7.599934 -120.34012)
					(mid 11.599926 -116.340128)
					(end 7.599934 -112.339882)
				)
				(arc
					(start 7.599934 -112.339882)
					(mid 3.599688 -116.340128)
					(end 7.599934 -120.34012)
				)
			)
		)
	)
	(zone
		(layer "B.Cu")
		(hatch none 0.5)
		(connect_pads
			(clearance 0)
		)
		(min_thickness 0.25)
		(keepout
			(tracks allowed)
			(vias allowed)
			(pads allowed)
			(copperpour allowed)
			(footprints not_allowed)
		)
		(placement
			(enabled no)
			(sheetname "")
		)
		(fill
			(thermal_gap 0.5)
			(thermal_bridge_width 0.5)
			(island_removal_mode 0)
		)
		(polygon
			(pts
				(arc
					(start 45.500036 -476.000064)
					(mid 41.500044 -480.000056)
					(end 45.500036 -484.000048)
				)
				(arc
					(start 45.500036 -484.000048)
					(mid 49.500028 -480.000056)
					(end 45.500036 -476.000064)
				)
			)
		)
	)
	(zone
		(net "P12V_AUX")
		(layer "B.Cu")
		(hatch none 0.5)
		(connect_pads
			(clearance 0.5)
		)
		(min_thickness 0.25)
		(fill yes
			(thermal_gap 0.5)
			(thermal_bridge_width 0.5)
			(island_removal_mode 0)
		)
		(polygon
			(pts
				(xy 46.609 -415.036) (xy 45.593 -414.02) (xy 14.097 -414.02) (xy 13.843 -414.274) (xy 13.843 -416.052)
				(xy 13.208 -416.687) (xy 13.208 -442.595) (xy 15.494 -444.881) (xy 15.494 -474.599) (xy 16.256 -475.361)
				(xy 30.353 -475.361) (xy 32.512 -473.202) (xy 32.512 -453.517) (xy 31.877 -452.882) (xy 29.718 -452.882)
				(xy 29.083 -452.247) (xy 29.083 -451.358) (xy 29.718 -450.723) (xy 32.004 -450.723) (xy 32.512 -450.215)
				(xy 32.512 -425.831) (xy 34.798 -423.545) (xy 46.101 -423.545) (xy 46.609 -423.037)
			)
		)
	)
	(zone
		(layer "B.Cu")
		(hatch none 0.5)
		(connect_pads
			(clearance 0)
		)
		(min_thickness 0.25)
		(keepout
			(tracks allowed)
			(vias allowed)
			(pads allowed)
			(copperpour allowed)
			(footprints not_allowed)
		)
		(placement
			(enabled no)
			(sheetname "")
		)
		(fill
			(thermal_gap 0.5)
			(thermal_bridge_width 0.5)
			(island_removal_mode 0)
		)
		(polygon
			(pts
				(arc
					(start 7.599934 -10.299954)
					(mid 11.599926 -6.299962)
					(end 7.599934 -2.29997)
				)
				(arc
					(start 7.599934 -2.29997)
					(mid 3.599942 -6.299962)
					(end 7.599934 -10.299954)
				)
			)
		)
	)
	(zone
		(layer "B.Cu")
		(hatch none 0.5)
		(connect_pads
			(clearance 0)
		)
		(min_thickness 0.25)
		(keepout
			(tracks allowed)
			(vias allowed)
			(pads allowed)
			(copperpour allowed)
			(footprints not_allowed)
		)
		(placement
			(enabled no)
			(sheetname "")
		)
		(fill
			(thermal_gap 0.5)
			(thermal_bridge_width 0.5)
			(island_removal_mode 0)
		)
		(polygon
			(pts
				(arc
					(start 7.599934 -200.33996)
					(mid 3.599942 -204.339952)
					(end 7.599934 -208.339944)
				)
				(arc
					(start 7.599934 -208.339944)
					(mid 11.599926 -204.339952)
					(end 7.599934 -200.33996)
				)
			)
		)
	)
	(zone
		(layer "B.Cu")
		(hatch none 0.5)
		(connect_pads
			(clearance 0)
		)
		(min_thickness 0.25)
		(keepout
			(tracks allowed)
			(vias allowed)
			(pads allowed)
			(copperpour allowed)
			(footprints not_allowed)
		)
		(placement
			(enabled no)
			(sheetname "")
		)
		(fill
			(thermal_gap 0.5)
			(thermal_bridge_width 0.5)
			(island_removal_mode 0)
		)
		(polygon
			(pts
				(arc
					(start 7.599934 -134.340092)
					(mid 3.599942 -138.340084)
					(end 7.599934 -142.340076)
				)
				(arc
					(start 7.599934 -142.340076)
					(mid 11.599926 -138.340084)
					(end 7.599934 -134.340092)
				)
			)
		)
	)
	(zone
		(layer "B.Cu")
		(hatch none 0.5)
		(connect_pads
			(clearance 0)
		)
		(min_thickness 0.25)
		(keepout
			(tracks allowed)
			(vias allowed)
			(pads allowed)
			(copperpour allowed)
			(footprints not_allowed)
		)
		(placement
			(enabled no)
			(sheetname "")
		)
		(fill
			(thermal_gap 0.5)
			(thermal_bridge_width 0.5)
			(island_removal_mode 0)
		)
		(polygon
			(pts
				(arc
					(start 7.599934 -24.299926)
					(mid 3.599942 -28.299918)
					(end 7.599934 -32.29991)
				)
				(arc
					(start 7.599934 -32.29991)
					(mid 11.599926 -28.299918)
					(end 7.599934 -24.299926)
				)
			)
		)
	)
	(zone
		(layer "B.Cu")
		(hatch none 0.5)
		(connect_pads
			(clearance 0)
		)
		(min_thickness 0.25)
		(keepout
			(tracks allowed)
			(vias allowed)
			(pads allowed)
			(copperpour allowed)
			(footprints not_allowed)
		)
		(placement
			(enabled no)
			(sheetname "")
		)
		(fill
			(thermal_gap 0.5)
			(thermal_bridge_width 0.5)
			(island_removal_mode 0)
		)
		(polygon
			(pts
				(arc
					(start 40.999918 -458.300074)
					(mid 36.249864 -463.050128)
					(end 40.999918 -467.799928)
				)
				(arc
					(start 40.999918 -467.799928)
					(mid 45.749718 -463.050128)
					(end 40.999918 -458.300074)
				)
			)
		)
	)
	(zone
		(layer "B.Cu")
		(hatch none 0.5)
		(connect_pads
			(clearance 0)
		)
		(min_thickness 0.25)
		(keepout
			(tracks allowed)
			(vias allowed)
			(pads allowed)
			(copperpour allowed)
			(footprints not_allowed)
		)
		(placement
			(enabled no)
			(sheetname "")
		)
		(fill
			(thermal_gap 0.5)
			(thermal_bridge_width 0.5)
			(island_removal_mode 0)
		)
		(polygon
			(pts
				(arc
					(start 7.599934 -208.339944)
					(mid 11.599926 -204.339952)
					(end 7.599934 -200.33996)
				)
				(arc
					(start 7.599934 -200.33996)
					(mid 3.599942 -204.339952)
					(end 7.599934 -208.339944)
				)
			)
		)
	)
	(zone
		(layer "B.Cu")
		(hatch none 0.5)
		(connect_pads
			(clearance 0)
		)
		(min_thickness 0.25)
		(keepout
			(tracks allowed)
			(vias allowed)
			(pads allowed)
			(copperpour allowed)
			(footprints not_allowed)
		)
		(placement
			(enabled no)
			(sheetname "")
		)
		(fill
			(thermal_gap 0.5)
			(thermal_bridge_width 0.5)
			(island_removal_mode 0)
		)
		(polygon
			(pts
				(arc
					(start 40.999918 -439.200036)
					(mid 36.249864 -443.95009)
					(end 40.999918 -448.69989)
				)
				(arc
					(start 40.999918 -448.69989)
					(mid 45.749718 -443.95009)
					(end 40.999918 -439.200036)
				)
			)
		)
	)
	(zone
		(layer "B.Cu")
		(hatch none 0.5)
		(connect_pads
			(clearance 0)
		)
		(min_thickness 0.25)
		(keepout
			(tracks allowed)
			(vias allowed)
			(pads allowed)
			(copperpour allowed)
			(footprints not_allowed)
		)
		(placement
			(enabled no)
			(sheetname "")
		)
		(fill
			(thermal_gap 0.5)
			(thermal_bridge_width 0.5)
			(island_removal_mode 0)
		)
		(polygon
			(pts
				(arc
					(start 7.599934 -142.340076)
					(mid 11.599926 -138.340084)
					(end 7.599934 -134.340092)
				)
				(arc
					(start 7.599934 -134.340092)
					(mid 3.599942 -138.340084)
					(end 7.599934 -142.340076)
				)
			)
		)
	)
	(zone
		(layer "B.Cu")
		(hatch none 0.5)
		(connect_pads
			(clearance 0)
		)
		(min_thickness 0.25)
		(keepout
			(tracks allowed)
			(vias allowed)
			(pads allowed)
			(copperpour allowed)
			(footprints not_allowed)
		)
		(placement
			(enabled no)
			(sheetname "")
		)
		(fill
			(thermal_gap 0.5)
			(thermal_bridge_width 0.5)
			(island_removal_mode 0)
		)
		(polygon
			(pts
				(arc
					(start 17.500092 -491.000034)
					(mid 17.792985 -490.292929)
					(end 18.50009 -490.000036)
				)
				(arc
					(start 51.500024 -490.000036)
					(mid 52.207129 -489.707143)
					(end 52.500022 -489.000038)
				)
				(arc
					(start 52.500022 -10.999978)
					(mid 52.207129 -10.292873)
					(end 51.500024 -9.99998)
				)
				(arc
					(start 18.50009 -9.99998)
					(mid 17.792985 -9.707087)
					(end 17.500092 -8.999982)
				)
				(arc
					(start 17.500092 -0.999998)
					(mid 17.207199 -0.292893)
					(end 16.500094 0)
				)
				(arc
					(start 0.999998 0)
					(mid 0.292893 -0.292893)
					(end 0 -0.999998)
				)
				(arc
					(start 0 -499.000018)
					(mid 0.292893 -499.707123)
					(end 0.999998 -500.000016)
				)
				(arc
					(start 16.500094 -500.000016)
					(mid 17.207199 -499.707123)
					(end 17.500092 -499.000018)
				)
			)
		)
	)
	(zone
		(layer "B.Cu")
		(hatch none 0.5)
		(connect_pads
			(clearance 0)
		)
		(min_thickness 0.25)
		(keepout
			(tracks allowed)
			(vias allowed)
			(pads allowed)
			(copperpour allowed)
			(footprints not_allowed)
		)
		(placement
			(enabled no)
			(sheetname "")
		)
		(fill
			(thermal_gap 0.5)
			(thermal_bridge_width 0.5)
			(island_removal_mode 0)
		)
		(polygon
			(pts
				(arc
					(start 7.599934 -178.340004)
					(mid 3.599942 -182.339996)
					(end 7.599934 -186.339988)
				)
				(arc
					(start 7.599934 -186.339988)
					(mid 11.599926 -182.339996)
					(end 7.599934 -178.340004)
				)
			)
		)
	)
	(zone
		(layer "B.Cu")
		(hatch none 0.5)
		(connect_pads
			(clearance 0)
		)
		(min_thickness 0.25)
		(keepout
			(tracks allowed)
			(vias allowed)
			(pads allowed)
			(copperpour allowed)
			(footprints not_allowed)
		)
		(placement
			(enabled no)
			(sheetname "")
		)
		(fill
			(thermal_gap 0.5)
			(thermal_bridge_width 0.5)
			(island_removal_mode 0)
		)
		(polygon
			(pts
				(arc
					(start 7.599934 -365.659924)
					(mid 11.599926 -361.659932)
					(end 7.599934 -357.65994)
				)
				(arc
					(start 7.599934 -357.65994)
					(mid 3.599942 -361.659932)
					(end 7.599934 -365.659924)
				)
			)
		)
	)
	(zone
		(layer "B.Cu")
		(hatch none 0.5)
		(connect_pads
			(clearance 0)
		)
		(min_thickness 0.25)
		(keepout
			(tracks allowed)
			(vias allowed)
			(pads allowed)
			(copperpour allowed)
			(footprints not_allowed)
		)
		(placement
			(enabled no)
			(sheetname "")
		)
		(fill
			(thermal_gap 0.5)
			(thermal_bridge_width 0.5)
			(island_removal_mode 0)
		)
		(polygon
			(pts
				(arc
					(start 7.599934 -497.700046)
					(mid 11.599926 -493.700054)
					(end 7.599934 -489.700062)
				)
				(arc
					(start 7.599934 -489.700062)
					(mid 3.599942 -493.700054)
					(end 7.599934 -497.700046)
				)
			)
		)
	)
	(zone
		(layer "B.Cu")
		(hatch none 0.5)
		(connect_pads
			(clearance 0)
		)
		(min_thickness 0.25)
		(keepout
			(tracks allowed)
			(vias allowed)
			(pads allowed)
			(copperpour allowed)
			(footprints not_allowed)
		)
		(placement
			(enabled no)
			(sheetname "")
		)
		(fill
			(thermal_gap 0.5)
			(thermal_bridge_width 0.5)
			(island_removal_mode 0)
		)
		(polygon
			(pts
				(arc
					(start 24.500078 -467.799928)
					(mid 29.249878 -463.050128)
					(end 24.500078 -458.300074)
				)
				(arc
					(start 24.500078 -458.300074)
					(mid 19.750024 -463.050128)
					(end 24.500078 -467.799928)
				)
			)
		)
	)
	(zone
		(layer "B.Cu")
		(hatch none 0.5)
		(connect_pads
			(clearance 0)
		)
		(min_thickness 0.25)
		(keepout
			(tracks allowed)
			(vias allowed)
			(pads allowed)
			(copperpour allowed)
			(footprints not_allowed)
		)
		(placement
			(enabled no)
			(sheetname "")
		)
		(fill
			(thermal_gap 0.5)
			(thermal_bridge_width 0.5)
			(island_removal_mode 0)
		)
		(polygon
			(pts
				(arc
					(start 7.599934 -467.700106)
					(mid 3.599942 -471.700098)
					(end 7.599934 -475.70009)
				)
				(arc
					(start 7.599934 -475.70009)
					(mid 11.599926 -471.700098)
					(end 7.599934 -467.700106)
				)
			)
		)
	)
	(zone
		(net "P12V_AUX")
		(layer "In1.Cu")
		(hatch none 0.5)
		(connect_pads
			(clearance 0.5)
		)
		(min_thickness 0.25)
		(fill yes
			(thermal_gap 0.5)
			(thermal_bridge_width 0.5)
			(island_removal_mode 0)
		)
		(polygon
			(pts
				(xy 32.7025 -450.517006) (xy 32.7025 -425.528994) (xy 32.052006 -424.8785) (xy 13.921994 -424.8785)
				(xy 13.0175 -425.782994) (xy 13.0175 -442.516006) (xy 15.4305 -444.929006) (xy 15.4305 -474.901006)
				(xy 15.953994 -475.4245) (xy 20.652994 -475.4245) (xy 21.2725 -476.044006) (xy 21.2725 -489.23702)
				(xy 22.2885 -489.23702) (xy 22.2885 -475.917006) (xy 22.781006 -475.4245) (xy 30.401006 -475.4245)
				(xy 32.7025 -473.123006) (xy 32.7025 -453.468994) (xy 31.4325 -452.198994) (xy 31.4325 -451.152006)
				(xy 32.052006 -450.5325) (xy 32.687006 -450.5325)
			)
		)
	)
	(zone
		(layer "In1.Cu")
		(hatch none 0.5)
		(connect_pads
			(clearance 0)
		)
		(min_thickness 0.25)
		(keepout
			(tracks not_allowed)
			(vias allowed)
			(pads allowed)
			(copperpour not_allowed)
			(footprints allowed)
		)
		(placement
			(enabled no)
			(sheetname "")
		)
		(fill
			(thermal_gap 0.5)
			(thermal_bridge_width 0.5)
			(island_removal_mode 0)
		)
		(polygon
			(pts
				(arc
					(start 5.160264 -311.740042)
					(mid 2.919984 -311.740042)
					(end 5.160264 -311.740042)
				)
			)
		)
	)
	(zone
		(layer "In1.Cu")
		(hatch none 0.5)
		(connect_pads
			(clearance 0)
		)
		(min_thickness 0.25)
		(keepout
			(tracks not_allowed)
			(vias allowed)
			(pads allowed)
			(copperpour not_allowed)
			(footprints allowed)
		)
		(placement
			(enabled no)
			(sheetname "")
		)
		(fill
			(thermal_gap 0.5)
			(thermal_bridge_width 0.5)
			(island_removal_mode 0)
		)
		(polygon
			(pts
				(arc
					(start 5.160264 -198.419974)
					(mid 2.919984 -198.419974)
					(end 5.160264 -198.419974)
				)
			)
		)
	)
	(zone
		(layer "In1.Cu")
		(hatch none 0.5)
		(connect_pads
			(clearance 0)
		)
		(min_thickness 0.25)
		(keepout
			(tracks not_allowed)
			(vias allowed)
			(pads allowed)
			(copperpour not_allowed)
			(footprints allowed)
		)
		(placement
			(enabled no)
			(sheetname "")
		)
		(fill
			(thermal_gap 0.5)
			(thermal_bridge_width 0.5)
			(island_removal_mode 0)
		)
		(polygon
			(pts
				(arc
					(start 5.160264 -487.780076)
					(mid 2.919984 -487.780076)
					(end 5.160264 -487.780076)
				)
			)
		)
	)
	(zone
		(net "GND")
		(layer "In1.Cu")
		(hatch none 0.5)
		(connect_pads
			(clearance 0.5)
		)
		(min_thickness 0.25)
		(fill yes
			(thermal_gap 0.5)
			(thermal_bridge_width 0.5)
			(island_removal_mode 0)
		)
		(polygon
			(pts
				(xy 22.6695 -476.074994) (xy 22.6695 -489.23702)
				(arc
					(start 51.500024 -489.23702)
					(mid 51.667596 -489.16761)
					(end 51.737006 -489.000038)
				)
				(arc
					(start 51.737006 -10.999978)
					(mid 51.667596 -10.832406)
					(end 51.500024 -10.762996)
				)
				(xy 18.50009 -10.762996) (xy 18.440146 -10.76198) (xy 18.184368 -10.76198)
				(arc
					(start 18.150586 -10.727944)
					(mid 17.253493 -10.246579)
					(end 16.772128 -9.349486)
				)
				(xy 16.738092 -9.315704) (xy 16.738092 -9.059926) (xy 16.737076 -8.999982)
				(arc
					(start 16.737076 -0.999998)
					(mid 16.667666 -0.832426)
					(end 16.500094 -0.763016)
				)
				(arc
					(start 0.999998 -0.763016)
					(mid 0.832426 -0.832426)
					(end 0.763016 -0.999998)
				)
				(arc
					(start 0.763016 -499.000018)
					(mid 0.832426 -499.16759)
					(end 0.999998 -499.237)
				)
				(arc
					(start 16.500094 -499.237)
					(mid 16.667666 -499.16759)
					(end 16.737076 -499.000018)
				)
				(xy 16.737076 -491.000034) (xy 16.738092 -490.94009) (xy 16.738092 -490.684312)
				(arc
					(start 16.772128 -490.65053)
					(mid 17.253493 -489.753437)
					(end 18.150586 -489.272072)
				)
				(xy 18.184368 -489.238036) (xy 18.440146 -489.238036) (xy 18.50009 -489.23702) (xy 20.8915 -489.23702)
				(xy 20.8915 -476.201994) (xy 20.495006 -475.8055) (xy 15.796006 -475.8055) (xy 15.0495 -475.058994)
				(xy 15.0495 -445.086994) (xy 12.6365 -442.673994) (xy 12.6365 -425.625006) (xy 13.764006 -424.4975)
				(xy 32.209994 -424.4975) (xy 33.0835 -425.371006) (xy 33.0835 -450.674994) (xy 32.844994 -450.9135)
				(xy 32.209994 -450.9135) (xy 31.8135 -451.309994) (xy 31.8135 -452.041006) (xy 33.0835 -453.311006)
				(xy 33.0835 -473.280994) (xy 30.558994 -475.8055) (xy 22.938994 -475.8055)
			)
		)
		(polygon
			(pts
				(arc
					(start 4.040124 -486.659936)
					(mid 4.040124 -488.900216)
					(end 4.040124 -486.659936)
				)
			)
		)
		(polygon
			(pts
				(arc
					(start 4.040124 -376.61977)
					(mid 4.040124 -378.86005)
					(end 4.040124 -376.61977)
				)
			)
		)
		(polygon
			(pts
				(arc
					(start 4.040124 -310.619902)
					(mid 4.040124 -312.860182)
					(end 4.040124 -310.619902)
				)
			)
		)
		(polygon
			(pts
				(arc
					(start 4.040124 -197.299834)
					(mid 4.040124 -199.540114)
					(end 4.040124 -197.299834)
				)
			)
		)
		(polygon
			(pts
				(arc
					(start 4.040124 -21.2598)
					(mid 4.040124 -23.50008)
					(end 4.040124 -21.2598)
				)
			)
		)
	)
	(zone
		(layer "In1.Cu")
		(hatch none 0.5)
		(connect_pads
			(clearance 0)
		)
		(min_thickness 0.25)
		(keepout
			(tracks not_allowed)
			(vias allowed)
			(pads allowed)
			(copperpour not_allowed)
			(footprints allowed)
		)
		(placement
			(enabled no)
			(sheetname "")
		)
		(fill
			(thermal_gap 0.5)
			(thermal_bridge_width 0.5)
			(island_removal_mode 0)
		)
		(polygon
			(pts
				(arc
					(start 5.160264 -377.73991)
					(mid 2.919984 -377.73991)
					(end 5.160264 -377.73991)
				)
			)
		)
	)
	(zone
		(layer "In1.Cu")
		(hatch none 0.5)
		(connect_pads
			(clearance 0)
		)
		(min_thickness 0.25)
		(keepout
			(tracks not_allowed)
			(vias allowed)
			(pads allowed)
			(copperpour not_allowed)
			(footprints allowed)
		)
		(placement
			(enabled no)
			(sheetname "")
		)
		(fill
			(thermal_gap 0.5)
			(thermal_bridge_width 0.5)
			(island_removal_mode 0)
		)
		(polygon
			(pts
				(arc
					(start 5.160264 -22.37994)
					(mid 2.919984 -22.37994)
					(end 5.160264 -22.37994)
				)
			)
		)
	)
	(zone
		(net "P12V")
		(layer "In2.Cu")
		(hatch none 0.5)
		(connect_pads
			(clearance 0.5)
		)
		(min_thickness 0.25)
		(fill yes
			(thermal_gap 0.5)
			(thermal_bridge_width 0.5)
			(island_removal_mode 0)
		)
		(polygon
			(pts
				(xy 28.7655 -79.677006) (xy 35.2425 -73.200006) (xy 35.2425 -64.945006) (xy 36.878006 -63.3095)
				(xy 46.941994 -63.3095) (xy 47.9425 -64.310006) (xy 47.9425 -79.199994) (xy 45.2755 -81.866994)
				(xy 45.2755 -112.8395) (xy 51.737006 -112.8395)
				(arc
					(start 51.737006 -10.999978)
					(mid 51.667596 -10.832406)
					(end 51.500024 -10.762996)
				)
				(xy 18.50009 -10.762996) (xy 18.440146 -10.76198) (xy 18.184368 -10.76198)
				(arc
					(start 18.150586 -10.727944)
					(mid 17.253493 -10.246579)
					(end 16.772128 -9.349486)
				)
				(xy 16.738092 -9.315704) (xy 16.738092 -9.059926) (xy 16.737076 -8.999982)
				(arc
					(start 16.737076 -0.999998)
					(mid 16.667666 -0.832426)
					(end 16.500094 -0.763016)
				)
				(arc
					(start 0.999998 -0.763016)
					(mid 0.832426 -0.832426)
					(end 0.763016 -0.999998)
				)
				(arc
					(start 0.763016 -336.678016)
					(mid 9.49988 -340.000082)
					(end 0.763016 -343.322148)
				)
				(arc
					(start 0.763016 -499.000018)
					(mid 0.832426 -499.16759)
					(end 0.999998 -499.237)
				)
				(arc
					(start 16.500094 -499.237)
					(mid 16.667666 -499.16759)
					(end 16.737076 -499.000018)
				)
				(xy 16.737076 -491.000034) (xy 16.738092 -490.94009) (xy 16.738092 -490.684312)
				(arc
					(start 16.772128 -490.65053)
					(mid 17.253493 -489.753437)
					(end 18.150586 -489.272072)
				)
				(xy 18.184368 -489.238036) (xy 18.440146 -489.238036) (xy 18.50009 -489.23702) (xy 34.876486 -489.23702)
				(xy 34.9885 -489.125006) (xy 34.9885 -481.886006) (xy 36.6395 -480.235006) (xy 36.6395 -474.042994)
				(xy 35.989006 -473.3925) (xy 32.971994 -473.3925) (xy 30.558994 -475.8055) (xy 15.796006 -475.8055)
				(xy 15.0495 -475.058994) (xy 15.0495 -445.086994) (xy 12.6365 -442.673994) (xy 12.6365 -411.528006)
				(xy 13.208 -410.956506) (xy 13.208 -410.225494) (xy 12.2555 -409.272994) (xy 12.2555 -401.622006)
				(xy 12.875006 -401.0025) (xy 46.941994 -401.0025) (xy 47.830994 -401.8915) (xy 51.483006 -401.8915)
				(xy 51.737006 -401.6375)
				(arc
					(start 51.737006 -341.589614)
					(mid 37.949882 -337.49996)
					(end 51.737006 -333.410306)
				)
				(xy 51.737006 -121.125488) (xy 51.386994 -121.4755) (xy 32.814006 -121.4755) (xy 32.3215 -120.982994)
				(xy 32.3215 -113.205006) (xy 32.496506 -113.03) (xy 28.7655 -109.298994) (xy 28.7655 -95.552006)
				(xy 29.5275 -94.790006) (xy 29.5275 -89.994994) (xy 28.7655 -89.232994)
			)
		)
		(polygon
			(pts
				(arc
					(start 6.999986 -454.999852)
					(mid 6.999986 -464.999832)
					(end 6.999986 -454.999852)
				)
			)
		)
		(polygon
			(pts
				(arc
					(start 45.500036 -289.999928)
					(mid 45.500036 -299.999908)
					(end 45.500036 -289.999928)
				)
			)
		)
		(polygon
			(pts
				(arc
					(start 6.999986 -154.999944)
					(mid 6.999986 -164.999924)
					(end 6.999986 -154.999944)
				)
			)
		)
		(polygon
			(pts
				(arc
					(start 45.499782 -139.999974)
					(mid 45.499782 -149.999954)
					(end 45.499782 -139.999974)
				)
			)
		)
		(polygon
			(pts
				(xy 9.4615 -72.819006) (xy 9.4615 -110.822994) (xy 11.541506 -112.903) (xy 9.9695 -114.475006) (xy 9.9695 -120.347994)
				(xy 11.351006 -121.7295) (xy 30.812994 -121.7295) (xy 31.8135 -120.728994) (xy 31.8135 -114.348006)
				(xy 30.304994 -112.8395) (xy 22.1615 -112.8395) (xy 22.1615 -110.695994) (xy 24.4475 -108.409994)
				(xy 24.4475 -95.044006) (xy 23.8125 -94.409006) (xy 23.8125 -89.740994) (xy 24.081994 -89.4715)
				(xy 24.589994 -89.4715) (xy 25.3365 -88.724994) (xy 25.3365 -81.231994) (xy 30.2895 -76.278994)
				(xy 30.2895 -64.945006) (xy 29.161994 -63.8175) (xy 19.733006 -63.8175) (xy 17.8435 -65.707006)
				(xy 17.8435 -71.422006) (xy 17.320006 -71.9455) (xy 10.335006 -71.9455)
			)
		)
		(polygon
			(pts
				(arc
					(start 6.999986 -34.99993)
					(mid 6.999986 -44.99991)
					(end 6.999986 -34.99993)
				)
			)
		)
		(polygon
			(pts
				(arc
					(start 45.500036 -14.99997)
					(mid 45.500036 -24.99995)
					(end 45.500036 -14.99997)
				)
			)
		)
	)
	(zone
		(net "P12V_SENSE_TRACE")
		(layer "In2.Cu")
		(hatch none 0.5)
		(connect_pads
			(clearance 0.5)
		)
		(min_thickness 0.25)
		(fill yes
			(thermal_gap 0.5)
			(thermal_bridge_width 0.5)
			(island_removal_mode 0)
		)
		(polygon
			(pts
				(xy 47.5615 -409.750006) (xy 47.5615 -402.160994) (xy 46.784006 -401.3835) (xy 13.032994 -401.3835)
				(xy 12.6365 -401.779994) (xy 12.6365 -409.115006) (xy 13.921994 -410.4005) (xy 46.911006 -410.4005)
			)
		)
	)
	(zone
		(net "P12VU")
		(layer "In2.Cu")
		(hatch none 0.5)
		(connect_pads
			(clearance 0.5)
		)
		(min_thickness 0.25)
		(fill yes
			(thermal_gap 0.5)
			(thermal_bridge_width 0.5)
			(island_removal_mode 0)
		)
		(polygon
			(pts
				(xy 24.9555 -81.074006) (xy 29.9085 -76.121006) (xy 29.9085 -65.102994) (xy 29.004006 -64.1985)
				(xy 19.890994 -64.1985) (xy 18.2245 -65.864994) (xy 18.2245 -71.579994) (xy 17.477994 -72.3265)
				(xy 10.492994 -72.3265) (xy 9.8425 -72.976994) (xy 9.8425 -110.665006) (xy 12.0015 -112.824006)
				(xy 12.0015 -112.8395) (xy 21.7805 -112.8395) (xy 21.7805 -110.538006) (xy 24.0665 -108.252006)
				(xy 24.0665 -95.201994) (xy 23.4315 -94.566994) (xy 23.4315 -89.583006) (xy 23.924006 -89.0905)
				(xy 24.432006 -89.0905) (xy 24.9555 -88.567006)
			)
		)
	)
	(zone
		(net "P12VL")
		(layer "In2.Cu")
		(hatch none 0.5)
		(connect_pads
			(clearance 0.5)
		)
		(min_thickness 0.25)
		(fill yes
			(thermal_gap 0.5)
			(thermal_bridge_width 0.5)
			(island_removal_mode 0)
		)
		(polygon
			(pts
				(xy 29.9085 -89.837006) (xy 29.9085 -94.947994) (xy 29.1465 -95.709994) (xy 29.1465 -109.141006)
				(xy 32.844994 -112.8395) (xy 44.8945 -112.8395) (xy 44.8945 -81.709006) (xy 47.5615 -79.042006)
				(xy 47.5615 -64.467994) (xy 46.784006 -63.6905) (xy 37.035994 -63.6905) (xy 35.6235 -65.102994)
				(xy 35.6235 -73.357994) (xy 29.1465 -79.834994) (xy 29.1465 -89.075006)
			)
		)
	)
	(zone
		(net "P12V_AUX")
		(layer "In2.Cu")
		(hatch none 0.5)
		(connect_pads
			(clearance 0.5)
		)
		(min_thickness 0.25)
		(fill yes
			(thermal_gap 0.5)
			(thermal_bridge_width 0.5)
			(island_removal_mode 0)
		)
		(polygon
			(pts
				(xy 46.9265 -423.339006) (xy 46.9265 -411.050994) (xy 46.657006 -410.7815) (xy 13.921994 -410.7815)
				(xy 13.0175 -411.685994) (xy 13.0175 -442.516006) (xy 15.4305 -444.929006) (xy 15.4305 -474.901006)
				(xy 15.953994 -475.4245) (xy 30.401006 -475.4245) (xy 32.7025 -473.123006) (xy 32.7025 -453.253856)
				(xy 32.062674 -452.933816) (xy 32.004762 -452.918068) (xy 31.994094 -452.899526) (xy 31.975298 -452.890128)
				(xy 31.956248 -452.833232) (xy 31.496 -452.027798) (xy 31.49473 -452.027544) (xy 31.457138 -451.959472)
				(xy 31.41853 -451.891908) (xy 31.418784 -451.890638) (xy 31.418276 -451.889622) (xy 31.439612 -451.814692)
				(xy 31.459932 -451.739762) (xy 31.461202 -451.739) (xy 31.673546 -450.995796) (xy 31.67126 -450.991732)
				(xy 31.694882 -450.920612) (xy 31.715456 -450.84873) (xy 31.719774 -450.846444) (xy 31.721298 -450.841872)
				(xy 31.7881 -450.808344) (xy 31.853378 -450.772276) (xy 31.858204 -450.773546) (xy 32.7025 -450.351144)
				(xy 32.7025 -425.625006) (xy 34.719006 -423.6085) (xy 46.657006 -423.6085)
			)
		)
	)
	(zone
		(net "P12VL_NET")
		(layer "In2.Cu")
		(hatch none 0.5)
		(connect_pads
			(clearance 0.5)
		)
		(min_thickness 0.25)
		(fill yes
			(thermal_gap 0.5)
			(thermal_bridge_width 0.5)
			(island_removal_mode 0)
		)
		(polygon
			(pts
				(xy 32.844994 -113.2205) (xy 32.7025 -113.362994) (xy 32.7025 -120.825006) (xy 32.971994 -121.0945)
				(xy 51.229006 -121.0945) (xy 51.737006 -120.5865) (xy 51.737006 -113.2205)
			)
		)
	)
	(zone
		(net "GND")
		(layer "In2.Cu")
		(hatch none 0.5)
		(connect_pads
			(clearance 0.5)
		)
		(min_thickness 0.25)
		(fill yes
			(thermal_gap 0.5)
			(thermal_bridge_width 0.5)
			(island_removal_mode 0)
		)
		(polygon
			(pts
				(arc
					(start 51.500024 -489.23702)
					(mid 51.667596 -489.16761)
					(end 51.737006 -489.000038)
				)
				(xy 51.737006 -402.5265) (xy 51.483006 -402.2725) (xy 48.3235 -402.2725) (xy 48.3235 -402.287994)
				(xy 47.9425 -402.668994) (xy 47.9425 -409.907994) (xy 47.3075 -410.542994) (xy 47.3075 -423.496994)
				(xy 46.814994 -423.9895) (xy 34.876994 -423.9895) (xy 33.0835 -425.782994) (xy 33.0835 -450.424042)
				(xy 33.09874 -450.454268) (xy 33.0835 -450.499988) (xy 33.0835 -450.547994) (xy 33.059624 -450.57187)
				(xy 33.048702 -450.604128) (xy 33.005776 -450.625464) (xy 32.971994 -450.6595) (xy 32.937958 -450.6595)
				(xy 32.037274 -451.109842) (xy 31.828232 -451.841108) (xy 32.267906 -452.610474) (xy 32.937958 -452.9455)
				(xy 32.971994 -452.9455) (xy 33.005776 -452.979536) (xy 33.048702 -453.000872) (xy 33.059624 -453.03313)
				(xy 33.0835 -453.057006) (xy 33.0835 -453.105012) (xy 33.09874 -453.150732) (xy 33.0835 -453.180958)
				(xy 33.0835 -473.0115) (xy 36.146994 -473.0115) (xy 37.0205 -473.885006) (xy 37.0205 -480.392994)
				(xy 35.3695 -482.043994) (xy 35.3695 -489.125006) (xy 35.481514 -489.23702)
			)
		)
		(polygon
			(pts
				(arc
					(start 45.500036 -475.000066)
					(mid 45.500036 -485.000046)
					(end 45.500036 -475.000066)
				)
			)
		)
	)
	(zone
		(net "P12VU_NET")
		(layer "In2.Cu")
		(hatch none 0.5)
		(connect_pads
			(clearance 0.5)
		)
		(min_thickness 0.25)
		(fill yes
			(thermal_gap 0.5)
			(thermal_bridge_width 0.5)
			(island_removal_mode 0)
		)
		(polygon
			(pts
				(xy 11.762994 -113.2205) (xy 10.3505 -114.632994) (xy 10.3505 -120.190006) (xy 11.508994 -121.3485)
				(xy 30.655006 -121.3485) (xy 31.4325 -120.571006) (xy 31.4325 -114.505994) (xy 30.147006 -113.2205)
			)
		)
	)
)
